CONCISE NET LIST - 1  
CLK_100M_BMC_P3E_DN      J41              A13      SCONN168_623403212-SCONN168_6-A
CLK_100M_BMC_P3E_DN      U4               B11      EMMITSBURG_REV0P9-GFNOCPU04302A
CLK_100M_BMC_P3E_DP      J41              A12      SCONN168_623403212-SCONN168_6-A
CLK_100M_BMC_P3E_DP      U4               D11      EMMITSBURG_REV0P9-GFNOCPU04302A
CLK_100M_CK440_PCH_EXTCLK_DN R554             2        Q_RES_0402LF-0,5%,1/16W,CHIP,CA
CLK_100M_CK440_PCH_EXTCLK_DN U4               D21      EMMITSBURG_REV0P9-GFNOCPU04302A
CLK_100M_CK440_PCH_EXTCLK_DP R553             2        Q_RES_0402LF-0,5%,1/16W,CHIP,CA
CLK_100M_CK440_PCH_EXTCLK_DP U4               B21      EMMITSBURG_REV0P9-GFNOCPU04302A
CLK_100M_CK440_PCH_EXTCLK_R_DN R554             1        Q_RES_0402LF-0,5%,1/16W,CHIP,CA
CLK_100M_CK440_PCH_EXTCLK_R_DN U13              A47      9SQ440NQQI8-9SQ440NQQI8,SMLF,IA
CLK_100M_CK440_PCH_EXTCLK_R_DP R553             1        Q_RES_0402LF-0,5%,1/16W,CHIP,CA
CLK_100M_CK440_PCH_EXTCLK_R_DP U13              A48      9SQ440NQQI8-9SQ440NQQI8,SMLF,IA
CLK_100M_DB2000_CPU0_BCLK0_DN U2               AT30     SOCKET4677_AZIFS054P001C01-SOCA
CLK_100M_DB2000_CPU0_BCLK0_DN U38              K1       9QXL2001BNHGI8-9QXL2001BNHGI8,A
CLK_100M_DB2000_CPU0_BCLK0_DP U2               AV30     SOCKET4677_AZIFS054P001C01-SOCA
CLK_100M_DB2000_CPU0_BCLK0_DP U38              J1       9QXL2001BNHGI8-9QXL2001BNHGI8,A
CLK_100M_DB2000_CPU0_BCLK1_DN U2               CY28     SOCKET4677_AZIFS054P001C01-SOCA
CLK_100M_DB2000_CPU0_BCLK1_DN U38              M1       9QXL2001BNHGI8-9QXL2001BNHGI8,A
CLK_100M_DB2000_CPU0_BCLK1_DP U2               CW29     SOCKET4677_AZIFS054P001C01-SOCA
CLK_100M_DB2000_CPU0_BCLK1_DP U38              L1       9QXL2001BNHGI8-9QXL2001BNHGI8,A
CLK_100M_DB2000_CPU0_BCLK2_DN U2               AU29     SOCKET4677_AZIFS054P001C01-SOCA
CLK_100M_DB2000_CPU0_BCLK2_DN U38              M3       9QXL2001BNHGI8-9QXL2001BNHGI8,A
CLK_100M_DB2000_CPU0_BCLK2_DP U2               AV28     SOCKET4677_AZIFS054P001C01-SOCA
CLK_100M_DB2000_CPU0_BCLK2_DP U38              M2       9QXL2001BNHGI8-9QXL2001BNHGI8,A
CLK_100M_DB2000_CPU0_BCLK3_DN U2               CW27     SOCKET4677_AZIFS054P001C01-SOCA
CLK_100M_DB2000_CPU0_BCLK3_DN U38              M5       9QXL2001BNHGI8-9QXL2001BNHGI8,A
CLK_100M_DB2000_CPU0_BCLK3_DP U2               DA27     SOCKET4677_AZIFS054P001C01-SOCA
CLK_100M_DB2000_CPU0_BCLK3_DP U38              M4       9QXL2001BNHGI8-9QXL2001BNHGI8,A
CLK_100M_DB2000_CPU1_BCLK0_DN U1               AT30     SOCKET4677_AZIFS054P001C01-SOCA
CLK_100M_DB2000_CPU1_BCLK0_DN U38              M8       9QXL2001BNHGI8-9QXL2001BNHGI8,A
CLK_100M_DB2000_CPU1_BCLK0_DP U1               AV30     SOCKET4677_AZIFS054P001C01-SOCA
CLK_100M_DB2000_CPU1_BCLK0_DP U38              M7       9QXL2001BNHGI8-9QXL2001BNHGI8,A
CLK_100M_DB2000_CPU1_BCLK1_DN U1               CY28     SOCKET4677_AZIFS054P001C01-SOCA
CLK_100M_DB2000_CPU1_BCLK1_DN U38              M10      9QXL2001BNHGI8-9QXL2001BNHGI8,A
CLK_100M_DB2000_CPU1_BCLK1_DP U1               CW29     SOCKET4677_AZIFS054P001C01-SOCA
CLK_100M_DB2000_CPU1_BCLK1_DP U38              M9       9QXL2001BNHGI8-9QXL2001BNHGI8,A
CLK_100M_DB2000_CPU1_BCLK2_DN U1               AU29     SOCKET4677_AZIFS054P001C01-SOCA
CLK_100M_DB2000_CPU1_BCLK2_DN U38              M12      9QXL2001BNHGI8-9QXL2001BNHGI8,A
CLK_100M_DB2000_CPU1_BCLK2_DP U1               AV28     SOCKET4677_AZIFS054P001C01-SOCA
CLK_100M_DB2000_CPU1_BCLK2_DP U38              M11      9QXL2001BNHGI8-9QXL2001BNHGI8,A
CLK_100M_DB2000_CPU1_BCLK3_DN U1               CW27     SOCKET4677_AZIFS054P001C01-SOCA
CLK_100M_DB2000_CPU1_BCLK3_DN U38              K12      9QXL2001BNHGI8-9QXL2001BNHGI8,A
CLK_100M_DB2000_CPU1_BCLK3_DP U1               DA27     SOCKET4677_AZIFS054P001C01-SOCA
CLK_100M_DB2000_CPU1_BCLK3_DP U38              L12      9QXL2001BNHGI8-9QXL2001BNHGI8,A
CLK_100M_DB2000_DN       U13              A33      9SQ440NQQI8-9SQ440NQQI8,SMLF,IA
CLK_100M_DB2000_DN       U38              H1       9QXL2001BNHGI8-9QXL2001BNHGI8,A
CLK_100M_DB2000_DP       U13              A34      9SQ440NQQI8-9SQ440NQQI8,SMLF,IA
CLK_100M_DB2000_DP       U38              G1       9QXL2001BNHGI8-9QXL2001BNHGI8,A
CLK_100M_E1S_0_DN        J90              B14      CONN56_ME2005602311011-CONN56_A
CLK_100M_E1S_0_DN        R529             2        Q_RES_0402LF-0,5%,1/16W,CHIP,CA
CLK_100M_E1S_0_DP        J90              B15      CONN56_ME2005602311011-CONN56_A
CLK_100M_E1S_0_DP        R528             2        Q_RES_0402LF-0,5%,1/16W,CHIP,CA
CLK_100M_E1S_0_R_DN      R529             1        Q_RES_0402LF-0,5%,1/16W,CHIP,CA
CLK_100M_E1S_0_R_DN      U13              A51      9SQ440NQQI8-9SQ440NQQI8,SMLF,IA
CLK_100M_E1S_0_R_DP      R528             1        Q_RES_0402LF-0,5%,1/16W,CHIP,CA
CLK_100M_E1S_0_R_DP      U13              A52      9SQ440NQQI8-9SQ440NQQI8,SMLF,IA
CLK_100M_E1S_1_DN        J91              B14      CONN56_ME2005602311011-CONN56_A
CLK_100M_E1S_1_DN        R531             2        Q_RES_0402LF-0,5%,1/16W,CHIP,CA
CLK_100M_E1S_1_DP        J91              B15      CONN56_ME2005602311011-CONN56_A
CLK_100M_E1S_1_DP        R530             2        Q_RES_0402LF-0,5%,1/16W,CHIP,CA
CLK_100M_E1S_1_R_DN      R531             1        Q_RES_0402LF-0,5%,1/16W,CHIP,CA
CLK_100M_E1S_1_R_DN      U13              A49      9SQ440NQQI8-9SQ440NQQI8,SMLF,IA
CLK_100M_E1S_1_R_DP      R530             1        Q_RES_0402LF-0,5%,1/16W,CHIP,CA
CLK_100M_E1S_1_R_DP      U13              A50      9SQ440NQQI8-9SQ440NQQI8,SMLF,IA
CLK_100M_E1S_2_DN        J92              B14      CONN56_ME2005602311011-CONN56_A
CLK_100M_E1S_2_DN        R533             2        Q_RES_0402LF-0,5%,1/16W,CHIP,CA
CLK_100M_E1S_2_DP        J92              B15      CONN56_ME2005602311011-CONN56_A
CLK_100M_E1S_2_DP        R532             2        Q_RES_0402LF-0,5%,1/16W,CHIP,CA
CLK_100M_E1S_2_R_DN      R533             1        Q_RES_0402LF-0,5%,1/16W,CHIP,CA
CLK_100M_E1S_2_R_DN      U13              A43      9SQ440NQQI8-9SQ440NQQI8,SMLF,IA
CLK_100M_E1S_2_R_DP      R532             1        Q_RES_0402LF-0,5%,1/16W,CHIP,CA
CLK_100M_E1S_2_R_DP      U13              A44      9SQ440NQQI8-9SQ440NQQI8,SMLF,IA
CLK_100M_E1S_3_DN        J93              B14      CONN56_ME2005602311011-CONN56_A
CLK_100M_E1S_3_DN        R535             2        Q_RES_0402LF-0,5%,1/16W,CHIP,CA
CLK_100M_E1S_3_DP        J93              B15      CONN56_ME2005602311011-CONN56_A
CLK_100M_E1S_3_DP        R534             2        Q_RES_0402LF-0,5%,1/16W,CHIP,CA
CLK_100M_E1S_3_R_DN      R535             1        Q_RES_0402LF-0,5%,1/16W,CHIP,CA
CLK_100M_E1S_3_R_DN      U13              A41      9SQ440NQQI8-9SQ440NQQI8,SMLF,IA
CLK_100M_E1S_3_R_DP      R534             1        Q_RES_0402LF-0,5%,1/16W,CHIP,CA
CLK_100M_E1S_3_R_DP      U13              A42      9SQ440NQQI8-9SQ440NQQI8,SMLF,IA
CLK_100M_EDSFF1A_1_DN    J62              A14      SCONN84_123318136-SCONN84_1-23A
CLK_100M_EDSFF1A_1_DN    R2144            2        Q_RES_0402LF-0,5%,1/16W,CHIP,CA
CLK_100M_EDSFF1A_1_DP    J62              A15      SCONN84_123318136-SCONN84_1-23A
CLK_100M_EDSFF1A_1_DP    R2143            2        Q_RES_0402LF-0,5%,1/16W,CHIP,CA
CLK_100M_EDSFF1A_1_R_DN  R2144            1        Q_RES_0402LF-0,5%,1/16W,CHIP,CA
CLK_100M_EDSFF1A_1_R_DN  U38              A8       9QXL2001BNHGI8-9QXL2001BNHGI8,A
CLK_100M_EDSFF1A_1_R_DP  R2143            1        Q_RES_0402LF-0,5%,1/16W,CHIP,CA
CLK_100M_EDSFF1A_1_R_DP  U38              A9       9QXL2001BNHGI8-9QXL2001BNHGI8,A
CLK_100M_EDSFF1A_DN      J62              B14      SCONN84_123318136-SCONN84_1-23A
CLK_100M_EDSFF1A_DN      R1278            2        Q_RES_0402LF-0,5%,1/16W,CHIP,CA
CLK_100M_EDSFF1A_DP      J62              B15      SCONN84_123318136-SCONN84_1-23A
CLK_100M_EDSFF1A_DP      R1277            2        Q_RES_0402LF-0,5%,1/16W,CHIP,CA
CLK_100M_EDSFF1A_R_DN    R1278            1        Q_RES_0402LF-0,5%,1/16W,CHIP,CA
CLK_100M_EDSFF1A_R_DN    U38              A10      9QXL2001BNHGI8-9QXL2001BNHGI8,A
CLK_100M_EDSFF1A_R_DP    R1277            1        Q_RES_0402LF-0,5%,1/16W,CHIP,CA
CLK_100M_EDSFF1A_R_DP    U38              A11      9QXL2001BNHGI8-9QXL2001BNHGI8,A
CLK_100M_EDSFF1B_1_DN    J87              A14      SCONN84_123318136-SCONN84_1-23A
CLK_100M_EDSFF1B_1_DN    R2146            2        Q_RES_0402LF-0,5%,1/16W,CHIP,CA
CLK_100M_EDSFF1B_1_DP    J87              A15      SCONN84_123318136-SCONN84_1-23A
CLK_100M_EDSFF1B_1_DP    R2145            2        Q_RES_0402LF-0,5%,1/16W,CHIP,CA
CLK_100M_EDSFF1B_1_R_DN  R2146            1        Q_RES_0402LF-0,5%,1/16W,CHIP,CA
CLK_100M_EDSFF1B_1_R_DN  U38              A4       9QXL2001BNHGI8-9QXL2001BNHGI8,A
CLK_100M_EDSFF1B_1_R_DP  R2145            1        Q_RES_0402LF-0,5%,1/16W,CHIP,CA
CLK_100M_EDSFF1B_1_R_DP  U38              A5       9QXL2001BNHGI8-9QXL2001BNHGI8,A
CLK_100M_EDSFF1B_DN      J87              B14      SCONN84_123318136-SCONN84_1-23A
CLK_100M_EDSFF1B_DN      R1280            2        Q_RES_0402LF-0,5%,1/16W,CHIP,CA
CLK_100M_EDSFF1B_DP      J87              B15      SCONN84_123318136-SCONN84_1-23A
CLK_100M_EDSFF1B_DP      R1279            2        Q_RES_0402LF-0,5%,1/16W,CHIP,CA
CLK_100M_EDSFF1B_R_DN    R1280            1        Q_RES_0402LF-0,5%,1/16W,CHIP,CA
CLK_100M_EDSFF1B_R_DN    U38              A6       9QXL2001BNHGI8-9QXL2001BNHGI8,A
CLK_100M_EDSFF1B_R_DP    R1279            1        Q_RES_0402LF-0,5%,1/16W,CHIP,CA
CLK_100M_EDSFF1B_R_DP    U38              A7       9QXL2001BNHGI8-9QXL2001BNHGI8,A
CLK_100M_EDSFF2A_DN      J33              B14      SCONN84_123318136-SCONN84_1-23A
CLK_100M_EDSFF2A_DN      R1362            2        Q_RES_0402LF-0,5%,1/16W,CHIP,CA
CLK_100M_EDSFF2A_DP      J33              B15      SCONN84_123318136-SCONN84_1-23A
CLK_100M_EDSFF2A_DP      R1361            2        Q_RES_0402LF-0,5%,1/16W,CHIP,CA
CLK_100M_EDSFF2A_R_DN    R1362            1        Q_RES_0402LF-0,5%,1/16W,CHIP,CA
CLK_100M_EDSFF2A_R_DN    U38              A2       9QXL2001BNHGI8-9QXL2001BNHGI8,A
CLK_100M_EDSFF2A_R_DP    R1361            1        Q_RES_0402LF-0,5%,1/16W,CHIP,CA
CLK_100M_EDSFF2A_R_DP    U38              A3       9QXL2001BNHGI8-9QXL2001BNHGI8,A
CLK_100M_EDSFF2B_DN      J34              B14      SCONN84_123318136-SCONN84_1-23A
CLK_100M_EDSFF2B_DN      R1364            2        Q_RES_0402LF-0,5%,1/16W,CHIP,CA
CLK_100M_EDSFF2B_DP      J34              B15      SCONN84_123318136-SCONN84_1-23A
CLK_100M_EDSFF2B_DP      R1363            2        Q_RES_0402LF-0,5%,1/16W,CHIP,CA
CLK_100M_EDSFF2B_R_DN    R1364            1        Q_RES_0402LF-0,5%,1/16W,CHIP,CA
CLK_100M_EDSFF2B_R_DN    U38              B1       9QXL2001BNHGI8-9QXL2001BNHGI8,A
CLK_100M_EDSFF2B_R_DP    R1363            1        Q_RES_0402LF-0,5%,1/16W,CHIP,CA
CLK_100M_EDSFF2B_R_DP    U38              A1       9QXL2001BNHGI8-9QXL2001BNHGI8,A
CLK_100M_EDSFF3_DN       J35              B17      SCONN140_G64V3431BHR-SCONN140_B
CLK_100M_EDSFF3_DN       R1282            2        Q_RES_0402LF-0,5%,1/16W,CHIP,CA
CLK_100M_EDSFF3_DP       J35              B18      SCONN140_G64V3431BHR-SCONN140_B
CLK_100M_EDSFF3_DP       R1281            2        Q_RES_0402LF-0,5%,1/16W,CHIP,CA
CLK_100M_EDSFF3_R_DN     R1282            1        Q_RES_0402LF-0,5%,1/16W,CHIP,CA
CLK_100M_EDSFF3_R_DN     U13              A37      9SQ440NQQI8-9SQ440NQQI8,SMLF,IA
CLK_100M_EDSFF3_R_DP     R1281            1        Q_RES_0402LF-0,5%,1/16W,CHIP,CA
CLK_100M_EDSFF3_R_DP     U13              A38      9SQ440NQQI8-9SQ440NQQI8,SMLF,IA
CLK_100M_EDSFF4A_DN      J88              B14      SCONN84_123318136-SCONN84_1-23A
CLK_100M_EDSFF4A_DN      R1284            2        Q_RES_0402LF-0,5%,1/16W,CHIP,CA
CLK_100M_EDSFF4A_DP      J88              B15      SCONN84_123318136-SCONN84_1-23A
CLK_100M_EDSFF4A_DP      R1283            2        Q_RES_0402LF-0,5%,1/16W,CHIP,CA
CLK_100M_EDSFF4A_R_DN    R1284            1        Q_RES_0402LF-0,5%,1/16W,CHIP,CA
CLK_100M_EDSFF4A_R_DN    U38              D1       9QXL2001BNHGI8-9QXL2001BNHGI8,A
CLK_100M_EDSFF4A_R_DP    R1283            1        Q_RES_0402LF-0,5%,1/16W,CHIP,CA
CLK_100M_EDSFF4A_R_DP    U38              C1       9QXL2001BNHGI8-9QXL2001BNHGI8,A
CLK_100M_EDSFF4B_DN      J61              B14      SCONN84_123318136-SCONN84_1-23A
CLK_100M_EDSFF4B_DN      R2049            2        Q_RES_0402LF-0,5%,1/16W,CHIP,CA
CLK_100M_EDSFF4B_DP      J61              B15      SCONN84_123318136-SCONN84_1-23A
CLK_100M_EDSFF4B_DP      R2048            2        Q_RES_0402LF-0,5%,1/16W,CHIP,CA
CLK_100M_EDSFF4B_R_DN    R2049            1        Q_RES_0402LF-0,5%,1/16W,CHIP,CA
CLK_100M_EDSFF4B_R_DN    U38              F1       9QXL2001BNHGI8-9QXL2001BNHGI8,A
CLK_100M_EDSFF4B_R_DP    R2048            1        Q_RES_0402LF-0,5%,1/16W,CHIP,CA
CLK_100M_EDSFF4B_R_DP    U38              E1       9QXL2001BNHGI8-9QXL2001BNHGI8,A
CLK_100M_OCP_SFF_0_DN    J37              B14      SCONN168_623403212-SCONN168_6-A
CLK_100M_OCP_SFF_0_DN    R564             2        Q_RES_0402LF-0,5%,1/16W,CHIP,CA
CLK_100M_OCP_SFF_0_DP    J37              B15      SCONN168_623403212-SCONN168_6-A
CLK_100M_OCP_SFF_0_DP    R563             2        Q_RES_0402LF-0,5%,1/16W,CHIP,CA
CLK_100M_OCP_SFF_0_R_DN  R564             1        Q_RES_0402LF-0,5%,1/16W,CHIP,CA
CLK_100M_OCP_SFF_0_R_DN  U38              H12      9QXL2001BNHGI8-9QXL2001BNHGI8,A
CLK_100M_OCP_SFF_0_R_DP  R563             1        Q_RES_0402LF-0,5%,1/16W,CHIP,CA
CLK_100M_OCP_SFF_0_R_DP  U38              J12      9QXL2001BNHGI8-9QXL2001BNHGI8,A
CLK_100M_OCP_SFF_1_DN    J37              A14      SCONN168_623403212-SCONN168_6-A
CLK_100M_OCP_SFF_1_DN    R566             2        Q_RES_0402LF-0,5%,1/16W,CHIP,CA
CLK_100M_OCP_SFF_1_DP    J37              A15      SCONN168_623403212-SCONN168_6-A
CLK_100M_OCP_SFF_1_DP    R565             2        Q_RES_0402LF-0,5%,1/16W,CHIP,CA
CLK_100M_OCP_SFF_1_R_DN  R566             1        Q_RES_0402LF-0,5%,1/16W,CHIP,CA
CLK_100M_OCP_SFF_1_R_DN  U38              F12      9QXL2001BNHGI8-9QXL2001BNHGI8,A
CLK_100M_OCP_SFF_1_R_DP  R565             1        Q_RES_0402LF-0,5%,1/16W,CHIP,CA
CLK_100M_OCP_SFF_1_R_DP  U38              G12      9QXL2001BNHGI8-9QXL2001BNHGI8,A
CLK_100M_OCP_SFF_2_DN    J37              OCP_B11  SCONN168_623403212-SCONN168_6-A
CLK_100M_OCP_SFF_2_DN    R1274            2        Q_RES_0402LF-0,5%,1/16W,CHIP,CA
CLK_100M_OCP_SFF_2_DP    J37              OCP_B12  SCONN168_623403212-SCONN168_6-A
CLK_100M_OCP_SFF_2_DP    R1273            2        Q_RES_0402LF-0,5%,1/16W,CHIP,CA
CLK_100M_OCP_SFF_2_R_DN  R1274            1        Q_RES_0402LF-0,5%,1/16W,CHIP,CA
CLK_100M_OCP_SFF_2_R_DN  U38              C12      9QXL2001BNHGI8-9QXL2001BNHGI8,A
CLK_100M_OCP_SFF_2_R_DP  R1273            1        Q_RES_0402LF-0,5%,1/16W,CHIP,CA
CLK_100M_OCP_SFF_2_R_DP  U38              D12      9QXL2001BNHGI8-9QXL2001BNHGI8,A
CLK_100M_OCP_SFF_3_DN    J37              OCP_A11  SCONN168_623403212-SCONN168_6-A
CLK_100M_OCP_SFF_3_DN    R1276            2        Q_RES_0402LF-0,5%,1/16W,CHIP,CA
CLK_100M_OCP_SFF_3_DP    J37              OCP_A12  SCONN168_623403212-SCONN168_6-A
CLK_100M_OCP_SFF_3_DP    R1275            2        Q_RES_0402LF-0,5%,1/16W,CHIP,CA
CLK_100M_OCP_SFF_3_R_DN  R1276            1        Q_RES_0402LF-0,5%,1/16W,CHIP,CA
CLK_100M_OCP_SFF_3_R_DN  U38              A12      9QXL2001BNHGI8-9QXL2001BNHGI8,A
CLK_100M_OCP_SFF_3_R_DP  R1275            1        Q_RES_0402LF-0,5%,1/16W,CHIP,CA
CLK_100M_OCP_SFF_3_R_DP  U38              B12      9QXL2001BNHGI8-9QXL2001BNHGI8,A
CLK_100M_PE_0_DN         J55              A14      SCONN140_G64V3431BHR-SCONN140_A
CLK_100M_PE_0_DN         R2182            2        Q_RES_0402LF-0,5%,1/16W,CHIP,CA
CLK_100M_PE_0_DP         J55              A15      SCONN140_G64V3431BHR-SCONN140_A
CLK_100M_PE_0_DP         R2181            2        Q_RES_0402LF-0,5%,1/16W,CHIP,CA
CLK_100M_PE_0_R_DN       R2182            1        Q_RES_0402LF-0,5%,1/16W,CHIP,CA
CLK_100M_PE_0_R_DN       U13              A31      9SQ440NQQI8-9SQ440NQQI8,SMLF,IA
CLK_100M_PE_0_R_DP       R2181            1        Q_RES_0402LF-0,5%,1/16W,CHIP,CA
CLK_100M_PE_0_R_DP       U13              A32      9SQ440NQQI8-9SQ440NQQI8,SMLF,IA
CLK_100M_PE_1_DN         J55              B14      SCONN140_G64V3431BHR-SCONN140_A
CLK_100M_PE_1_DN         R2184            2        Q_RES_0402LF-0,5%,1/16W,CHIP,CA
CLK_100M_PE_1_DP         J55              B15      SCONN140_G64V3431BHR-SCONN140_A
CLK_100M_PE_1_DP         R2183            2        Q_RES_0402LF-0,5%,1/16W,CHIP,CA
CLK_100M_PE_1_R_DN       R2184            1        Q_RES_0402LF-0,5%,1/16W,CHIP,CA
CLK_100M_PE_1_R_DN       U13              A27      9SQ440NQQI8-9SQ440NQQI8,SMLF,IA
CLK_100M_PE_1_R_DP       R2183            1        Q_RES_0402LF-0,5%,1/16W,CHIP,CA
CLK_100M_PE_1_R_DP       U13              A28      9SQ440NQQI8-9SQ440NQQI8,SMLF,IA
CLK_100M_PE_2_DN         J89              A33      SCONN280_ME1028040102011-SCONNA
CLK_100M_PE_2_DN         R521             2        Q_RES_0402LF-0,5%,1/16W,CHIP,CA
CLK_100M_PE_2_DP         J89              A34      SCONN280_ME1028040102011-SCONNA
CLK_100M_PE_2_DP         R520             2        Q_RES_0402LF-0,5%,1/16W,CHIP,CA
CLK_100M_PE_2_R_DN       R521             1        Q_RES_0402LF-0,5%,1/16W,CHIP,CA
CLK_100M_PE_2_R_DN       U13              A24      9SQ440NQQI8-9SQ440NQQI8,SMLF,IA
CLK_100M_PE_2_R_DP       R520             1        Q_RES_0402LF-0,5%,1/16W,CHIP,CA
CLK_100M_PE_2_R_DP       U13              A25      9SQ440NQQI8-9SQ440NQQI8,SMLF,IA
CLK_100M_PE_3_DN         J89              B33      SCONN280_ME1028040102011-SCONNA
CLK_100M_PE_3_DN         R523             2        Q_RES_0402LF-0,5%,1/16W,CHIP,CA
CLK_100M_PE_3_DP         J89              B34      SCONN280_ME1028040102011-SCONNA
CLK_100M_PE_3_DP         R522             2        Q_RES_0402LF-0,5%,1/16W,CHIP,CA
CLK_100M_PE_3_R_DN       R523             1        Q_RES_0402LF-0,5%,1/16W,CHIP,CA
CLK_100M_PE_3_R_DN       U13              A22      9SQ440NQQI8-9SQ440NQQI8,SMLF,IA
CLK_100M_PE_3_R_DP       R522             1        Q_RES_0402LF-0,5%,1/16W,CHIP,CA
CLK_100M_PE_3_R_DP       U13              A23      9SQ440NQQI8-9SQ440NQQI8,SMLF,IA
CLK_100M_PE_4_DN         J57              A14      SCONN140_G64V3431BHR-SCONN140_A
CLK_100M_PE_4_DN         R525             2        Q_RES_0402LF-0,5%,1/16W,CHIP,CA
CLK_100M_PE_4_DP         J57              A15      SCONN140_G64V3431BHR-SCONN140_A
CLK_100M_PE_4_DP         R524             2        Q_RES_0402LF-0,5%,1/16W,CHIP,CA
CLK_100M_PE_4_R_DN       R525             1        Q_RES_0402LF-0,5%,1/16W,CHIP,CA
CLK_100M_PE_4_R_DN       U13              A20      9SQ440NQQI8-9SQ440NQQI8,SMLF,IA
CLK_100M_PE_4_R_DP       R524             1        Q_RES_0402LF-0,5%,1/16W,CHIP,CA
CLK_100M_PE_4_R_DP       U13              A21      9SQ440NQQI8-9SQ440NQQI8,SMLF,IA
CLK_100M_PE_5_DN         J57              B14      SCONN140_G64V3431BHR-SCONN140_A
CLK_100M_PE_5_DN         R527             2        Q_RES_0402LF-0,5%,1/16W,CHIP,CA
CLK_100M_PE_5_DP         J57              B15      SCONN140_G64V3431BHR-SCONN140_A
CLK_100M_PE_5_DP         R526             2        Q_RES_0402LF-0,5%,1/16W,CHIP,CA
CLK_100M_PE_5_R_DN       R527             1        Q_RES_0402LF-0,5%,1/16W,CHIP,CA
CLK_100M_PE_5_R_DN       U13              A18      9SQ440NQQI8-9SQ440NQQI8,SMLF,IA
CLK_100M_PE_5_R_DP       R526             1        Q_RES_0402LF-0,5%,1/16W,CHIP,CA
CLK_100M_PE_5_R_DP       U13              A19      9SQ440NQQI8-9SQ440NQQI8,SMLF,IA
CLK_100M_PE_M2_0_DN      J59              53       SCONN75K_APCI0155P004A-SCONN75A
CLK_100M_PE_M2_0_DN      U4               H21      EMMITSBURG_REV0P9-GFNOCPU04302A
CLK_100M_PE_M2_0_DP      J59              55       SCONN75K_APCI0155P004A-SCONN75A
CLK_100M_PE_M2_0_DP      U4               K21      EMMITSBURG_REV0P9-GFNOCPU04302A
CLK_24M_66M_LPC0_ESPI    R1872            1        Q_RES_0402LF-0,5%,1/16W,CHIP,CA
CLK_24M_66M_LPC0_ESPI    U4               BD13     EMMITSBURG_REV0P9-GFNOCPU04302A
CLK_25M_CK440_CPU0_DN    R1014            1        Q_RES_0402LF-0,5%,1/16W,CHIP,CA
CLK_25M_CK440_CPU0_DN    U13              A4       9SQ440NQQI8-9SQ440NQQI8,SMLF,IA
CLK_25M_CK440_CPU0_DP    R1012            1        Q_RES_0402LF-0,5%,1/16W,CHIP,CA
CLK_25M_CK440_CPU0_DP    U13              A5       9SQ440NQQI8-9SQ440NQQI8,SMLF,IA
CLK_25M_CK440_CPU0_R_DN  R1014            2        Q_RES_0402LF-0,5%,1/16W,CHIP,CA
CLK_25M_CK440_CPU0_R_DN  R1021            1        Q_RES_0402LF-0,5%,1/16W,CHIP,CA
CLK_25M_CK440_CPU0_R_DP  R1012            2        Q_RES_0402LF-0,5%,1/16W,CHIP,CA
CLK_25M_CK440_CPU0_R_DP  R1020            1        Q_RES_0402LF-0,5%,1/16W,CHIP,CA
CLK_25M_CK440_CPU1_DN    R1018            1        Q_RES_0402LF-0,5%,1/16W,CHIP,CA
CLK_25M_CK440_CPU1_DN    U13              A2       9SQ440NQQI8-9SQ440NQQI8,SMLF,IA
CLK_25M_CK440_CPU1_DP    R1016            1        Q_RES_0402LF-0,5%,1/16W,CHIP,CA
CLK_25M_CK440_CPU1_DP    U13              A3       9SQ440NQQI8-9SQ440NQQI8,SMLF,IA
CLK_25M_CK440_CPU1_R_DN  R1018            2        Q_RES_0402LF-0,5%,1/16W,CHIP,CA
CLK_25M_CK440_CPU1_R_DN  R1023            1        Q_RES_0402LF-0,5%,1/16W,CHIP,CA
CLK_25M_CK440_CPU1_R_DP  R1016            2        Q_RES_0402LF-0,5%,1/16W,CHIP,CA
CLK_25M_CK440_CPU1_R_DP  R1022            1        Q_RES_0402LF-0,5%,1/16W,CHIP,CA
CLK_25M_CK440_ISCLK_REF_DN R1011            1        Q_RES_0402LF-0,5%,1/16W,CHIP,CA
CLK_25M_CK440_ISCLK_REF_DN U13              A55      9SQ440NQQI8-9SQ440NQQI8,SMLF,IA
CLK_25M_CK440_ISCLK_REF_DP R1010            1        Q_RES_0402LF-0,5%,1/16W,CHIP,CA
CLK_25M_CK440_ISCLK_REF_DP U13              A56      9SQ440NQQI8-9SQ440NQQI8,SMLF,IA
CLK_25M_NSSC_CPU0_DN     R1015            2        Q_RES_0402LF-0,5%,1/16W,EMPTY,A
CLK_25M_NSSC_CPU0_DN     R1021            2        Q_RES_0402LF-0,5%,1/16W,CHIP,CA
CLK_25M_NSSC_CPU0_DN     U2               CW31     SOCKET4677_AZIFS054P001C01-SOCA
CLK_25M_NSSC_CPU0_DP     R1013            2        Q_RES_0402LF-0,5%,1/16W,EMPTY,A
CLK_25M_NSSC_CPU0_DP     R1020            2        Q_RES_0402LF-0,5%,1/16W,CHIP,CA
CLK_25M_NSSC_CPU0_DP     U2               CY32     SOCKET4677_AZIFS054P001C01-SOCA
CLK_25M_NSSC_CPU1_DN     R1019            2        Q_RES_0402LF-0,5%,1/16W,EMPTY,A
CLK_25M_NSSC_CPU1_DN     R1023            2        Q_RES_0402LF-0,5%,1/16W,CHIP,CA
CLK_25M_NSSC_CPU1_DN     U1               CW31     SOCKET4677_AZIFS054P001C01-SOCA
CLK_25M_NSSC_CPU1_DP     R1017            2        Q_RES_0402LF-0,5%,1/16W,EMPTY,A
CLK_25M_NSSC_CPU1_DP     R1022            2        Q_RES_0402LF-0,5%,1/16W,CHIP,CA
CLK_25M_NSSC_CPU1_DP     U1               CY32     SOCKET4677_AZIFS054P001C01-SOCA
CLK_25M_OSC_FPGA_R       OSC2             3        Q_OSC4P_SMLF-25MHZ,OSC,BF62500A
CLK_25M_OSC_FPGA_R       R1100            1        Q_RES_0402LF-33.2,1%,1/16W,CHIA
CLK_25M_OSC_MAIN_FPGA    R1100            2        Q_RES_0402LF-33.2,1%,1/16W,CHIA
CLK_25M_OSC_MAIN_FPGA    U122             L3       10M04SAU324I7G-10M04SAU324I7G,A
CLK_25M_PCH_CPU0_DN      R1015            1        Q_RES_0402LF-0,5%,1/16W,EMPTY,A
CLK_25M_PCH_CPU0_DN      U4               D27      EMMITSBURG_REV0P9-GFNOCPU04302A
CLK_25M_PCH_CPU0_DP      R1013            1        Q_RES_0402LF-0,5%,1/16W,EMPTY,A
CLK_25M_PCH_CPU0_DP      U4               B27      EMMITSBURG_REV0P9-GFNOCPU04302A
CLK_25M_PCH_CPU1_DN      R1019            1        Q_RES_0402LF-0,5%,1/16W,EMPTY,A
CLK_25M_PCH_CPU1_DN      U4               C28      EMMITSBURG_REV0P9-GFNOCPU04302A
CLK_25M_PCH_CPU1_DP      R1017            1        Q_RES_0402LF-0,5%,1/16W,EMPTY,A
CLK_25M_PCH_CPU1_DP      U4               A28      EMMITSBURG_REV0P9-GFNOCPU04302A
CLK_25M_PCH_REF_NS_DN    R1011            2        Q_RES_0402LF-0,5%,1/16W,CHIP,CA
CLK_25M_PCH_REF_NS_DN    U4               D25      EMMITSBURG_REV0P9-GFNOCPU04302A
CLK_25M_PCH_REF_NS_DP    R1010            2        Q_RES_0402LF-0,5%,1/16W,CHIP,CA
CLK_25M_PCH_REF_NS_DP    U4               B25      EMMITSBURG_REV0P9-GFNOCPU04302A
CLK_50M_BMC_MAC_R        R1140            1        Q_RES_0402LF-27.4,1%,1/16W,CHIA
CLK_50M_BMC_MAC_R        U90              3        PI6CV304LE-PI6CV304LE,SMLF,IC,A
CLK_50M_EN               OSC1             1        OSC4_SIT1602AI2233E50000000D-5A
CLK_50M_EN               R1138            2        Q_RES_0402LF-10K,1%,1/16W,CHIPA
CLK_50M_EN               U90              2        PI6CV304LE-PI6CV304LE,SMLF,IC,A
CLK_50M_NCSI_OCP_1       R1141            1        Q_RES_0402LF-27.4,1%,1/16W,CHIA
CLK_50M_NCSI_OCP_1       U90              5        PI6CV304LE-PI6CV304LE,SMLF,IC,A
CLK_50M_NCSI_OCP_SFF     J37              OCP_A14  SCONN168_623403212-SCONN168_6-A
CLK_50M_NCSI_OCP_SFF     R1141            2        Q_RES_0402LF-27.4,1%,1/16W,CHIA
CLK_50M_RMII             OSC1             3        OSC4_SIT1602AI2233E50000000D-5A
CLK_50M_RMII             R1139            1        Q_RES_0402LF-0,5%,1/16W,CHIP,CA
CLK_50M_RMII_BMC_OCP     J41              B18      SCONN168_623403212-SCONN168_6-A
CLK_50M_RMII_BMC_OCP     R1140            2        Q_RES_0402LF-27.4,1%,1/16W,CHIA
CLK_50M_RMII_R           R1139            2        Q_RES_0402LF-0,5%,1/16W,CHIP,CA
CLK_50M_RMII_R           U90              1        PI6CV304LE-PI6CV304LE,SMLF,IC,A
CLK_CK440_SMB_ADDR0      R912             2        Q_RES_0402LF-4.75K,1%,1/16W,EMA
CLK_CK440_SMB_ADDR0      R953             1        Q_RES_0402LF-4.75K,1%,1/16W,CHA
CLK_CK440_SMB_ADDR0      U13              A11      9SQ440NQQI8-9SQ440NQQI8,SMLF,IA
CLK_CK440_SMB_ADDR1      R562             2        Q_RES_0402LF-4.75K,1%,1/16W,EMA
CLK_CK440_SMB_ADDR1      R734             1        Q_RES_0402LF-4.75K,1%,1/16W,CHA
CLK_CK440_SMB_ADDR1      U13              B9       9SQ440NQQI8-9SQ440NQQI8,SMLF,IA
CPU_RMCA_CATERR_LVT3_N   Q33              G        MOSFET_PCH_GDS_ESD_PROTECTED-PA
CPU_RMCA_CATERR_LVT3_N   R365             2        Q_RES_0402LF-0,5%,1/16W,CHIP,CA
DBP_CPU0_HOOK8_MBP2_GTL_QS_R_N R24              1        Q_RES_0402LF-10,1%,1/16W,CHIP,A
DBP_CPU0_HOOK8_MBP2_GTL_QS_R_N U2               BJ23     SOCKET4677_AZIFS054P001C01-SOCA
DBP_CPU0_HOOK9_MBP3_GTL_QS_R_N R25              1        Q_RES_0402LF-10,1%,1/16W,CHIP,A
DBP_CPU0_HOOK9_MBP3_GTL_QS_R_N U2               BK24     SOCKET4677_AZIFS054P001C01-SOCA
DBP_CPU0_MBP0_GTL_R_N    R22              1        Q_RES_0402LF-100,1%,1/16W,CHIPA
DBP_CPU0_MBP0_GTL_R_N    U2               BL23     SOCKET4677_AZIFS054P001C01-SOCA
DBP_CPU0_MBP1_GTL_R_N    R23              1        Q_RES_0402LF-100,1%,1/16W,CHIPA
DBP_CPU0_MBP1_GTL_R_N    U2               BN25     SOCKET4677_AZIFS054P001C01-SOCA
DBP_CPU1_HOOK8_MBP2_GTL_QS_R_N R53              1        Q_RES_0402LF-10,1%,1/16W,CHIP,A
DBP_CPU1_HOOK8_MBP2_GTL_QS_R_N U1               BJ23     SOCKET4677_AZIFS054P001C01-SOCA
DBP_CPU1_HOOK9_MBP3_GTL_QS_R_N R54              1        Q_RES_0402LF-10,1%,1/16W,CHIP,A
DBP_CPU1_HOOK9_MBP3_GTL_QS_R_N U1               BK24     SOCKET4677_AZIFS054P001C01-SOCA
DBP_CPU1_MBP0_GTL_R_N    R51              1        Q_RES_0402LF-100,1%,1/16W,CHIPA
DBP_CPU1_MBP0_GTL_R_N    U1               BL23     SOCKET4677_AZIFS054P001C01-SOCA
DBP_CPU1_MBP1_GTL_R_N    R52              1        Q_RES_0402LF-100,1%,1/16W,CHIPA
DBP_CPU1_MBP1_GTL_R_N    U1               BN25     SOCKET4677_AZIFS054P001C01-SOCA
DBP_CPU_HOOK8_MBP2_GTL_QS_N R24              2        Q_RES_0402LF-10,1%,1/16W,CHIP,A
DBP_CPU_HOOK8_MBP2_GTL_QS_N R53              2        Q_RES_0402LF-10,1%,1/16W,CHIP,A
DBP_CPU_HOOK8_MBP2_GTL_QS_N R760             2        Q_RES_0402LF-499,1%,1/16W,CHIPA
DBP_CPU_HOOK8_MBP2_GTL_QS_N U18              6        74CBTLV3126PW-74CBTLV3126PW,SMA
DBP_CPU_HOOK9_MBP3_GTL_QS_N R25              2        Q_RES_0402LF-10,1%,1/16W,CHIP,A
DBP_CPU_HOOK9_MBP3_GTL_QS_N R54              2        Q_RES_0402LF-10,1%,1/16W,CHIP,A
DBP_CPU_HOOK9_MBP3_GTL_QS_N R761             2        Q_RES_0402LF-499,1%,1/16W,CHIPA
DBP_CPU_HOOK9_MBP3_GTL_QS_N U18              3        74CBTLV3126PW-74CBTLV3126PW,SMA
DBP_CPU_MBP0_GTL_N       R18              2        Q_RES_0402LF-499,1%,1/16W,CHIPA
DBP_CPU_MBP0_GTL_N       R20              1        Q_RES_0402LF-0,5%,1/16W,CHIP,CA
DBP_CPU_MBP0_GTL_N       R22              2        Q_RES_0402LF-100,1%,1/16W,CHIPA
DBP_CPU_MBP0_GTL_N       R49              2        Q_RES_0402LF-499,1%,1/16W,CHIPA
DBP_CPU_MBP0_GTL_N       R51              2        Q_RES_0402LF-100,1%,1/16W,CHIPA
DBP_CPU_MBP1_GTL_N       R19              2        Q_RES_0402LF-499,1%,1/16W,CHIPA
DBP_CPU_MBP1_GTL_N       R21              1        Q_RES_0402LF-0,5%,1/16W,CHIP,CA
DBP_CPU_MBP1_GTL_N       R23              2        Q_RES_0402LF-100,1%,1/16W,CHIPA
DBP_CPU_MBP1_GTL_N       R50              2        Q_RES_0402LF-499,1%,1/16W,CHIPA
DBP_CPU_MBP1_GTL_N       R52              2        Q_RES_0402LF-100,1%,1/16W,CHIPA
DELTA_L_85_10INCH_BOT_DN J76              2        DELTA_L-DELTA-L,THLF,EMPTY,TP24
DELTA_L_85_10INCH_BOT_DN J82              1        DELTA_L-DELTA-L,THLF,EMPTY,TP24
DELTA_L_85_10INCH_BOT_DP J76              1        DELTA_L-DELTA-L,THLF,EMPTY,TP24
DELTA_L_85_10INCH_BOT_DP J82              2        DELTA_L-DELTA-L,THLF,EMPTY,TP24
DELTA_L_85_10INCH_IN1_DN J77              2        DELTA_L-DELTA-L,THLF,EMPTY,TP24
DELTA_L_85_10INCH_IN1_DN J83              1        DELTA_L-DELTA-L,THLF,EMPTY,TP24
DELTA_L_85_10INCH_IN1_DP J77              1        DELTA_L-DELTA-L,THLF,EMPTY,TP24
DELTA_L_85_10INCH_IN1_DP J83              2        DELTA_L-DELTA-L,THLF,EMPTY,TP24
DELTA_L_85_10INCH_IN2_DN J78              2        DELTA_L-DELTA-L,THLF,EMPTY,TP24
DELTA_L_85_10INCH_IN2_DN J84              1        DELTA_L-DELTA-L,THLF,EMPTY,TP24
DELTA_L_85_10INCH_IN2_DP J78              1        DELTA_L-DELTA-L,THLF,EMPTY,TP24
DELTA_L_85_10INCH_IN2_DP J84              2        DELTA_L-DELTA-L,THLF,EMPTY,TP24
DELTA_L_85_10INCH_IN3_DN J79              2        DELTA_L-DELTA-L,THLF,EMPTY,TP24
DELTA_L_85_10INCH_IN3_DN J85              1        DELTA_L-DELTA-L,THLF,EMPTY,TP24
DELTA_L_85_10INCH_IN3_DP J79              1        DELTA_L-DELTA-L,THLF,EMPTY,TP24
DELTA_L_85_10INCH_IN3_DP J85              2        DELTA_L-DELTA-L,THLF,EMPTY,TP24
DELTA_L_85_10INCH_IN4_DN J80              2        DELTA_L-DELTA-L,THLF,EMPTY,TP24
DELTA_L_85_10INCH_IN4_DN J86              1        DELTA_L-DELTA-L,THLF,EMPTY,TP24
DELTA_L_85_10INCH_IN4_DP J80              1        DELTA_L-DELTA-L,THLF,EMPTY,TP24
DELTA_L_85_10INCH_IN4_DP J86              2        DELTA_L-DELTA-L,THLF,EMPTY,TP24
DELTA_L_85_10INCH_TOP_DN J75              2        DELTA_L-DELTA-L,THLF,EMPTY,TP24
DELTA_L_85_10INCH_TOP_DN J81              1        DELTA_L-DELTA-L,THLF,EMPTY,TP24
DELTA_L_85_10INCH_TOP_DP J75              1        DELTA_L-DELTA-L,THLF,EMPTY,TP24
DELTA_L_85_10INCH_TOP_DP J81              2        DELTA_L-DELTA-L,THLF,EMPTY,TP24
DELTA_L_85_5INCH_BOT_DN  J64              2        DELTA_L-DELTA-L,THLF,EMPTY,TP24
DELTA_L_85_5INCH_BOT_DN  J70              1        DELTA_L-DELTA-L,THLF,EMPTY,TP24
DELTA_L_85_5INCH_BOT_DP  J64              1        DELTA_L-DELTA-L,THLF,EMPTY,TP24
DELTA_L_85_5INCH_BOT_DP  J70              2        DELTA_L-DELTA-L,THLF,EMPTY,TP24
DELTA_L_85_5INCH_IN1_DN  J65              2        DELTA_L-DELTA-L,THLF,EMPTY,TP24
DELTA_L_85_5INCH_IN1_DN  J71              1        DELTA_L-DELTA-L,THLF,EMPTY,TP24
DELTA_L_85_5INCH_IN1_DP  J65              1        DELTA_L-DELTA-L,THLF,EMPTY,TP24
DELTA_L_85_5INCH_IN1_DP  J71              2        DELTA_L-DELTA-L,THLF,EMPTY,TP24
DELTA_L_85_5INCH_IN2_DN  J66              2        DELTA_L-DELTA-L,THLF,EMPTY,TP24
DELTA_L_85_5INCH_IN2_DN  J72              1        DELTA_L-DELTA-L,THLF,EMPTY,TP24
DELTA_L_85_5INCH_IN2_DP  J66              1        DELTA_L-DELTA-L,THLF,EMPTY,TP24
DELTA_L_85_5INCH_IN2_DP  J72              2        DELTA_L-DELTA-L,THLF,EMPTY,TP24
DELTA_L_85_5INCH_IN3_DN  J67              2        DELTA_L-DELTA-L,THLF,EMPTY,TP24
DELTA_L_85_5INCH_IN3_DN  J73              1        DELTA_L-DELTA-L,THLF,EMPTY,TP24
DELTA_L_85_5INCH_IN3_DP  J67              1        DELTA_L-DELTA-L,THLF,EMPTY,TP24
DELTA_L_85_5INCH_IN3_DP  J73              2        DELTA_L-DELTA-L,THLF,EMPTY,TP24
DELTA_L_85_5INCH_IN4_DN  J68              2        DELTA_L-DELTA-L,THLF,EMPTY,TP24
DELTA_L_85_5INCH_IN4_DN  J74              1        DELTA_L-DELTA-L,THLF,EMPTY,TP24
DELTA_L_85_5INCH_IN4_DP  J68              1        DELTA_L-DELTA-L,THLF,EMPTY,TP24
DELTA_L_85_5INCH_IN4_DP  J74              2        DELTA_L-DELTA-L,THLF,EMPTY,TP24
DELTA_L_85_5INCH_TOP_DN  J63              2        DELTA_L-DELTA-L,THLF,EMPTY,TP24
DELTA_L_85_5INCH_TOP_DN  J69              1        DELTA_L-DELTA-L,THLF,EMPTY,TP24
DELTA_L_85_5INCH_TOP_DP  J63              1        DELTA_L-DELTA-L,THLF,EMPTY,TP24
DELTA_L_85_5INCH_TOP_DP  J69              2        DELTA_L-DELTA-L,THLF,EMPTY,TP24
DELTA_L_GND              J65              3        DELTA_L-DELTA-L,THLF,EMPTY,TP24
DELTA_L_GND              J66              3        DELTA_L-DELTA-L,THLF,EMPTY,TP24
DELTA_L_GND              J67              3        DELTA_L-DELTA-L,THLF,EMPTY,TP24
DELTA_L_GND              J71              3        DELTA_L-DELTA-L,THLF,EMPTY,TP24
DELTA_L_GND              J72              3        DELTA_L-DELTA-L,THLF,EMPTY,TP24
DELTA_L_GND              J73              3        DELTA_L-DELTA-L,THLF,EMPTY,TP24
DELTA_L_GND              J77              3        DELTA_L-DELTA-L,THLF,EMPTY,TP24
DELTA_L_GND              J80              3        DELTA_L-DELTA-L,THLF,EMPTY,TP24
DELTA_L_GND              J83              3        DELTA_L-DELTA-L,THLF,EMPTY,TP24
DELTA_L_GND              J86              3        DELTA_L-DELTA-L,THLF,EMPTY,TP24
DELTA_R_GND              J63              3        DELTA_L-DELTA-L,THLF,EMPTY,TP24
DELTA_R_GND              J64              3        DELTA_L-DELTA-L,THLF,EMPTY,TP24
DELTA_R_GND              J68              3        DELTA_L-DELTA-L,THLF,EMPTY,TP24
DELTA_R_GND              J69              3        DELTA_L-DELTA-L,THLF,EMPTY,TP24
DELTA_R_GND              J70              3        DELTA_L-DELTA-L,THLF,EMPTY,TP24
DELTA_R_GND              J74              3        DELTA_L-DELTA-L,THLF,EMPTY,TP24
DELTA_R_GND              J75              3        DELTA_L-DELTA-L,THLF,EMPTY,TP24
DELTA_R_GND              J76              3        DELTA_L-DELTA-L,THLF,EMPTY,TP24
DELTA_R_GND              J78              3        DELTA_L-DELTA-L,THLF,EMPTY,TP24
DELTA_R_GND              J79              3        DELTA_L-DELTA-L,THLF,EMPTY,TP24
DELTA_R_GND              J81              3        DELTA_L-DELTA-L,THLF,EMPTY,TP24
DELTA_R_GND              J82              3        DELTA_L-DELTA-L,THLF,EMPTY,TP24
DELTA_R_GND              J84              3        DELTA_L-DELTA-L,THLF,EMPTY,TP24
DELTA_R_GND              J85              3        DELTA_L-DELTA-L,THLF,EMPTY,TP24
DMI_CPU0_PCH_RX_C_DN<0>  C169             1        Q_CAP_DIFFBUS_C0201-DIFF BUS_0A
DMI_CPU0_PCH_RX_C_DN<0>  U2               BB18     SOCKET4677_AZIFS054P001C01-SOCA
DMI_CPU0_PCH_RX_C_DN<1>  C167             1        Q_CAP_DIFFBUS_C0201-DIFF BUS_0A
DMI_CPU0_PCH_RX_C_DN<1>  U2               BD18     SOCKET4677_AZIFS054P001C01-SOCA
DMI_CPU0_PCH_RX_C_DN<2>  C165             1        Q_CAP_DIFFBUS_C0201-DIFF BUS_0A
DMI_CPU0_PCH_RX_C_DN<2>  U2               BF18     SOCKET4677_AZIFS054P001C01-SOCA
DMI_CPU0_PCH_RX_C_DN<3>  C163             1        Q_CAP_DIFFBUS_C0201-DIFF BUS_0A
DMI_CPU0_PCH_RX_C_DN<3>  U2               BH18     SOCKET4677_AZIFS054P001C01-SOCA
DMI_CPU0_PCH_RX_C_DN<4>  C161             1        Q_CAP_DIFFBUS_C0201-DIFF BUS_0A
DMI_CPU0_PCH_RX_C_DN<4>  U2               BL19     SOCKET4677_AZIFS054P001C01-SOCA
DMI_CPU0_PCH_RX_C_DN<5>  C159             1        Q_CAP_DIFFBUS_C0201-DIFF BUS_0A
DMI_CPU0_PCH_RX_C_DN<5>  U2               BM18     SOCKET4677_AZIFS054P001C01-SOCA
DMI_CPU0_PCH_RX_C_DN<6>  C157             1        Q_CAP_DIFFBUS_C0201-DIFF BUS_0A
DMI_CPU0_PCH_RX_C_DN<6>  U2               BR19     SOCKET4677_AZIFS054P001C01-SOCA
DMI_CPU0_PCH_RX_C_DN<7>  C155             1        Q_CAP_DIFFBUS_C0201-DIFF BUS_0A
DMI_CPU0_PCH_RX_C_DN<7>  U2               BU17     SOCKET4677_AZIFS054P001C01-SOCA
DMI_CPU0_PCH_RX_C_DP<0>  C170             1        Q_CAP_DIFFBUS_C0201-DIFF BUS_0A
DMI_CPU0_PCH_RX_C_DP<0>  U2               BC19     SOCKET4677_AZIFS054P001C01-SOCA
DMI_CPU0_PCH_RX_C_DP<1>  C168             1        Q_CAP_DIFFBUS_C0201-DIFF BUS_0A
DMI_CPU0_PCH_RX_C_DP<1>  U2               BE17     SOCKET4677_AZIFS054P001C01-SOCA
DMI_CPU0_PCH_RX_C_DP<2>  C166             1        Q_CAP_DIFFBUS_C0201-DIFF BUS_0A
DMI_CPU0_PCH_RX_C_DP<2>  U2               BG19     SOCKET4677_AZIFS054P001C01-SOCA
DMI_CPU0_PCH_RX_C_DP<3>  C164             1        Q_CAP_DIFFBUS_C0201-DIFF BUS_0A
DMI_CPU0_PCH_RX_C_DP<3>  U2               BJ17     SOCKET4677_AZIFS054P001C01-SOCA
DMI_CPU0_PCH_RX_C_DP<4>  C162             1        Q_CAP_DIFFBUS_C0201-DIFF BUS_0A
DMI_CPU0_PCH_RX_C_DP<4>  U2               BK18     SOCKET4677_AZIFS054P001C01-SOCA
DMI_CPU0_PCH_RX_C_DP<5>  C160             1        Q_CAP_DIFFBUS_C0201-DIFF BUS_0A
DMI_CPU0_PCH_RX_C_DP<5>  U2               BN17     SOCKET4677_AZIFS054P001C01-SOCA
DMI_CPU0_PCH_RX_C_DP<6>  C158             1        Q_CAP_DIFFBUS_C0201-DIFF BUS_0A
DMI_CPU0_PCH_RX_C_DP<6>  U2               BP18     SOCKET4677_AZIFS054P001C01-SOCA
DMI_CPU0_PCH_RX_C_DP<7>  C156             1        Q_CAP_DIFFBUS_C0201-DIFF BUS_0A
DMI_CPU0_PCH_RX_C_DP<7>  U2               BT18     SOCKET4677_AZIFS054P001C01-SOCA
DMI_CPU0_PCH_RX_DN<0>    C169             2        Q_CAP_DIFFBUS_C0201-DIFF BUS_0A
DMI_CPU0_PCH_RX_DN<0>    U4               K28      EMMITSBURG_REV0P9-GFNOCPU04302A
DMI_CPU0_PCH_RX_DN<1>    C167             2        Q_CAP_DIFFBUS_C0201-DIFF BUS_0A
DMI_CPU0_PCH_RX_DN<1>    U4               G29      EMMITSBURG_REV0P9-GFNOCPU04302A
DMI_CPU0_PCH_RX_DN<2>    C165             2        Q_CAP_DIFFBUS_C0201-DIFF BUS_0A
DMI_CPU0_PCH_RX_DN<2>    U4               J29      EMMITSBURG_REV0P9-GFNOCPU04302A
DMI_CPU0_PCH_RX_DN<3>    C163             2        Q_CAP_DIFFBUS_C0201-DIFF BUS_0A
DMI_CPU0_PCH_RX_DN<3>    U4               L32      EMMITSBURG_REV0P9-GFNOCPU04302A
DMI_CPU0_PCH_RX_DN<4>    C161             2        Q_CAP_DIFFBUS_C0201-DIFF BUS_0A
DMI_CPU0_PCH_RX_DN<4>    U4               J32      EMMITSBURG_REV0P9-GFNOCPU04302A
DMI_CPU0_PCH_RX_DN<5>    C159             2        Q_CAP_DIFFBUS_C0201-DIFF BUS_0A
DMI_CPU0_PCH_RX_DN<5>    U4               G36      EMMITSBURG_REV0P9-GFNOCPU04302A
DMI_CPU0_PCH_RX_DN<6>    C157             2        Q_CAP_DIFFBUS_C0201-DIFF BUS_0A
DMI_CPU0_PCH_RX_DN<6>    U4               K37      EMMITSBURG_REV0P9-GFNOCPU04302A
DMI_CPU0_PCH_RX_DN<7>    C155             2        Q_CAP_DIFFBUS_C0201-DIFF BUS_0A
DMI_CPU0_PCH_RX_DN<7>    U4               F37      EMMITSBURG_REV0P9-GFNOCPU04302A
DMI_CPU0_PCH_RX_DP<0>    C170             2        Q_CAP_DIFFBUS_C0201-DIFF BUS_0A
DMI_CPU0_PCH_RX_DP<0>    U4               H28      EMMITSBURG_REV0P9-GFNOCPU04302A
DMI_CPU0_PCH_RX_DP<1>    C168             2        Q_CAP_DIFFBUS_C0201-DIFF BUS_0A
DMI_CPU0_PCH_RX_DP<1>    U4               F28      EMMITSBURG_REV0P9-GFNOCPU04302A
DMI_CPU0_PCH_RX_DP<2>    C166             2        Q_CAP_DIFFBUS_C0201-DIFF BUS_0A
DMI_CPU0_PCH_RX_DP<2>    U4               H31      EMMITSBURG_REV0P9-GFNOCPU04302A
DMI_CPU0_PCH_RX_DP<3>    C164             2        Q_CAP_DIFFBUS_C0201-DIFF BUS_0A
DMI_CPU0_PCH_RX_DP<3>    U4               K31      EMMITSBURG_REV0P9-GFNOCPU04302A
DMI_CPU0_PCH_RX_DP<4>    C162             2        Q_CAP_DIFFBUS_C0201-DIFF BUS_0A
DMI_CPU0_PCH_RX_DP<4>    U4               G32      EMMITSBURG_REV0P9-GFNOCPU04302A
DMI_CPU0_PCH_RX_DP<5>    C160             2        Q_CAP_DIFFBUS_C0201-DIFF BUS_0A
DMI_CPU0_PCH_RX_DP<5>    U4               H34      EMMITSBURG_REV0P9-GFNOCPU04302A
DMI_CPU0_PCH_RX_DP<6>    C158             2        Q_CAP_DIFFBUS_C0201-DIFF BUS_0A
DMI_CPU0_PCH_RX_DP<6>    U4               J36      EMMITSBURG_REV0P9-GFNOCPU04302A
DMI_CPU0_PCH_RX_DP<7>    C156             2        Q_CAP_DIFFBUS_C0201-DIFF BUS_0A
DMI_CPU0_PCH_RX_DP<7>    U4               H37      EMMITSBURG_REV0P9-GFNOCPU04302A
DMI_CPU0_PCH_TX_C_DN<0>  C153             1        Q_CAP_DIFFBUS_C0201-DIFF BUS_0A
DMI_CPU0_PCH_TX_C_DN<0>  U4               A30      EMMITSBURG_REV0P9-GFNOCPU04302A
DMI_CPU0_PCH_TX_C_DN<1>  C151             1        Q_CAP_DIFFBUS_C0201-DIFF BUS_0A
DMI_CPU0_PCH_TX_C_DN<1>  U4               B31      EMMITSBURG_REV0P9-GFNOCPU04302A
DMI_CPU0_PCH_TX_C_DN<2>  C149             1        Q_CAP_DIFFBUS_C0201-DIFF BUS_0A
DMI_CPU0_PCH_TX_C_DN<2>  U4               A32      EMMITSBURG_REV0P9-GFNOCPU04302A
DMI_CPU0_PCH_TX_C_DN<3>  C147             1        Q_CAP_DIFFBUS_C0201-DIFF BUS_0A
DMI_CPU0_PCH_TX_C_DN<3>  U4               B33      EMMITSBURG_REV0P9-GFNOCPU04302A
DMI_CPU0_PCH_TX_C_DN<4>  C145             1        Q_CAP_DIFFBUS_C0201-DIFF BUS_0A
DMI_CPU0_PCH_TX_C_DN<4>  U4               A34      EMMITSBURG_REV0P9-GFNOCPU04302A
DMI_CPU0_PCH_TX_C_DN<5>  C143             1        Q_CAP_DIFFBUS_C0201-DIFF BUS_0A
DMI_CPU0_PCH_TX_C_DN<5>  U4               B35      EMMITSBURG_REV0P9-GFNOCPU04302A
DMI_CPU0_PCH_TX_C_DN<6>  C141             1        Q_CAP_DIFFBUS_C0201-DIFF BUS_0A
DMI_CPU0_PCH_TX_C_DN<6>  U4               A36      EMMITSBURG_REV0P9-GFNOCPU04302A
DMI_CPU0_PCH_TX_C_DN<7>  C139             1        Q_CAP_DIFFBUS_C0201-DIFF BUS_0A
DMI_CPU0_PCH_TX_C_DN<7>  U4               B37      EMMITSBURG_REV0P9-GFNOCPU04302A
DMI_CPU0_PCH_TX_C_DP<0>  C154             1        Q_CAP_DIFFBUS_C0201-DIFF BUS_0A
DMI_CPU0_PCH_TX_C_DP<0>  U4               C30      EMMITSBURG_REV0P9-GFNOCPU04302A
DMI_CPU0_PCH_TX_C_DP<1>  C152             1        Q_CAP_DIFFBUS_C0201-DIFF BUS_0A
DMI_CPU0_PCH_TX_C_DP<1>  U4               D31      EMMITSBURG_REV0P9-GFNOCPU04302A
DMI_CPU0_PCH_TX_C_DP<2>  C150             1        Q_CAP_DIFFBUS_C0201-DIFF BUS_0A
DMI_CPU0_PCH_TX_C_DP<2>  U4               C32      EMMITSBURG_REV0P9-GFNOCPU04302A
DMI_CPU0_PCH_TX_C_DP<3>  C148             1        Q_CAP_DIFFBUS_C0201-DIFF BUS_0A
DMI_CPU0_PCH_TX_C_DP<3>  U4               D33      EMMITSBURG_REV0P9-GFNOCPU04302A
DMI_CPU0_PCH_TX_C_DP<4>  C146             1        Q_CAP_DIFFBUS_C0201-DIFF BUS_0A
DMI_CPU0_PCH_TX_C_DP<4>  U4               C34      EMMITSBURG_REV0P9-GFNOCPU04302A
DMI_CPU0_PCH_TX_C_DP<5>  C144             1        Q_CAP_DIFFBUS_C0201-DIFF BUS_0A
DMI_CPU0_PCH_TX_C_DP<5>  U4               D35      EMMITSBURG_REV0P9-GFNOCPU04302A
DMI_CPU0_PCH_TX_C_DP<6>  C142             1        Q_CAP_DIFFBUS_C0201-DIFF BUS_0A
DMI_CPU0_PCH_TX_C_DP<6>  U4               C36      EMMITSBURG_REV0P9-GFNOCPU04302A
DMI_CPU0_PCH_TX_C_DP<7>  C140             1        Q_CAP_DIFFBUS_C0201-DIFF BUS_0A
DMI_CPU0_PCH_TX_C_DP<7>  U4               D37      EMMITSBURG_REV0P9-GFNOCPU04302A
DMI_CPU0_PCH_TX_DN<0>    C153             2        Q_CAP_DIFFBUS_C0201-DIFF BUS_0A
DMI_CPU0_PCH_TX_DN<0>    U2               CA19     SOCKET4677_AZIFS054P001C01-SOCA
DMI_CPU0_PCH_TX_DN<1>    C151             2        Q_CAP_DIFFBUS_C0201-DIFF BUS_0A
DMI_CPU0_PCH_TX_DN<1>    U2               BY18     SOCKET4677_AZIFS054P001C01-SOCA
DMI_CPU0_PCH_TX_DN<2>    C149             2        Q_CAP_DIFFBUS_C0201-DIFF BUS_0A
DMI_CPU0_PCH_TX_DN<2>    U2               CC19     SOCKET4677_AZIFS054P001C01-SOCA
DMI_CPU0_PCH_TX_DN<3>    C147             2        Q_CAP_DIFFBUS_C0201-DIFF BUS_0A
DMI_CPU0_PCH_TX_DN<3>    U2               CE17     SOCKET4677_AZIFS054P001C01-SOCA
DMI_CPU0_PCH_TX_DN<4>    C145             2        Q_CAP_DIFFBUS_C0201-DIFF BUS_0A
DMI_CPU0_PCH_TX_DN<4>    U2               CF18     SOCKET4677_AZIFS054P001C01-SOCA
DMI_CPU0_PCH_TX_DN<5>    C143             2        Q_CAP_DIFFBUS_C0201-DIFF BUS_0A
DMI_CPU0_PCH_TX_DN<5>    U2               CJ17     SOCKET4677_AZIFS054P001C01-SOCA
DMI_CPU0_PCH_TX_DN<6>    C141             2        Q_CAP_DIFFBUS_C0201-DIFF BUS_0A
DMI_CPU0_PCH_TX_DN<6>    U2               CL19     SOCKET4677_AZIFS054P001C01-SOCA
DMI_CPU0_PCH_TX_DN<7>    C139             2        Q_CAP_DIFFBUS_C0201-DIFF BUS_0A
DMI_CPU0_PCH_TX_DN<7>    U2               CM18     SOCKET4677_AZIFS054P001C01-SOCA
DMI_CPU0_PCH_TX_DP<0>    C154             2        Q_CAP_DIFFBUS_C0201-DIFF BUS_0A
DMI_CPU0_PCH_TX_DP<0>    U2               BW19     SOCKET4677_AZIFS054P001C01-SOCA
DMI_CPU0_PCH_TX_DP<1>    C152             2        Q_CAP_DIFFBUS_C0201-DIFF BUS_0A
DMI_CPU0_PCH_TX_DP<1>    U2               CA17     SOCKET4677_AZIFS054P001C01-SOCA
DMI_CPU0_PCH_TX_DP<2>    C150             2        Q_CAP_DIFFBUS_C0201-DIFF BUS_0A
DMI_CPU0_PCH_TX_DP<2>    U2               CB18     SOCKET4677_AZIFS054P001C01-SOCA
DMI_CPU0_PCH_TX_DP<3>    C148             2        Q_CAP_DIFFBUS_C0201-DIFF BUS_0A
DMI_CPU0_PCH_TX_DP<3>    U2               CD18     SOCKET4677_AZIFS054P001C01-SOCA
DMI_CPU0_PCH_TX_DP<4>    C146             2        Q_CAP_DIFFBUS_C0201-DIFF BUS_0A
DMI_CPU0_PCH_TX_DP<4>    U2               CG19     SOCKET4677_AZIFS054P001C01-SOCA
DMI_CPU0_PCH_TX_DP<5>    C144             2        Q_CAP_DIFFBUS_C0201-DIFF BUS_0A
DMI_CPU0_PCH_TX_DP<5>    U2               CH18     SOCKET4677_AZIFS054P001C01-SOCA
DMI_CPU0_PCH_TX_DP<6>    C142             2        Q_CAP_DIFFBUS_C0201-DIFF BUS_0A
DMI_CPU0_PCH_TX_DP<6>    U2               CK18     SOCKET4677_AZIFS054P001C01-SOCA
DMI_CPU0_PCH_TX_DP<7>    C140             2        Q_CAP_DIFFBUS_C0201-DIFF BUS_0A
DMI_CPU0_PCH_TX_DP<7>    U2               CN17     SOCKET4677_AZIFS054P001C01-SOCA
E1S_0_BUF_PRSNT_N        R2106            1        Q_RES_0402LF-0,5%,1/16W,CHIP,CA
E1S_0_BUF_PRSNT_N        U130             8        PCA9555PW_SMLF-PCA9555PW,IC,TMA
E1S_0_BUF_PRSNT_R_N      R2106            2        Q_RES_0402LF-0,5%,1/16W,CHIP,CA
E1S_0_BUF_PRSNT_R_N      U132             6        SN74LVC2G17DCKR-SN74LVC2G17DCKA
E1S_0_EN                 R2105            2        Q_RES_0402LF-0,5%,1/16W,CHIP,CA
E1S_0_EN                 R2160            1        Q_RES_0402LF-0,5%,1/16W,CHIP,CA
E1S_0_EN                 R2164            1        Q_RES_0402LF-0,5%,1/16W,CHIP,CA
E1S_0_LED_ACT_N          J90              A10      CONN56_ME2005602311011-CONN56_A
E1S_0_LED_ACT_N          R2151            2        Q_RES_0402LF-0,5%,1/16W,CHIP,CA
E1S_0_PRSNT_N            J90              A12      CONN56_ME2005602311011-CONN56_A
E1S_0_PRSNT_N            U132             1        SN74LVC2G17DCKR-SN74LVC2G17DCKA
E1S_0_PWR_FAIL_N         R2151            1        Q_RES_0402LF-0,5%,1/16W,CHIP,CA
E1S_0_PWR_FAIL_N         U130             5        PCA9555PW_SMLF-PCA9555PW,IC,TMA
E1S_1_BUF_EN             R2105            1        Q_RES_0402LF-0,5%,1/16W,CHIP,CA
E1S_1_BUF_EN             R2107            1        Q_RES_0402LF-0,5%,1/16W,CHIP,CA
E1S_1_BUF_EN             U130             6        PCA9555PW_SMLF-PCA9555PW,IC,TMA
E1S_1_BUF_EN             U130             15       PCA9555PW_SMLF-PCA9555PW,IC,TMA
E1S_1_BUF_PRSNT_N        R2108            1        Q_RES_0402LF-0,5%,1/16W,CHIP,CA
E1S_1_BUF_PRSNT_N        U130             17       PCA9555PW_SMLF-PCA9555PW,IC,TMA
E1S_1_BUF_PRSNT_R_N      R2108            2        Q_RES_0402LF-0,5%,1/16W,CHIP,CA
E1S_1_BUF_PRSNT_R_N      U132             4        SN74LVC2G17DCKR-SN74LVC2G17DCKA
E1S_1_EN                 R2107            2        Q_RES_0402LF-0,5%,1/16W,CHIP,CA
E1S_1_EN                 R2161            1        Q_RES_0402LF-0,5%,1/16W,CHIP,CA
E1S_1_EN                 R2165            1        Q_RES_0402LF-0,5%,1/16W,CHIP,CA
E1S_1_LED_ACT_N          J91              A10      CONN56_ME2005602311011-CONN56_A
E1S_1_LED_ACT_N          R2152            2        Q_RES_0402LF-0,5%,1/16W,CHIP,CA
E1S_1_PRSNT_N            J91              A12      CONN56_ME2005602311011-CONN56_A
E1S_1_PRSNT_N            U132             3        SN74LVC2G17DCKR-SN74LVC2G17DCKA
E1S_1_PWR_FAIL_N         R2152            1        Q_RES_0402LF-0,5%,1/16W,CHIP,CA
E1S_1_PWR_FAIL_N         U130             14       PCA9555PW_SMLF-PCA9555PW,IC,TMA
E1S_2_BUF_EN             R2109            1        Q_RES_0402LF-0,5%,1/16W,CHIP,CA
E1S_2_BUF_EN             U131             6        PCA9555PW_SMLF-PCA9555PW,IC,TMA
E1S_2_BUF_PRSNT_N        R2110            1        Q_RES_0402LF-0,5%,1/16W,CHIP,CA
E1S_2_BUF_PRSNT_N        U131             8        PCA9555PW_SMLF-PCA9555PW,IC,TMA
E1S_2_BUF_PRSNT_R_N      R2110            2        Q_RES_0402LF-0,5%,1/16W,CHIP,CA
E1S_2_BUF_PRSNT_R_N      U133             6        SN74LVC2G17DCKR-SN74LVC2G17DCKA
E1S_2_EN                 R2109            2        Q_RES_0402LF-0,5%,1/16W,CHIP,CA
E1S_2_EN                 R2159            1        Q_RES_0402LF-0,5%,1/16W,CHIP,CA
E1S_2_EN                 R2163            1        Q_RES_0402LF-0,5%,1/16W,CHIP,CA
E1S_2_LED_ACT_N          J92              A10      CONN56_ME2005602311011-CONN56_A
E1S_2_LED_ACT_N          R2153            2        Q_RES_0402LF-0,5%,1/16W,CHIP,CA
E1S_2_PRSNT_N            J92              A12      CONN56_ME2005602311011-CONN56_A
E1S_2_PRSNT_N            U133             1        SN74LVC2G17DCKR-SN74LVC2G17DCKA
E1S_2_PWR_FAIL_N         R2153            1        Q_RES_0402LF-0,5%,1/16W,CHIP,CA
E1S_2_PWR_FAIL_N         U131             5        PCA9555PW_SMLF-PCA9555PW,IC,TMA
E1S_3_BUF_EN             R2111            1        Q_RES_0402LF-0,5%,1/16W,CHIP,CA
E1S_3_BUF_EN             U131             15       PCA9555PW_SMLF-PCA9555PW,IC,TMA
E1S_3_BUF_PRSNT_N        R2112            1        Q_RES_0402LF-0,5%,1/16W,CHIP,CA
E1S_3_BUF_PRSNT_N        U131             17       PCA9555PW_SMLF-PCA9555PW,IC,TMA
E1S_3_BUF_PRSNT_R_N      R2112            2        Q_RES_0402LF-0,5%,1/16W,CHIP,CA
E1S_3_BUF_PRSNT_R_N      U133             4        SN74LVC2G17DCKR-SN74LVC2G17DCKA
E1S_3_EN                 R2111            2        Q_RES_0402LF-0,5%,1/16W,CHIP,CA
E1S_3_EN                 R2162            1        Q_RES_0402LF-0,5%,1/16W,CHIP,CA
E1S_3_EN                 R2166            1        Q_RES_0402LF-0,5%,1/16W,CHIP,CA
E1S_3_LED_ACT_N          J93              A10      CONN56_ME2005602311011-CONN56_A
E1S_3_LED_ACT_N          R2154            2        Q_RES_0402LF-0,5%,1/16W,CHIP,CA
E1S_3_PRSNT_N            J93              A12      CONN56_ME2005602311011-CONN56_A
E1S_3_PRSNT_N            U133             3        SN74LVC2G17DCKR-SN74LVC2G17DCKA
E1S_3_PWR_FAIL_N         R2154            1        Q_RES_0402LF-0,5%,1/16W,CHIP,CA
E1S_3_PWR_FAIL_N         U131             14       PCA9555PW_SMLF-PCA9555PW,IC,TMA
EDSFF1A_PERST1_CLKREQ_N  J62              A11      SCONN84_123318136-SCONN84_1-23A
EDSFF1A_PERST1_CLKREQ_N  R1542            2        Q_RES_0402LF-10K,1%,1/16W,CHIPA
EDSFF1A_PERST1_CLKREQ_N  R1544            1        Q_RES_0402LF-0,5%,1/16W,CHIP,CA
EDSFF1A_PERST1_CLKREQ_N  R1969            1        Q_RES_0402LF-10K,1%,1/16W,EMPTA
EDSFF3_CLK_EN_N          R2148            2        Q_RES_0402LF-0,5%,1/16W,CHIP,CA
EDSFF3_CLK_EN_N          U13              A30      9SQ440NQQI8-9SQ440NQQI8,SMLF,IA
EDSFF3_PRSNT_0_N         J35              A1       SCONN140_G64V3431BHR-SCONN140_B
EDSFF3_PRSNT_0_N         R1618            1        Q_RES_0402LF-100,1%,1/16W,CHIPA
EDSFF3_USB2_5_DN         J35              A14      SCONN140_G64V3431BHR-SCONN140_B
EDSFF3_USB2_5_DN         R2149            1        Q_RES_0402LF-0,5%,1/16W,CHIP,CA
EDSFF3_USB2_5_DP         J35              A15      SCONN140_G64V3431BHR-SCONN140_B
EDSFF3_USB2_5_DP         R2150            1        Q_RES_0402LF-0,5%,1/16W,CHIP,CA
EDSFF4A_PERST1_CLKREQ_N  J88              A11      SCONN84_123318136-SCONN84_1-23A
EDSFF4A_PERST1_CLKREQ_N  R1989            1        Q_RES_0402LF-10K,1%,1/16W,CHIPA
EDSFF4B_PERST1_CLKREQ_N  J61              A11      SCONN84_123318136-SCONN84_1-23A
EDSFF4B_PERST1_CLKREQ_N  R2001            1        Q_RES_0402LF-10K,1%,1/16W,CHIPA
ESPI_ALERT1_N_LPC_RCIN_N R1255            2        Q_RES_0402LF-1K,1%,1/16W,CHIP,A
ESPI_ALERT1_N_LPC_RCIN_N U4               BD15     EMMITSBURG_REV0P9-GFNOCPU04302A
ESPI_BMC_LPC_RST_N       J41              B4       SCONN168_623403212-SCONN168_6-A
ESPI_BMC_LPC_RST_N       U61              4        NC7SB3157_SMLF-NC7SB3157P6X,NCA
ESPI_HOST_LPC_BMC_CLK    J41              B1       SCONN168_623403212-SCONN168_6-A
ESPI_HOST_LPC_BMC_CLK    R1872            2        Q_RES_0402LF-0,5%,1/16W,CHIP,CA
ESPI_HOST_LPC_BMC_LFRAME_N J41              B2       SCONN168_623403212-SCONN168_6-A
ESPI_HOST_LPC_BMC_LFRAME_N R1479            2        Q_RES_0402LF-33.2,1%,1/16W,CHIA
ESPI_LAD0_DATA_IO0       R1871            1        Q_RES_0402LF-0,5%,1/16W,CHIP,CA
ESPI_LAD0_DATA_IO0       U4               BG12     EMMITSBURG_REV0P9-GFNOCPU04302A
ESPI_LAD0_DATA_IO1       R1870            1        Q_RES_0402LF-0,5%,1/16W,CHIP,CA
ESPI_LAD0_DATA_IO1       U4               BF19     EMMITSBURG_REV0P9-GFNOCPU04302A
ESPI_LAD0_DATA_IO2       R1869            1        Q_RES_0402LF-0,5%,1/16W,CHIP,CA
ESPI_LAD0_DATA_IO2       U4               BE18     EMMITSBURG_REV0P9-GFNOCPU04302A
ESPI_LAD0_DATA_IO3       R1868            1        Q_RES_0402LF-0,5%,1/16W,CHIP,CA
ESPI_LAD0_DATA_IO3       U4               BD19     EMMITSBURG_REV0P9-GFNOCPU04302A
ESPI_LFRAME_N_BMC_CS0_N  R1479            1        Q_RES_0402LF-33.2,1%,1/16W,CHIA
ESPI_LFRAME_N_BMC_CS0_N  R1961            2        Q_RES_0402LF-10K,1%,1/16W,CHIPA
ESPI_LFRAME_N_BMC_CS0_N  U4               BE20     EMMITSBURG_REV0P9-GFNOCPU04302A
ESPI_LPC_LAD0_IO0        J41              B5       SCONN168_623403212-SCONN168_6-A
ESPI_LPC_LAD0_IO0        R1871            2        Q_RES_0402LF-0,5%,1/16W,CHIP,CA
ESPI_LPC_LAD0_IO1        J41              B6       SCONN168_623403212-SCONN168_6-A
ESPI_LPC_LAD0_IO1        R1870            2        Q_RES_0402LF-0,5%,1/16W,CHIP,CA
ESPI_LPC_LAD0_IO2        J41              B7       SCONN168_623403212-SCONN168_6-A
ESPI_LPC_LAD0_IO2        R1869            2        Q_RES_0402LF-0,5%,1/16W,CHIP,CA
ESPI_LPC_LAD0_IO3        J41              B8       SCONN168_623403212-SCONN168_6-A
ESPI_LPC_LAD0_IO3        R1868            2        Q_RES_0402LF-0,5%,1/16W,CHIP,CA
FAN_PDB_PRSNT_N          J44              2        CONN24_52SH90245BRD-CONN24_52SA
FAN_PDB_PRSNT_N          R2157            2        Q_RES_0402LF-4.7K,1%,1/16W,CHIA
FB_BMC_ISOLATE           R1289            1        Q_RES_0402LF-100K,1%,1/16W,CHIA
FB_BMC_ISOLATE           U66              4        74HC1G126GW-74HC1G126GW,SMLF,IA
FB_BMC_ISOLATE           U67              1        74CBTLV3126PW-74CBTLV3126PW,SMA
FB_BMC_ISOLATE           U67              4        74CBTLV3126PW-74CBTLV3126PW,SMA
FB_BMC_ISOLATE           U67              10       74CBTLV3126PW-74CBTLV3126PW,SMA
FB_BMC_ISOLATE           U67              13       74CBTLV3126PW-74CBTLV3126PW,SMA
FB_BMC_ISOLATE           U68              1        74CBTLV3126PW-74CBTLV3126PW,SMA
FB_BMC_ISOLATE           U68              4        74CBTLV3126PW-74CBTLV3126PW,SMA
FB_BMC_ISOLATE           U68              10       74CBTLV3126PW-74CBTLV3126PW,SMA
FB_BMC_ISOLATE           U68              13       74CBTLV3126PW-74CBTLV3126PW,SMA
FM_ADR_ACK               R369             2        Q_RES_0402LF-1K,5%,1/16W,CHIP,A
FM_ADR_ACK               R700             2        Q_RES_0402LF-0,5%,1/16W,CHIP,CA
FM_ADR_ACK               U4               AD4      EMMITSBURG_REV0P9-GFNOCPU04302A
FM_ADR_ACK_R             R700             1        Q_RES_0402LF-0,5%,1/16W,CHIP,CA
FM_ADR_ACK_R             U122             L11      10M04SAU324I7G-10M04SAU324I7G,A
FM_ADR_COMPLETE          R1341            1        Q_RES_0402LF-10K,1%,1/16W,CHIPA
FM_ADR_COMPLETE          S1               6        SW8S_DHNF04FTVTR-SW8S_DHNF04FTA
FM_ADR_COMPLETE          U4               AC1      EMMITSBURG_REV0P9-GFNOCPU04302A
FM_ADR_COMPLETE          U122             L15      10M04SAU324I7G-10M04SAU324I7G,A
FM_ADR_MODE0             R773             2        Q_RES_0402LF-1K,1%,1/16W,CHIP,A
FM_ADR_MODE0             R1455            2        Q_RES_0402LF-49.9     ,1%  ,1/A
FM_ADR_MODE0             R1809            2        Q_RES_0402LF-20K,1%,1/16W,CHIPA
FM_ADR_MODE0             R1810            1        Q_RES_0402LF-1K,5%,1/16W,EMPTYA
FM_ADR_MODE0             U4               AV11     EMMITSBURG_REV0P9-GFNOCPU04302A
FM_ADR_MODE0_R           R1455            1        Q_RES_0402LF-49.9     ,1%  ,1/A
FM_ADR_MODE0_R           U122             L12      10M04SAU324I7G-10M04SAU324I7G,A
FM_ADR_MODE1             R269             1        Q_RES_0402LF-33.2,1%,1/16W,CHIA
FM_ADR_MODE1             R378             2        Q_RES_0402LF-1K,5%,1/16W,EMPTYA
FM_ADR_MODE1             R379             1        Q_RES_0402LF-1K,5%,1/16W,CHIP,A
FM_ADR_MODE1             U4               AL5      EMMITSBURG_REV0P9-GFNOCPU04302A
FM_ADR_MODE1_R           R269             2        Q_RES_0402LF-33.2,1%,1/16W,CHIA
FM_ADR_MODE1_R           U122             A17      10M04SAU324I7G-10M04SAU324I7G,A
FM_ADR_TRIGGER_N         R698             2        Q_RES_0402LF-49.9     ,1%  ,1/A
FM_ADR_TRIGGER_N         R1435            1        Q_RES_0402LF-10K,1%,1/16W,CHIPA
FM_ADR_TRIGGER_N         U122             L16      10M04SAU324I7G-10M04SAU324I7G,A
FM_ADR_TRIGGER_R_N       R698             1        Q_RES_0402LF-49.9     ,1%  ,1/A
FM_ADR_TRIGGER_R_N       U4               AH4      EMMITSBURG_REV0P9-GFNOCPU04302A
FM_AUX_SW_EN             R991             1        Q_RES_0402LF-2K,1%,1/16W,CHIP,A
FM_AUX_SW_EN             U122             C7       10M04SAU324I7G-10M04SAU324I7G,A
FM_BIOS_ADV_FUNCTIONS    R1498            2        Q_RES_0402LF-1K,1%,1/16W,EMPTYA
FM_BIOS_ADV_FUNCTIONS    R1499            1        Q_RES_0402LF-1K,1%,1/16W,CHIP,A
FM_BIOS_ADV_FUNCTIONS    U4               AF11     EMMITSBURG_REV0P9-GFNOCPU04302A
FM_BIOS_DEBUG_EN_N       R2147            1        Q_RES_0402LF-0,5%,1/16W,CHIP,CA
FM_BIOS_DEBUG_EN_N       U122             F5       10M04SAU324I7G-10M04SAU324I7G,A
FM_BIOS_DEBUG_EN_R_N     R2147            2        Q_RES_0402LF-0,5%,1/16W,CHIP,CA
FM_BIOS_DEBUG_EN_R_N     U4               AA3      EMMITSBURG_REV0P9-GFNOCPU04302A
FM_BIOS_IMAGE_SWAP_N     R1339            2        Q_RES_0402LF-10K,1%,1/16W,CHIPA
FM_BIOS_IMAGE_SWAP_N     S1               5        SW8S_DHNF04FTVTR-SW8S_DHNF04FTA
FM_BIOS_IMAGE_SWAP_N     U4               Y4       EMMITSBURG_REV0P9-GFNOCPU04302A
FM_BIOS_POST_CMPLT_BMC_N R1300            2        Q_RES_0402LF-33.2,1%,1/16W,CHIA
FM_BIOS_POST_CMPLT_BMC_N U122             D9       10M04SAU324I7G-10M04SAU324I7G,A
FM_BIOS_POST_CMPLT_N     R1300            1        Q_RES_0402LF-33.2,1%,1/16W,CHIA
FM_BIOS_POST_CMPLT_N     R1449            2        Q_RES_0402LF-10K,1%,1/16W,CHIPA
FM_BIOS_POST_CMPLT_N     U4               AL3      EMMITSBURG_REV0P9-GFNOCPU04302A
FM_BMC_CPU_FBRK_OUT_N    R1381            2        Q_RES_0402LF-1K,1%,1/16W,CHIP,A
FM_BMC_CPU_FBRK_OUT_N    R1845            1        Q_RES_0402LF-0,5%,1/16W,CHIP,CA
FM_BMC_CPU_FBRK_OUT_N    U84              12       GTL2014PW-GTL2014PW,SMLF,IC,ALA
FM_BMC_CPU_FBRK_OUT_R_N  J41              A54      SCONN168_623403212-SCONN168_6-A
FM_BMC_CPU_FBRK_OUT_R_N  R1845            2        Q_RES_0402LF-0,5%,1/16W,CHIP,CA
FM_BMC_DBP_PRESENT_R_N   R1472            2        Q_RES_0402LF-33.2,1%,1/16W,CHIA
FM_BMC_DBP_PRESENT_R_N   U122             A4       10M04SAU324I7G-10M04SAU324I7G,A
FM_BMC_EN_DET            C1293            1        Q_CAP_C0402-1UF,25V,10%,X6S,CHA
FM_BMC_EN_DET            R1375            1        Q_RES_0402LF-10K,1%,1/16W,CHIPA
FM_BMC_EN_DET            U86              2        74CBTLV3126PW-74CBTLV3126PW,SMA
FM_BMC_EN_DET            U86              5        74CBTLV3126PW-74CBTLV3126PW,SMA
FM_BMC_EN_DET            U86              9        74CBTLV3126PW-74CBTLV3126PW,SMA
FM_BMC_EN_DET            U86              12       74CBTLV3126PW-74CBTLV3126PW,SMA
FM_BMC_EN_DET            U87              S        MOSFET_N_SMLF-BSS138K,BSS138K,A
FM_BMC_PWRBTN_N          R139             1        Q_RES_0402LF-10K,1%,1/16W,CHIPA
FM_BMC_PWRBTN_N          R1744            2        Q_RES_0402LF-0,5%,1/16W,CHIP,CA
FM_BMC_PWRBTN_N          U4               AR10     EMMITSBURG_REV0P9-GFNOCPU04302A
FM_BMC_PWRBTN_OUT_N      R1744            1        Q_RES_0402LF-0,5%,1/16W,CHIP,CA
FM_BMC_PWRBTN_OUT_N      R1815            1        Q_RES_0402LF-0,5%,1/16W,CHIP,CA
FM_BMC_PWRBTN_OUT_R_N    J41              A47      SCONN168_623403212-SCONN168_6-A
FM_BMC_PWRBTN_OUT_R_N    R1815            2        Q_RES_0402LF-0,5%,1/16W,CHIP,CA
FM_BMC_READY_R_N         R2155            2        Q_RES_0402LF-0,5%,1/16W,CHIP,CA
FM_BMC_READY_R_N         U4               W10      EMMITSBURG_REV0P9-GFNOCPU04302A
FM_BMC_READY_R_PLD_N     R2155            1        Q_RES_0402LF-0,5%,1/16W,CHIP,CA
FM_BMC_READY_R_PLD_N     U122             D13      10M04SAU324I7G-10M04SAU324I7G,A
FM_BMC_RSTBTN_OUT_N      R697             1        Q_RES_0402LF-33,5%,1/16W,CHIP,A
FM_BMC_RSTBTN_OUT_N      U122             D10      10M04SAU324I7G-10M04SAU324I7G,A
FM_BMC_SUSACK_R_N        R2071            1        Q_RES_0402LF-0,5%,1/16W,EMPTY,A
FM_BMC_SUSACK_R_N        U122             K4       10M04SAU324I7G-10M04SAU324I7G,A
FM_CK440Q_DEV_25M_EN     C1324            1        Q_CAP_0402-0.1UF,25V,10%,EMPTYA
FM_CK440Q_DEV_25M_EN     R1483            2        Q_RES_0402LF-10K,1%,1/16W,EMPTA
FM_CK440Q_DEV_25M_EN     R1484            1        Q_RES_0402LF-1K,1%,1/16W,EMPTYA
FM_CK440Q_DEV_25M_EN     R1680            2        Q_RES_0402LF-0,5%,1/16W,CHIP,CA
FM_CK440Q_DEV_25M_EN     U13              A1       9SQ440NQQI8-9SQ440NQQI8,SMLF,IA
FM_CK440_MXCK_25M_100M   R1194            2        Q_RES_0402LF-4.75K,1%,1/16W,EMA
FM_CK440_MXCK_25M_100M   R1196            1        Q_RES_0402LF-4.75K,1%,1/16W,CHA
FM_CK440_MXCK_25M_100M   U13              B38      9SQ440NQQI8-9SQ440NQQI8,SMLF,IA
FM_CLK_CK440_SS_EN       R1471            2        Q_RES_0402LF-4.75K,1%,1/16W,CHA
FM_CLK_CK440_SS_EN       R1502            1        Q_RES_0402LF-4.75K,1%,1/16W,CHA
FM_CLK_CK440_SS_EN       U13              A16      9SQ440NQQI8-9SQ440NQQI8,SMLF,IA
FM_CLK_GEN1_OE0_N        R1527            1        Q_RES_0402LF-1K,1%,1/16W,CHIP,A
FM_CLK_GEN1_OE0_N        U13              B27      9SQ440NQQI8-9SQ440NQQI8,SMLF,IA
FM_COMP_P3V3_AUX_ENIN    R1690            2        Q_RES_0402LF-10K,1%,1/16W,CHIPA
FM_COMP_P3V3_AUX_ENIN    R1745            1        Q_RES_0402LF-0,5%,1/16W,EMPTY,A
FM_COMP_P3V3_AUX_ENIN    U94              1        ADM1086AKSZREEL7-ADM1086AKSZ-RA
FM_COMP_P3V3_AUX_ENIN    U117             1        TPS3897PDRYR-TPS3897PDRYR,SMLFA
FM_COMP_P3V3_AUX_VIN     R1688            2        Q_RES_0402LF-100K,1%,1/16W,CHIA
FM_COMP_P3V3_AUX_VIN     R1689            1        Q_RES_0402LF-6.19K,1%,1/16W,CHA
FM_COMP_P3V3_AUX_VIN     R1950            1        Q_RES_0402LF-0,5%,1/16W,CHIP,CA
FM_COMP_P3V3_AUX_VIN     U94              3        ADM1086AKSZREEL7-ADM1086AKSZ-RA
FM_COMP_P3V3_AUX_VIN     U117             3        TPS3897PDRYR-TPS3897PDRYR,SMLFA
FM_COMP_P3V3_STBY_CEXT   C1316            1        Q_CAP_C0402-0.047UF,25V,10%,X7A
FM_COMP_P3V3_STBY_CEXT   U94              5        ADM1086AKSZREEL7-ADM1086AKSZ-RA
FM_COMP_P3V3_STBY_CEXT   U117             5        TPS3897PDRYR-TPS3897PDRYR,SMLFA
FM_CPU0_PKGID0           R283             2        Q_RES_0402LF-10K,1%,1/16W,CHIPA
FM_CPU0_PKGID0           U2               BL64     SOCKET4677_AZIFS054P001C01-SOCA
FM_CPU0_PKGID0           U122             F15      10M04SAU324I7G-10M04SAU324I7G,A
FM_CPU0_PKGID1           R284             2        Q_RES_0402LF-10K,1%,1/16W,CHIPA
FM_CPU0_PKGID1           U2               AY63     SOCKET4677_AZIFS054P001C01-SOCA
FM_CPU0_PKGID1           U122             F16      10M04SAU324I7G-10M04SAU324I7G,A
FM_CPU0_PKGID2           R285             2        Q_RES_0402LF-10K,1%,1/16W,CHIPA
FM_CPU0_PKGID2           U2               BN64     SOCKET4677_AZIFS054P001C01-SOCA
FM_CPU0_PKGID2           U122             F18      10M04SAU324I7G-10M04SAU324I7G,A
FM_CPU0_PROC_ID0         R286             2        Q_RES_0402LF-10K,1%,1/16W,CHIPA
FM_CPU0_PROC_ID0         U2               BG72     SOCKET4677_AZIFS054P001C01-SOCA
FM_CPU0_PROC_ID0         U122             J15      10M04SAU324I7G-10M04SAU324I7G,A
FM_CPU0_PROC_ID1         R287             2        Q_RES_0402LF-10K,1%,1/16W,CHIPA
FM_CPU0_PROC_ID1         U2               BH71     SOCKET4677_AZIFS054P001C01-SOCA
FM_CPU0_PROC_ID1         U122             J16      10M04SAU324I7G-10M04SAU324I7G,A
FM_CPU0_SKTOCC_LVT3_N    R738             1        Q_RES_0402LF-0,5%,1/16W,CHIP,CA
FM_CPU0_SKTOCC_LVT3_N    R1447            1        Q_RES_0402LF-33.2,1%,1/16W,CHIA
FM_CPU0_SKTOCC_LVT3_N    U2               CG66     SOCKET4677_AZIFS054P001C01-SOCA
FM_CPU0_SKTOCC_LVT3_PLD_N R1447            2        Q_RES_0402LF-33.2,1%,1/16W,CHIA
FM_CPU0_SKTOCC_LVT3_PLD_N U122             G15      10M04SAU324I7G-10M04SAU324I7G,A
FM_CPU0_SKTOCC_N         R738             2        Q_RES_0402LF-0,5%,1/16W,CHIP,CA
FM_CPU0_SKTOCC_N         R740             2        Q_RES_0402LF-10K,1%,1/16W,CHIPA
FM_CPU0_SKTOCC_N         U21              6        NC7SB3157_SMLF-NC7SB3157P6X,NCA
FM_CPU0_SKTOCC_N         U23              2        74LVC1G02GW_SMLF-74LVC1G02GW,IA
FM_CPU1_PKGID0           R270             2        Q_RES_0402LF-10K,1%,1/16W,CHIPA
FM_CPU1_PKGID0           U1               BL64     SOCKET4677_AZIFS054P001C01-SOCA
FM_CPU1_PKGID0           U122             D17      10M04SAU324I7G-10M04SAU324I7G,A
FM_CPU1_PKGID1           R271             2        Q_RES_0402LF-10K,1%,1/16W,CHIPA
FM_CPU1_PKGID1           U1               AY63     SOCKET4677_AZIFS054P001C01-SOCA
FM_CPU1_PKGID1           U122             D16      10M04SAU324I7G-10M04SAU324I7G,A
FM_CPU1_PKGID2           R272             2        Q_RES_0402LF-10K,1%,1/16W,CHIPA
FM_CPU1_PKGID2           U1               BN64     SOCKET4677_AZIFS054P001C01-SOCA
FM_CPU1_PKGID2           U122             D15      10M04SAU324I7G-10M04SAU324I7G,A
FM_CPU1_PROC_ID0         R273             2        Q_RES_0402LF-10K,1%,1/16W,CHIPA
FM_CPU1_PROC_ID0         U1               BG72     SOCKET4677_AZIFS054P001C01-SOCA
FM_CPU1_PROC_ID0         U122             K17      10M04SAU324I7G-10M04SAU324I7G,A
FM_CPU1_PROC_ID1         R274             2        Q_RES_0402LF-10K,1%,1/16W,CHIPA
FM_CPU1_PROC_ID1         U1               BH71     SOCKET4677_AZIFS054P001C01-SOCA
FM_CPU1_PROC_ID1         U122             K18      10M04SAU324I7G-10M04SAU324I7G,A
FM_CPU1_SKTOCC_LVT3_N    R737             1        Q_RES_0402LF-0,5%,1/16W,CHIP,CA
FM_CPU1_SKTOCC_LVT3_N    R1448            1        Q_RES_0402LF-33.2,1%,1/16W,CHIA
FM_CPU1_SKTOCC_LVT3_N    U1               CG66     SOCKET4677_AZIFS054P001C01-SOCA
FM_CPU1_SKTOCC_LVT3_PLD_N R1448            2        Q_RES_0402LF-33.2,1%,1/16W,CHIA
FM_CPU1_SKTOCC_LVT3_PLD_N U122             D18      10M04SAU324I7G-10M04SAU324I7G,A
FM_CPU1_SKTOCC_N         R737             2        Q_RES_0402LF-0,5%,1/16W,CHIP,CA
FM_CPU1_SKTOCC_N         R739             2        Q_RES_0402LF-10K,1%,1/16W,CHIPA
FM_CPU1_SKTOCC_N         U22              6        NC7SB3157_SMLF-NC7SB3157P6X,NCA
FM_CPU1_SKTOCC_N         U23              1        74LVC1G02GW_SMLF-74LVC1G02GW,IA
FM_CPU_EN                R745             1        Q_RES_0402LF-33,5%,1/16W,CHIP,A
FM_CPU_EN                U23              4        74LVC1G02GW_SMLF-74LVC1G02GW,IA
FM_CPU_EN_R              R745             2        Q_RES_0402LF-33,5%,1/16W,CHIP,A
FM_CPU_EN_R              U16              4        NC7SZ66M5X_SMLF-NC7SZ66M5X,NC7A
FM_CPU_FBRK_DEBUG_N      C552             1        Q_CAP_0402-0.1UF,25V,10%,X7R,CA
FM_CPU_FBRK_DEBUG_N      J42              38       SCONN60_QSH03001LDAKTR-SCONN60A
FM_CPU_FBRK_DEBUG_N      R779             2        Q_RES_0402LF-150,5%,1/16W,CHIPA
FM_CPU_FBRK_DEBUG_N      R780             1        Q_RES_0402LF-49.9     ,1%  ,1/A
FM_CPU_FBRK_DEBUG_N      R1247            2        Q_RES_0402LF-0,5%,1/16W,CHIP,CA
FM_CPU_FBRK_DEBUG_N      U84              3        GTL2014PW-GTL2014PW,SMLF,IC,ALA
FM_CPU_FBRK_DEBUG_R_N    R780             2        Q_RES_0402LF-49.9     ,1%  ,1/A
FM_CPU_FBRK_DEBUG_R_N    U1               AV57     SOCKET4677_AZIFS054P001C01-SOCA
FM_CPU_FBRK_DEBUG_R_N    U2               AV57     SOCKET4677_AZIFS054P001C01-SOCA
FM_CPU_RMCA_CATERR_DLY_LVT3_R_N R1456            1        Q_RES_0402LF-49.9     ,1%  ,1/A
FM_CPU_RMCA_CATERR_DLY_LVT3_R_N U122             R16      10M04SAU324I7G-10M04SAU324I7G,A
FM_CPU_RMCA_CATERR_DLY_N R1456            2        Q_RES_0402LF-49.9     ,1%  ,1/A
FM_CPU_RMCA_CATERR_DLY_N U4               AF4      EMMITSBURG_REV0P9-GFNOCPU04302A
FM_CPU_RMCA_CATERR_LVT3_R_N R365             1        Q_RES_0402LF-0,5%,1/16W,CHIP,CA
FM_CPU_RMCA_CATERR_LVT3_R_N R1558            1        Q_RES_0402LF-10K,1%,1/16W,CHIPA
FM_CPU_RMCA_CATERR_LVT3_R_N R1841            2        Q_RES_0402LF-10K,1%,1/16W,EMPTA
FM_CPU_RMCA_CATERR_LVT3_R_N U122             R15      10M04SAU324I7G-10M04SAU324I7G,A
FM_DB2000_12_OE_N        R1544            2        Q_RES_0402LF-0,5%,1/16W,CHIP,CA
FM_DB2000_12_OE_N        U38              B10      9QXL2001BNHGI8-9QXL2001BNHGI8,A
FM_DB2000_1_OE_N         R576             2        Q_RES_0402LF-49.9     ,1%  ,1/A
FM_DB2000_1_OE_N         U38              K11      9QXL2001BNHGI8-9QXL2001BNHGI8,A
FM_DB2000_1_OE_N         U38              L8       9QXL2001BNHGI8-9QXL2001BNHGI8,A
FM_DB2000_1_OE_N         U38              L10      9QXL2001BNHGI8-9QXL2001BNHGI8,A
FM_DB2000_8_OE_N         R1543            2        Q_RES_0402LF-0,5%,1/16W,CHIP,CA
FM_DB2000_8_OE_N         U38              C11      9QXL2001BNHGI8-9QXL2001BNHGI8,A
FM_DB2000_8_OE_N         U38              E11      9QXL2001BNHGI8-9QXL2001BNHGI8,A
FM_DB2000_8_OE_N         U38              E12      9QXL2001BNHGI8-9QXL2001BNHGI8,A
FM_DB2000_8_OE_N         U38              H11      9QXL2001BNHGI8-9QXL2001BNHGI8,A
FM_DB2000_DEV_EN         R575             2        Q_RES_0402LF-49.9     ,1%  ,1/A
FM_DB2000_DEV_EN         U38              M6       9QXL2001BNHGI8-9QXL2001BNHGI8,A
FM_DB2000_OE_N           R113             2        Q_RES_0402LF-33.2,1%,1/16W,CHIA
FM_DB2000_OE_N           R576             1        Q_RES_0402LF-49.9     ,1%  ,1/A
FM_DB2000_VSBEN          R573             2        Q_RES_0402LF-4.7K,1%,1/16W,EMPA
FM_DB2000_VSBEN          R574             1        Q_RES_0402LF-4.7K,1%,1/16W,CHIA
FM_DB2000_VSBEN          U38              E2       9QXL2001BNHGI8-9QXL2001BNHGI8,A
FM_DIMM_12V_CPS_SX_N     R735             2        Q_RES_0402LF-10K,1%,1/16W,CHIPA
FM_DIMM_12V_CPS_SX_N     R736             1        Q_RES_0402LF-1K,1%,1/16W,EMPTYA
FM_DIMM_12V_CPS_SX_N     U122             E5       10M04SAU324I7G-10M04SAU324I7G,A
FM_DIS_PS_PWROK_DLY      R1492            1        Q_RES_0402LF-10K,1%,1/16W,EMPTA
FM_DIS_PS_PWROK_DLY      R1494            1        Q_RES_0402LF-1K,1%,1/16W,CHIP,A
FM_DIS_PS_PWROK_DLY      U122             D14      10M04SAU324I7G-10M04SAU324I7G,A
FM_EDSFF1A_PWRBRK_N      J62              B8       SCONN84_123318136-SCONN84_1-23A
FM_EDSFF1A_PWRBRK_N      R1965            2        Q_RES_0402LF-0,5%,1/16W,CHIP,CA
FM_EDSFF1A_TYPE_ID       J62              B7       SCONN84_123318136-SCONN84_1-23A
FM_EDSFF1A_TYPE_ID       R1963            2        Q_RES_0402LF-10K,1%,1/16W,CHIPA
FM_EDSFF1A_TYPE_ID       U4               AV24     EMMITSBURG_REV0P9-GFNOCPU04302A
FM_EDSFF1B_PWRBRK_N      J87              B8       SCONN84_123318136-SCONN84_1-23A
FM_EDSFF1B_PWRBRK_N      R1975            2        Q_RES_0402LF-0,5%,1/16W,CHIP,CA
FM_EDSFF1B_TYPE_ID       J87              B7       SCONN84_123318136-SCONN84_1-23A
FM_EDSFF1B_TYPE_ID       R1973            2        Q_RES_0402LF-10K,1%,1/16W,CHIPA
FM_EDSFF1B_TYPE_ID       U4               AV28     EMMITSBURG_REV0P9-GFNOCPU04302A
FM_EDSFF2A_PWRBRK_N      J33              B8       SCONN84_123318136-SCONN84_1-23A
FM_EDSFF2A_PWRBRK_N      R1585            2        Q_RES_0402LF-0,5%,1/16W,CHIP,CA
FM_EDSFF2A_TYPE_ID       J33              B7       SCONN84_123318136-SCONN84_1-23A
FM_EDSFF2A_TYPE_ID       R1609            2        Q_RES_0402LF-10K,1%,1/16W,CHIPA
FM_EDSFF2A_TYPE_ID       U4               BB24     EMMITSBURG_REV0P9-GFNOCPU04302A
FM_EDSFF2B_PWRBRK_N      J34              B8       SCONN84_123318136-SCONN84_1-23A
FM_EDSFF2B_PWRBRK_N      R1587            2        Q_RES_0402LF-0,5%,1/16W,CHIP,CA
FM_EDSFF2B_TYPE_ID       J34              B7       SCONN84_123318136-SCONN84_1-23A
FM_EDSFF2B_TYPE_ID       R1610            2        Q_RES_0402LF-10K,1%,1/16W,CHIPA
FM_EDSFF2B_TYPE_ID       U4               AW32     EMMITSBURG_REV0P9-GFNOCPU04302A
FM_EDSFF3_PWRBRK_N       J35              B14      SCONN140_G64V3431BHR-SCONN140_B
FM_EDSFF3_PWRBRK_N       R1589            2        Q_RES_0402LF-0,5%,1/16W,CHIP,CA
FM_EDSFF3_TYPE_ID        J35              A17      SCONN140_G64V3431BHR-SCONN140_B
FM_EDSFF3_TYPE_ID        R2180            2        Q_RES_0402LF-10K,1%,1/16W,CHIPA
FM_EDSFF3_TYPE_ID        U4               AW36     EMMITSBURG_REV0P9-GFNOCPU04302A
FM_EDSFF4A_PWRBRK_N      J88              B8       SCONN84_123318136-SCONN84_1-23A
FM_EDSFF4A_PWRBRK_N      R1985            2        Q_RES_0402LF-0,5%,1/16W,CHIP,CA
FM_EDSFF4A_TYPE_ID       J61              B7       SCONN84_123318136-SCONN84_1-23A
FM_EDSFF4A_TYPE_ID       J88              B7       SCONN84_123318136-SCONN84_1-23A
FM_EDSFF4A_TYPE_ID       R1983            2        Q_RES_0402LF-10K,1%,1/16W,CHIPA
FM_EDSFF4A_TYPE_ID       U4               BA29     EMMITSBURG_REV0P9-GFNOCPU04302A
FM_EDSFF4B_TYPE_ID       R1993            2        Q_RES_0402LF-10K,1%,1/16W,CHIPA
FM_EDSFF4B_TYPE_ID       U4               AV31     EMMITSBURG_REV0P9-GFNOCPU04302A
FM_ESPI_CS_SWIZZLE       R609             2        Q_RES_0402LF-1K,5%,1/16W,EMPTYA
FM_ESPI_CS_SWIZZLE       R610             1        Q_RES_0402LF-10K,1%,1/16W,CHIPA
FM_ESPI_CS_SWIZZLE       U4               BB8      EMMITSBURG_REV0P9-GFNOCPU04302A
FM_ESPI_FLASH_MODE       R607             2        Q_RES_0402LF-1K,5%,1/16W,EMPTYA
FM_ESPI_FLASH_MODE       R608             1        Q_RES_0402LF-10K,1%,1/16W,CHIPA
FM_ESPI_FLASH_MODE       U4               AG1      EMMITSBURG_REV0P9-GFNOCPU04302A
FM_ESPI_PLD_EN           R1748            1        Q_RES_0402LF-0,5%,1/16W,CHIP,CA
FM_ESPI_PLD_EN           U60              6        NC7SB3157_SMLF-NC7SB3157P6X,NCA
FM_ESPI_PLD_EN           U61              6        NC7SB3157_SMLF-NC7SB3157P6X,NCA
FM_ESPI_PLD_R_EN         R1748            2        Q_RES_0402LF-0,5%,1/16W,CHIP,CA
FM_ESPI_PLD_R_EN         R1749            1        Q_RES_0402LF-10K,1%,1/16W,EMPTA
FM_ESPI_PLD_R_EN         R1750            2        Q_RES_0402LF-1K,1%,1/16W,CHIP,A
FM_ESPI_PLD_R_EN         R2132            2        Q_RES_0402LF-0,5%,1/16W,EMPTY,A
FM_ESPI_PLD_R_EN         U122             A5       10M04SAU324I7G-10M04SAU324I7G,A
FM_EUP_LOT6_N            R1461            1        Q_RES_0402LF-0,5%,1/16W,CHIP,CA
FM_EUP_LOT6_N            U4               AR13     EMMITSBURG_REV0P9-GFNOCPU04302A
FM_FAN_ID                R1645            2        Q_RES_0402LF-4.7K,5%,1/16W,EMPA
FM_FAN_ID                R1646            1        Q_RES_0402LF-4.7K,5%,1/16W,CHIA
FM_FLASH_SECURITY_STRAP  R380             2        Q_RES_0402LF-1K,5%,1/16W,EMPTYA
FM_FLASH_SECURITY_STRAP  R381             1        Q_RES_0402LF-10K,1%,1/16W,CHIPA
FM_FLASH_SECURITY_STRAP  R1337            1        Q_RES_0402LF-10K,1%,1/16W,CHIPA
FM_FLASH_SECURITY_STRAP  S2               8        SW8S_DHNF04FTVTR-SW8S_DHNF04FTA
FM_FLASH_SECURITY_STRAP  U4               AJ1      EMMITSBURG_REV0P9-GFNOCPU04302A
FM_FORCE_PWRON_LVC3      R1493            1        Q_RES_0402LF-1K,1%,1/16W,EMPTYA
FM_FORCE_PWRON_LVC3      R1495            1        Q_RES_0402LF-10K,1%,1/16W,CHIPA
FM_FORCE_PWRON_LVC3      U122             B2       10M04SAU324I7G-10M04SAU324I7G,A
FM_HBM2_HBM3_VPP_SEL     U73              G        MOSFET_N_SMLF-BSS138K,BSS138K,B
FM_HBM2_HBM3_VPP_SEL     U74              G        MOSFET_N_SMLF-BSS138K,BSS138K,A
FM_HBM2_HBM3_VPP_SEL     U122             C10      10M04SAU324I7G-10M04SAU324I7G,A
FM_HBM_VPP_SEL_CPU0_D    R2336            2        Q_RES_0402LF-26.1K,1%,1/16W,EMA
FM_HBM_VPP_SEL_CPU0_D    U73              D        MOSFET_N_SMLF-BSS138K,BSS138K,B
FM_HBM_VPP_SEL_CPU1_D    R2381            2        Q_RES_0402LF-26.1K,1%,1/16W,CHA
FM_HBM_VPP_SEL_CPU1_D    U74              D        MOSFET_N_SMLF-BSS138K,BSS138K,A
FM_INTRUDER_HDR_PCH_N    JP8              2        CONN3_HFK1030G000LAF-CONN3_HFKA
FM_INTRUDER_HDR_PCH_N    R989             1        Q_RES_0402LF-10K,1%,1/16W,CHIPA
FM_INTRUDER_HDR_PCH_N    U4               BG8      EMMITSBURG_REV0P9-GFNOCPU04302A
FM_JTAG_BMC_MUX_SEL      R1813            2        Q_RES_0402LF-10K,1%,1/16W,EMPTA
FM_JTAG_BMC_MUX_SEL      R1814            1        Q_RES_0402LF-1K,1%,1/16W,CHIP,A
FM_JTAG_BMC_MUX_SEL      R1833            1        Q_RES_0402LF-0,5%,1/16W,CHIP,CA
FM_JTAG_BMC_MUX_SEL      R1842            2        Q_RES_0402LF-33.2,1%,1/16W,CHIA
FM_JTAG_BMC_MUX_SEL      U96              7        TS3A24157RSER-TS3A24157RSER,SMA
FM_JTAG_BMC_MUX_SEL      U96              8        TS3A24157RSER-TS3A24157RSER,SMA
FM_JTAG_BMC_MUX_SEL      U97              7        TS3A24157RSER-TS3A24157RSER,SMA
FM_JTAG_BMC_MUX_SEL      U97              8        TS3A24157RSER-TS3A24157RSER,SMA
FM_JTAG_BMC_PLD_MUX_SEL  R1842            1        Q_RES_0402LF-33.2,1%,1/16W,CHIA
FM_JTAG_BMC_PLD_MUX_SEL  U122             A2       10M04SAU324I7G-10M04SAU324I7G,A
FM_JTAG_EDSFF4_SEL       J61              A10      SCONN84_123318136-SCONN84_1-23A
FM_JTAG_EDSFF4_SEL       R2185            1        Q_RES_0402LF-0,5%,1/16W,CHIP,CA
FM_JTAG_ODT_DISABLE      R613             2        Q_RES_0402LF-10K,1%,1/16W,CHIPA
FM_JTAG_ODT_DISABLE      R614             1        Q_RES_0402LF-1K,5%,1/16W,EMPTYA
FM_JTAG_ODT_DISABLE      U4               AW10     EMMITSBURG_REV0P9-GFNOCPU04302A
FM_JTAG_TCK_MUX_SEL      R1365            1        Q_RES_0402LF-1K,1%,1/16W,CHIP,A
FM_JTAG_TCK_MUX_SEL      U85              6        NC7SB3157_SMLF-NC7SB3157P6X,NCA
FM_JTAG_TCK_MUX_SEL      U122             A3       10M04SAU324I7G-10M04SAU324I7G,A
FM_LPC_ESPI_SEL          J41              B9       SCONN168_623403212-SCONN168_6-A
FM_LPC_ESPI_SEL          R1763            2        Q_RES_0402LF-10K,1%,1/16W,EMPTA
FM_LPC_ESPI_SEL          R1764            1        Q_RES_0402LF-1K,1%,1/16W,EMPTYA
FM_LT_KEY_DOWNGRADE_N    R619             2        Q_RES_0402LF-10K,1%,1/16W,CHIPA
FM_LT_KEY_DOWNGRADE_N    U4               L4       EMMITSBURG_REV0P9-GFNOCPU04302A
FM_M2_SSD_1_PEDET        J59              69       SCONN75K_APCI0155P004A-SCONN75A
FM_M2_SSD_1_PEDET        R1396            1        Q_RES_0402LF-10K,1%,1/16W,CHIPA
FM_M2_SSD_1_PEDET        U4               AW23     EMMITSBURG_REV0P9-GFNOCPU04302A
FM_M2_SSD_1_PEDET        U4               BA23     EMMITSBURG_REV0P9-GFNOCPU04302A
FM_M2_SSD_1_PEDET        U4               BA26     EMMITSBURG_REV0P9-GFNOCPU04302A
FM_M2_SSD_1_PEDET        U4               BB21     EMMITSBURG_REV0P9-GFNOCPU04302A
FM_ME_AUTHN_FAIL         R1554            2        Q_RES_0402LF-10K,1%,1/16W,CHIPA
FM_ME_AUTHN_FAIL         U4               AW20     EMMITSBURG_REV0P9-GFNOCPU04302A
FM_ME_AUTHN_FAIL         U122             R17      10M04SAU324I7G-10M04SAU324I7G,A
FM_ME_BT_DONE            R71              2        Q_RES_0402LF-10K,1%,1/16W,CHIPA
FM_ME_BT_DONE            U4               AW29     EMMITSBURG_REV0P9-GFNOCPU04302A
FM_ME_BT_DONE            U122             R18      10M04SAU324I7G-10M04SAU324I7G,A
FM_ME_RCVR_N             R1342            2        Q_RES_0402LF-10K,1%,1/16W,CHIPA
FM_ME_RCVR_N             S2               6        SW8S_DHNF04FTVTR-SW8S_DHNF04FTA
FM_ME_RCVR_N             U4               AG7      EMMITSBURG_REV0P9-GFNOCPU04302A
FM_MFG_MODE              R1298            2        Q_RES_0402LF-1K,5%,1/16W,EMPTYA
FM_MFG_MODE              R1299            1        Q_RES_0402LF-10K,1%,1/16W,CHIPA
FM_MFG_MODE              U4               AG10     EMMITSBURG_REV0P9-GFNOCPU04302A
FM_OCP_SFF_PWR_GOOD      J37              OCP_B1   SCONN168_623403212-SCONN168_6-A
FM_OCP_SFF_PWR_GOOD      R413             2        Q_RES_0402LF-100K,1%,1/16W,CHIA
FM_OCP_SFF_PWR_GOOD      R1606            1        Q_RES_0402LF-0,5%,1/16W,CHIP,CA
FM_OCP_SFF_PWR_GOOD      U66              2        74HC1G126GW-74HC1G126GW,SMLF,IA
FM_OCP_SFF_PWR_GOOD_R    R1606            2        Q_RES_0402LF-0,5%,1/16W,CHIP,CA
FM_OCP_SFF_PWR_GOOD_R    U122             J3       10M04SAU324I7G-10M04SAU324I7G,A
FM_OV_ADR_TRIGGER_N      J44              9        CONN24_52SH90245BRD-CONN24_52SA
FM_OV_ADR_TRIGGER_N      R473             2        Q_RES_0402LF-0,5%,1/16W,CHIP,CA
FM_P12V_E1S_0_EN         R2036            2        Q_RES_0402LF-100K,1%,1/16W,EMPA
FM_P12V_E1S_0_EN         R2160            2        Q_RES_0402LF-0,5%,1/16W,CHIP,CA
FM_P12V_E1S_0_EN         U126             2        TPS259540DSGR-TPS259540DSGR,SMA
FM_P12V_E1S_1_EN         R2042            2        Q_RES_0402LF-100K,1%,1/16W,EMPA
FM_P12V_E1S_1_EN         R2161            2        Q_RES_0402LF-0,5%,1/16W,CHIP,CA
FM_P12V_E1S_1_EN         U128             2        TPS259540DSGR-TPS259540DSGR,SMA
FM_P12V_E1S_2_EN         R2037            2        Q_RES_0402LF-100K,1%,1/16W,EMPA
FM_P12V_E1S_2_EN         R2159            2        Q_RES_0402LF-0,5%,1/16W,CHIP,CA
FM_P12V_E1S_2_EN         U127             2        TPS259540DSGR-TPS259540DSGR,SMA
FM_P12V_E1S_3_EN         R2043            2        Q_RES_0402LF-100K,1%,1/16W,EMPA
FM_P12V_E1S_3_EN         R2162            2        Q_RES_0402LF-0,5%,1/16W,CHIP,CA
FM_P12V_E1S_3_EN         U129             2        TPS259540DSGR-TPS259540DSGR,SMA
FM_P1V05_PCH_AUX_EN      PR1389           1        Q_RES_0402LF-0,5%,1/16W,CHIP,CA
FM_P1V05_PCH_AUX_EN      U122             C9       10M04SAU324I7G-10M04SAU324I7G,A
FM_P1V05_PCH_AUX_R_EN    C1286            1        Q_CAP_0402-1000PF,50V,5%,EMPTYA
FM_P1V05_PCH_AUX_R_EN    PR1388           2        Q_RES_0402LF-0,5%,1/16W,EMPTY,A
FM_P1V05_PCH_AUX_R_EN    PR1389           2        Q_RES_0402LF-0,5%,1/16W,CHIP,CA
FM_P1V05_PCH_AUX_R_EN    PR1647           2        Q_RES_0402LF-10K,1%,1/16W,EMPTA
FM_P1V05_PCH_AUX_R_EN    PU73             8        MPQ8633BGLEC838Z-MPQ8633BGLE-CA
FM_P1V05_PCH_AUX_R_EN    R1649            1        Q_RES_0402LF-2K,1%,1/16W,CHIP,A
FM_P3V3_E1S_0_EN         R2014            2        Q_RES_0402LF-100K,1%,1/16W,EMPA
FM_P3V3_E1S_0_EN         R2164            2        Q_RES_0402LF-0,5%,1/16W,CHIP,CA
FM_P3V3_E1S_0_EN         U40              2        TPS259520DSGR-TPS259520DSGR,SMA
FM_P3V3_E1S_1_EN         R2018            2        Q_RES_0402LF-100K,1%,1/16W,EMPA
FM_P3V3_E1S_1_EN         R2165            2        Q_RES_0402LF-0,5%,1/16W,CHIP,CA
FM_P3V3_E1S_1_EN         U124             2        TPS259520DSGR-TPS259520DSGR,SMA
FM_P3V3_E1S_2_EN         R2015            2        Q_RES_0402LF-100K,1%,1/16W,EMPA
FM_P3V3_E1S_2_EN         R2163            2        Q_RES_0402LF-0,5%,1/16W,CHIP,CA
FM_P3V3_E1S_2_EN         U123             2        TPS259520DSGR-TPS259520DSGR,SMA
FM_P3V3_E1S_3_EN         R2019            2        Q_RES_0402LF-100K,1%,1/16W,EMPA
FM_P3V3_E1S_3_EN         R2166            2        Q_RES_0402LF-0,5%,1/16W,CHIP,CA
FM_P3V3_E1S_3_EN         U125             2        TPS259520DSGR-TPS259520DSGR,SMA
FM_P5V_EN                R1640            1        Q_RES_0402LF-0,5%,1/16W,EMPTY,A
FM_P5V_EN                U122             C6       10M04SAU324I7G-10M04SAU324I7G,A
FM_PASSWORD_CLEAR_N      R1343            2        Q_RES_0402LF-10K,1%,1/16W,CHIPA
FM_PASSWORD_CLEAR_N      S2               5        SW8S_DHNF04FTVTR-SW8S_DHNF04FTA
FM_PASSWORD_CLEAR_N      U4               AB8      EMMITSBURG_REV0P9-GFNOCPU04302A
FM_PCHHOT_N              R474             1        Q_RES_0402LF-33,5%,1/16W,CHIP,A
FM_PCHHOT_N              R1955            2        Q_RES_0402LF-10K,1%,1/16W,CHIPA
FM_PCHHOT_N              U4               AH2      EMMITSBURG_REV0P9-GFNOCPU04302A
FM_PCHHOT_R_N            R474             2        Q_RES_0402LF-33,5%,1/16W,CHIP,A
FM_PCHHOT_R_N            U122             B8       10M04SAU324I7G-10M04SAU324I7G,A
FM_PCH_BIOS_RCVR_MODE    R1338            1        Q_RES_0402LF-10K,1%,1/16W,CHIPA
FM_PCH_BIOS_RCVR_MODE    S1               7        SW8S_DHNF04FTVTR-SW8S_DHNF04FTA
FM_PCH_BIOS_RCVR_MODE    U4               R7       EMMITSBURG_REV0P9-GFNOCPU04302A
FM_PCH_BMC_THERMTRIP_N   R1263            2        Q_RES_0402LF-33,5%,1/16W,CHIP,A
FM_PCH_BMC_THERMTRIP_N   U122             U18      10M04SAU324I7G-10M04SAU324I7G,A
FM_PCH_BOOT_BIOS_STRAP   R371             2        Q_RES_0402LF-1K,5%,1/16W,EMPTYA
FM_PCH_BOOT_BIOS_STRAP   R372             1        Q_RES_0402LF-10K,1%,1/16W,CHIPA
FM_PCH_BOOT_BIOS_STRAP   U4               W1       EMMITSBURG_REV0P9-GFNOCPU04302A
FM_PCH_CONSENT_STRAP_N   R502             2        Q_RES_0402LF-20K,5%,1/16W,EMPTA
FM_PCH_CONSENT_STRAP_N   R771             2        Q_RES_0402LF-1K,1%,1/16W,CHIP,A
FM_PCH_CONSENT_STRAP_N   R1962            1        Q_RES_0402LF-20K,5%,1/16W,CHIPA
FM_PCH_CONSENT_STRAP_N   U4               AT18     EMMITSBURG_REV0P9-GFNOCPU04302A
FM_PCH_CPU_PWR_DEBUG_N   R1247            1        Q_RES_0402LF-0,5%,1/16W,CHIP,CA
FM_PCH_CPU_PWR_DEBUG_N   U4               F5       EMMITSBURG_REV0P9-GFNOCPU04302A
FM_PCH_CRASHLOG_TRIG_N   R699             2        Q_RES_0402LF-33,5%,1/16W,CHIP,A
FM_PCH_CRASHLOG_TRIG_N   U4               AE3      EMMITSBURG_REV0P9-GFNOCPU04302A
FM_PCH_CRASHLOG_TRIG_R_N R699             1        Q_RES_0402LF-33,5%,1/16W,CHIP,A
FM_PCH_CRASHLOG_TRIG_R_N U122             E14      10M04SAU324I7G-10M04SAU324I7G,A
FM_PCH_DFXTESTMODE       R1496            2        Q_RES_0402LF-10K,1%,1/16W,CHIPA
FM_PCH_DFXTESTMODE       R1497            1        Q_RES_0402LF-12K,1%,1/16W,EMPTA
FM_PCH_DFXTESTMODE       U4               P3       EMMITSBURG_REV0P9-GFNOCPU04302A
FM_PCH_EXTERNALCLKMODE   R611             2        Q_RES_0402LF-1K,5%,1/16W,CHIP,A
FM_PCH_EXTERNALCLKMODE   R612             1        Q_RES_0402LF-10K,1%,1/16W,EMPTA
FM_PCH_EXTERNALCLKMODE   U4               L2       EMMITSBURG_REV0P9-GFNOCPU04302A
FM_PCH_GLB_RST_WARN_N    R1258            2        Q_RES_0402LF-10K,1%,1/16W,CHIPA
FM_PCH_GLB_RST_WARN_N    R1313            1        Q_RES_0402LF-33.2,1%,1/16W,CHIA
FM_PCH_GLB_RST_WARN_N    U4               AA1      EMMITSBURG_REV0P9-GFNOCPU04302A
FM_PCH_IO_EXPANDER       R617             2        Q_RES_0402LF-1K,5%,1/16W,EMPTYA
FM_PCH_IO_EXPANDER       R618             1        Q_RES_0402LF-10K,1%,1/16W,CHIPA
FM_PCH_IO_EXPANDER       U4               K1       EMMITSBURG_REV0P9-GFNOCPU04302A
FM_PCH_MCRO_LDO          R1220            2        Q_RES_0402LF-1K,1%,1/16W,EMPTYA
FM_PCH_MCRO_LDO          R1221            1        Q_RES_0402LF-1K,1%,1/16W,CHIP,A
FM_PCH_MCRO_LDO          U4               K3       EMMITSBURG_REV0P9-GFNOCPU04302A
FM_PCH_P1V8_AUX_EN       PR411            1        Q_RES_0402LF-0,5%,1/16W,CHIP,CA
FM_PCH_P1V8_AUX_EN       R1404            1        Q_RES_0402LF-2K,1%,1/16W,CHIP,A
FM_PCH_P1V8_AUX_EN       U122             C8       10M04SAU324I7G-10M04SAU324I7G,A
FM_PCH_P1V8_AUX_EN_R     PR411            2        Q_RES_0402LF-0,5%,1/16W,CHIP,CA
FM_PCH_P1V8_AUX_EN_R     PR412            2        Q_RES_0402LF-0,5%,1/16W,EMPTY,A
FM_PCH_P1V8_AUX_EN_R     PU74             5        NB695GDZ-NB695GD-Z,SMLF,IC,AL0A
FM_PCH_P1V8_AUX_EN_R     R1850            2        Q_RES_0402LF-1K,5%,1/16W,EMPTYA
FM_PCH_PLD_GLB_RST_WARN_N R1313            2        Q_RES_0402LF-33.2,1%,1/16W,CHIA
FM_PCH_PLD_GLB_RST_WARN_N U122             J4       10M04SAU324I7G-10M04SAU324I7G,A
FM_PCH_PRSNT_N           R498             2        Q_RES_0402LF-10K,1%,1/16W,CHIPA
FM_PCH_PRSNT_N           U4               A41      EMMITSBURG_REV0P9-GFNOCPU04302A
FM_PCH_PRSNT_N           U122             G11      10M04SAU324I7G-10M04SAU324I7G,A
FM_PCH_RING_OSC_BYPASS_MGPIO_TE R1475            2        Q_RES_0402LF-1K,1%,1/16W,EMPTYA
FM_PCH_RING_OSC_BYPASS_MGPIO_TE R1476            1        Q_RES_0402LF-1K,1%,1/16W,CHIP,A
FM_PCH_RING_OSC_BYPASS_MGPIO_TE U4               G2       EMMITSBURG_REV0P9-GFNOCPU04302A
FM_PCH_SATA_RAID_KEY     R1271            2        Q_RES_0402LF-2.21K    ,1%  ,1/A
FM_PCH_SATA_RAID_KEY     R1487            1        Q_RES_0402LF-100,1%,1/16W,CHIPA
FM_PCH_SATA_RAID_KEY     U4               BD11     EMMITSBURG_REV0P9-GFNOCPU04302A
FM_PCH_SKIP_RTC_CLOCK    R621             2        Q_RES_0402LF-1K,5%,1/16W,EMPTYA
FM_PCH_SKIP_RTC_CLOCK    R622             1        Q_RES_0402LF-1K,5%,1/16W,CHIP,A
FM_PCH_SKIP_RTC_CLOCK    U4               AU10     EMMITSBURG_REV0P9-GFNOCPU04302A
FM_PCH_SLP_S3_N          R1995            1        Q_RES_0402LF-33,5%,1/16W,CHIP,A
FM_PCH_SLP_S3_N          U4               AP8      EMMITSBURG_REV0P9-GFNOCPU04302A
FM_PCH_SLP_S4_N          R1996            1        Q_RES_0402LF-33,5%,1/16W,CHIP,A
FM_PCH_SLP_S4_N          U4               AL13     EMMITSBURG_REV0P9-GFNOCPU04302A
FM_PCH_SLP_SUS_N         R1736            1        Q_RES_0402LF-0,5%,1/16W,CHIP,CA
FM_PCH_SLP_SUS_N         U4               AL7      EMMITSBURG_REV0P9-GFNOCPU04302A
FM_PCH_SPARE0            R1222            2        Q_RES_0402LF-5.11K,1%,1/16W,CHA
FM_PCH_SPARE0            U4               AN10     EMMITSBURG_REV0P9-GFNOCPU04302A
FM_PCH_TRIGGER0_N        R20              2        Q_RES_0402LF-0,5%,1/16W,CHIP,CA
FM_PCH_TRIGGER0_N        R1200            1        Q_RES_0402LF-100,1%,1/16W,CHIPA
FM_PCH_TRIGGER0_R_N      R1200            2        Q_RES_0402LF-100,1%,1/16W,CHIPA
FM_PCH_TRIGGER0_R_N      R1485            2        Q_RES_0402LF-200,1%,1/16W,EMPTA
FM_PCH_TRIGGER0_R_N      U4               H11      EMMITSBURG_REV0P9-GFNOCPU04302A
FM_PCH_TRIGGER1_N        R21              2        Q_RES_0402LF-0,5%,1/16W,CHIP,CA
FM_PCH_TRIGGER1_N        R1201            1        Q_RES_0402LF-49.9     ,1%  ,1/A
FM_PCH_TRIGGER1_R_N      R1201            2        Q_RES_0402LF-49.9     ,1%  ,1/A
FM_PCH_TRIGGER1_R_N      R1486            2        Q_RES_0402LF-200,1%,1/16W,EMPTA
FM_PCH_TRIGGER1_R_N      U4               K8       EMMITSBURG_REV0P9-GFNOCPU04302A
FM_PCH_VISA_DEFAULT      R615             2        Q_RES_0402LF-1K,5%,1/16W,CHIP,A
FM_PCH_VISA_DEFAULT      U4               G4       EMMITSBURG_REV0P9-GFNOCPU04302A
FM_PCH_XTALSEL           R623             2        Q_RES_0402LF-1K,5%,1/16W,EMPTYA
FM_PCH_XTALSEL           R624             1        Q_RES_0402LF-10K,1%,1/16W,CHIPA
FM_PCH_XTALSEL           U4               R4       EMMITSBURG_REV0P9-GFNOCPU04302A
FM_PCH_XTAL_INPUT_MODE_MGPIO_TE R1477            2        Q_RES_0402LF-1K,1%,1/16W,EMPTYA
FM_PCH_XTAL_INPUT_MODE_MGPIO_TE R1478            1        Q_RES_0402LF-10K,1%,1/16W,CHIPA
FM_PCH_XTAL_INPUT_MODE_MGPIO_TE U4               H3       EMMITSBURG_REV0P9-GFNOCPU04302A
FM_PCIE_EDSFF1A_PRSNT_1_N J62              B42      SCONN84_123318136-SCONN84_1-23A
FM_PCIE_EDSFF1A_PRSNT_1_N R1968            1        Q_RES_0402LF-4.7K,5%,1/16W,CHIA
FM_PCIE_EDSFF1A_PRSNT_1_N U4               U7       EMMITSBURG_REV0P9-GFNOCPU04302A
FM_PCIE_EDSFF1B_PRSNT_1_N J87              B42      SCONN84_123318136-SCONN84_1-23A
FM_PCIE_EDSFF1B_PRSNT_1_N R1978            1        Q_RES_0402LF-4.7K,5%,1/16W,CHIA
FM_PCIE_EDSFF1B_PRSNT_1_N U4               AC10     EMMITSBURG_REV0P9-GFNOCPU04302A
FM_PCIE_EDSFF2A_PRSNT_1_N J33              B42      SCONN84_123318136-SCONN84_1-23A
FM_PCIE_EDSFF2A_PRSNT_1_N R394             1        Q_RES_0402LF-4.7K,5%,1/16W,CHIA
FM_PCIE_EDSFF2A_PRSNT_1_N U4               T8       EMMITSBURG_REV0P9-GFNOCPU04302A
FM_PCIE_EDSFF2B_PRSNT_1_N J34              B42      SCONN84_123318136-SCONN84_1-23A
FM_PCIE_EDSFF2B_PRSNT_1_N R398             1        Q_RES_0402LF-4.7K,5%,1/16W,CHIA
FM_PCIE_EDSFF2B_PRSNT_1_N U4               AC7      EMMITSBURG_REV0P9-GFNOCPU04302A
FM_PCIE_EDSFF3_PRSNT_1_N J35              B42      SCONN140_G64V3431BHR-SCONN140_B
FM_PCIE_EDSFF3_PRSNT_1_N R402             1        Q_RES_0402LF-4.7K,5%,1/16W,CHIA
FM_PCIE_EDSFF3_PRSNT_1_N R2148            1        Q_RES_0402LF-0,5%,1/16W,CHIP,CA
FM_PCIE_EDSFF3_PRSNT_1_N U4               N10      EMMITSBURG_REV0P9-GFNOCPU04302A
FM_PCIE_EDSFF4A_PRSNT_1_N J88              B42      SCONN84_123318136-SCONN84_1-23A
FM_PCIE_EDSFF4A_PRSNT_1_N R1988            1        Q_RES_0402LF-4.7K,5%,1/16W,CHIA
FM_PCIE_EDSFF4A_PRSNT_1_N U4               W13      EMMITSBURG_REV0P9-GFNOCPU04302A
FM_PCIE_EDSFF4B_PRSNT_1_N J61              B42      SCONN84_123318136-SCONN84_1-23A
FM_PCIE_EDSFF4B_PRSNT_1_N R2000            1        Q_RES_0402LF-4.7K,5%,1/16W,CHIA
FM_PCIE_EDSFF4B_PRSNT_1_N U4               AE10     EMMITSBURG_REV0P9-GFNOCPU04302A
FM_PCIE_EV_BIF_EN        R1675            1        Q_RES_0402LF-2.49K,1%,1/16W,CHA
FM_PCIE_EV_BIF_EN        R1676            1        Q_RES_0402LF-1K,1%,1/16W,EMPTYA
FM_PCIE_EV_BIF_EN        U4               F8       EMMITSBURG_REV0P9-GFNOCPU04302A
FM_PEHPCPU0_ALERT_N      Q15              3        MOSFET_NCH_DUAL-2N7002KDW,SMLFA
FM_PEHPCPU0_ALERT_N      R1006            2        Q_RES_0402LF-4.7K,5%,1/16W,CHIA
FM_PEHPCPU0_ALERT_N      U2               BV26     SOCKET4677_AZIFS054P001C01-SOCA
FM_PEHPCPU1_ALERT_N      Q16              3        MOSFET_NCH_DUAL-2N7002KDW,SMLFA
FM_PEHPCPU1_ALERT_N      R1007            2        Q_RES_0402LF-4.7K,5%,1/16W,CHIA
FM_PEHPCPU1_ALERT_N      U1               BV26     SOCKET4677_AZIFS054P001C01-SOCA
FM_PFR_DSW_PWROK_N       R1399            1        Q_RES_0402LF-10K,1%,1/16W,CHIPA
FM_PFR_DSW_PWROK_N       R1745            2        Q_RES_0402LF-0,5%,1/16W,EMPTY,A
FM_PFR_DSW_PWROK_N       U122             T16      10M04SAU324I7G-10M04SAU324I7G,A
FM_PLD_CLKS_DEV_EN       R106             2        Q_RES_0402LF-2K,1%,1/16W,CHIP,A
FM_PLD_CLKS_DEV_EN       R110             2        Q_RES_0402LF-33.2,1%,1/16W,CHIA
FM_PLD_CLKS_DEV_EN       R575             1        Q_RES_0402LF-49.9     ,1%  ,1/A
FM_PLD_CLKS_DEV_EN       R1305            2        Q_RES_0402LF-10K,1%,1/16W,EMPTA
FM_PLD_CLKS_DEV_EN       R1390            1        Q_RES_0402LF-1K,1%,1/16W,EMPTYA
FM_PLD_CLKS_DEV_EN       U13              A17      9SQ440NQQI8-9SQ440NQQI8,SMLF,IA
FM_PLD_CLKS_DEV_EN       U70              G        MOSFET_N_SMLF-BSS138K,BSS138K,A
FM_PLD_CLKS_DEV_R_EN     R110             1        Q_RES_0402LF-33.2,1%,1/16W,CHIA
FM_PLD_CLKS_DEV_R_EN     U122             A8       10M04SAU324I7G-10M04SAU324I7G,A
FM_PLD_CLKS_OE_R_N       R111             2        Q_RES_0402LF-10K,1%,1/16W,CHIPA
FM_PLD_CLKS_OE_R_N       R113             1        Q_RES_0402LF-33.2,1%,1/16W,CHIA
FM_PLD_CLKS_OE_R_N       U70              D        MOSFET_N_SMLF-BSS138K,BSS138K,A
FM_PLD_CLK_25M_EN        R109             2        Q_RES_0402LF-33.2,1%,1/16W,CHIA
FM_PLD_CLK_25M_EN        R1680            1        Q_RES_0402LF-0,5%,1/16W,CHIP,CA
FM_PLD_CLK_25M_R_EN      R109             1        Q_RES_0402LF-33.2,1%,1/16W,CHIA
FM_PLD_CLK_25M_R_EN      R990             1        Q_RES_0402LF-2K,1%,1/16W,CHIP,A
FM_PLD_CLK_25M_R_EN      U122             A9       10M04SAU324I7G-10M04SAU324I7G,A
FM_PLD_HEARTBEAT_LVC3    R1437            1        Q_RES_0402LF-10K,1%,1/16W,CHIPA
FM_PLD_HEARTBEAT_LVC3    U89              G        MOSFET_N_SMLF-BSS138K,BSS138K,A
FM_PLD_HEARTBEAT_LVC3    U122             D5       10M04SAU324I7G-10M04SAU324I7G,A
FM_PLD_HEARTBEAT_LVC3_D  D0               C        Q_LED_SMLF-LED_GREEN,19-213/GVA
FM_PLD_HEARTBEAT_LVC3_D  U89              D        MOSFET_N_SMLF-BSS138K,BSS138K,A
FM_PLD_REV_N             C1325            1        Q_CAP_0402-0.1UF,25V,10%,X7R,CA
FM_PLD_REV_N             R1710            2        Q_RES_0402LF-49.9     ,1%  ,1/A
FM_PLD_REV_N             U122             D6       10M04SAU324I7G-10M04SAU324I7G,A
FM_PLD_REV_R_N           R1106            2        Q_RES_0402LF-10K,1%,1/16W,CHIPA
FM_PLD_REV_R_N           R1710            1        Q_RES_0402LF-49.9     ,1%  ,1/A
FM_PLT_BMC_THERMTRIP_R_N R1263            1        Q_RES_0402LF-33,5%,1/16W,CHIP,A
FM_PLT_BMC_THERMTRIP_R_N R1820            2        Q_RES_0402LF-10K,1%,1/16W,CHIPA
FM_PLT_BMC_THERMTRIP_R_N U4               Y2       EMMITSBURG_REV0P9-GFNOCPU04302A
FM_PMBUS_ALERT_B_EN      R1659            1        Q_RES_0402LF-10K,1%,1/16W,CHIPA
FM_PMBUS_ALERT_B_EN      U4               AV3      EMMITSBURG_REV0P9-GFNOCPU04302A
FM_PSU_THROTTLE_L        L12              2        Q_INDUCTOR_SMLF-BLM15AG121SN1DA
FM_PSU_THROTTLE_L        R1539            1        Q_RES_0402LF-10K,1%,1/16W,CHIPA
FM_PSU_THROTTLE_L        U19              G        MOSFET_N_SMLF-BSS138K,BSS138K,A
FM_PSU_THROTTLE_N        R1540            2        Q_RES_0402LF-100K,1%,1/16W,EMPB
FM_PSU_THROTTLE_N        U19              D        MOSFET_N_SMLF-BSS138K,BSS138K,A
FM_PSU_THROTTLE_N        U122             G1       10M04SAU324I7G-10M04SAU324I7G,A
FM_PS_EN_PLD_R           R1607            1        Q_RES_0402LF-0,5%,1/16W,CHIP,CA
FM_PS_EN_PLD_R           U122             N18      10M04SAU324I7G-10M04SAU324I7G,A
FM_PS_PWROK_DLY_R_SEL    R8               2        Q_RES_0402LF-10K,1%,1/16W,CHIPA
FM_PS_PWROK_DLY_R_SEL    R1306            1        Q_RES_0402LF-33.2,1%,1/16W,CHIA
FM_PS_PWROK_DLY_R_SEL    U4               BA20     EMMITSBURG_REV0P9-GFNOCPU04302A
FM_PS_PWROK_DLY_SEL      R1306            2        Q_RES_0402LF-33.2,1%,1/16W,CHIA
FM_PS_PWROK_DLY_SEL      U122             A10      10M04SAU324I7G-10M04SAU324I7G,A
FM_PVCCD_HV_CPU0_EN      PR363            1        Q_RES_0402LF-0,5%,1/16W,CHIP,CA
FM_PVCCD_HV_CPU0_EN      R1413            1        Q_RES_0402LF-2K,1%,1/16W,CHIP,A
FM_PVCCD_HV_CPU0_EN      U122             A14      10M04SAU324I7G-10M04SAU324I7G,A
FM_PVCCD_HV_CPU1_EN      PR208            1        Q_RES_0402LF-0,5%,1/16W,CHIP,CA
FM_PVCCD_HV_CPU1_EN      R1414            1        Q_RES_0402LF-2K,1%,1/16W,CHIP,A
FM_PVCCD_HV_CPU1_EN      U122             C14      10M04SAU324I7G-10M04SAU324I7G,A
FM_PVCCFA_EHV_CPU0_EN    PR119            1        Q_RES_0402LF-0,5%,1/16W,CHIP,CA
FM_PVCCFA_EHV_CPU0_EN    R982             2        Q_RES_0402LF-33,5%,1/16W,CHIP,A
FM_PVCCFA_EHV_CPU0_R_EN  R982             1        Q_RES_0402LF-33,5%,1/16W,CHIP,A
FM_PVCCFA_EHV_CPU0_R_EN  R1409            1        Q_RES_0402LF-2K,1%,1/16W,CHIP,A
FM_PVCCFA_EHV_CPU0_R_EN  U122             A13      10M04SAU324I7G-10M04SAU324I7G,A
FM_PVCCFA_EHV_CPU1_EN    PR272            1        Q_RES_0402LF-0,5%,1/16W,CHIP,CA
FM_PVCCFA_EHV_CPU1_EN    R986             2        Q_RES_0402LF-33,5%,1/16W,CHIP,A
FM_PVCCFA_EHV_CPU1_R_EN  R986             1        Q_RES_0402LF-33,5%,1/16W,CHIP,A
FM_PVCCFA_EHV_CPU1_R_EN  R1410            1        Q_RES_0402LF-2K,1%,1/16W,CHIP,A
FM_PVCCFA_EHV_CPU1_R_EN  U122             C13      10M04SAU324I7G-10M04SAU324I7G,A
FM_PVCCFA_EHV_FIVRA_CPU0_EN PR337            1        Q_RES_0402LF-0,5%,1/16W,CHIP,CA
FM_PVCCFA_EHV_FIVRA_CPU0_EN R984             2        Q_RES_0402LF-33,5%,1/16W,CHIP,A
FM_PVCCFA_EHV_FIVRA_CPU0_R_EN R984             1        Q_RES_0402LF-33,5%,1/16W,CHIP,A
FM_PVCCFA_EHV_FIVRA_CPU0_R_EN R1411            1        Q_RES_0402LF-2K,1%,1/16W,CHIP,A
FM_PVCCFA_EHV_FIVRA_CPU0_R_EN U122             A15      10M04SAU324I7G-10M04SAU324I7G,A
FM_PVCCFA_EHV_FIVRA_CPU1_EN PR234            1        Q_RES_0402LF-0,5%,1/16W,CHIP,CA
FM_PVCCFA_EHV_FIVRA_CPU1_EN R988             2        Q_RES_0402LF-33,5%,1/16W,CHIP,A
FM_PVCCFA_EHV_FIVRA_CPU1_R_EN R988             1        Q_RES_0402LF-33,5%,1/16W,CHIP,A
FM_PVCCFA_EHV_FIVRA_CPU1_R_EN R1412            1        Q_RES_0402LF-2K,1%,1/16W,CHIP,A
FM_PVCCFA_EHV_FIVRA_CPU1_R_EN U122             C15      10M04SAU324I7G-10M04SAU324I7G,A
FM_PVCCINFAON_CPU0_EN    PR111            1        Q_RES_0402LF-0,5%,1/16W,CHIP,CA
FM_PVCCINFAON_CPU0_EN    R983             2        Q_RES_0402LF-33,5%,1/16W,CHIP,A
FM_PVCCINFAON_CPU0_R_EN  R983             1        Q_RES_0402LF-33,5%,1/16W,CHIP,A
FM_PVCCINFAON_CPU0_R_EN  R1407            1        Q_RES_0402LF-2K,1%,1/16W,CHIP,A
FM_PVCCINFAON_CPU0_R_EN  U122             A12      10M04SAU324I7G-10M04SAU324I7G,A
FM_PVCCINFAON_CPU1_EN    PR264            1        Q_RES_0402LF-0,5%,1/16W,CHIP,CA
FM_PVCCINFAON_CPU1_EN    R987             2        Q_RES_0402LF-33,5%,1/16W,CHIP,A
FM_PVCCINFAON_CPU1_R_EN  R987             1        Q_RES_0402LF-33,5%,1/16W,CHIP,A
FM_PVCCINFAON_CPU1_R_EN  R1408            1        Q_RES_0402LF-2K,1%,1/16W,CHIP,A
FM_PVCCINFAON_CPU1_R_EN  U122             C12      10M04SAU324I7G-10M04SAU324I7G,A
FM_PVCCIN_CPU0_EN        PR162            1        Q_RES_0402LF-0,5%,1/16W,CHIP,CA
FM_PVCCIN_CPU0_EN        R981             2        Q_RES_0402LF-33,5%,1/16W,CHIP,A
FM_PVCCIN_CPU0_R_EN      R981             1        Q_RES_0402LF-33,5%,1/16W,CHIP,A
FM_PVCCIN_CPU0_R_EN      R1405            1        Q_RES_0402LF-2K,1%,1/16W,CHIP,A
FM_PVCCIN_CPU0_R_EN      U122             A11      10M04SAU324I7G-10M04SAU324I7G,A
FM_PVCCIN_CPU1_EN        PR309            1        Q_RES_0402LF-0,5%,1/16W,CHIP,CA
FM_PVCCIN_CPU1_EN        R985             2        Q_RES_0402LF-33,5%,1/16W,CHIP,A
FM_PVCCIN_CPU1_R_EN      R985             1        Q_RES_0402LF-33,5%,1/16W,CHIP,A
FM_PVCCIN_CPU1_R_EN      R1406            1        Q_RES_0402LF-2K,1%,1/16W,CHIP,A
FM_PVCCIN_CPU1_R_EN      U122             C11      10M04SAU324I7G-10M04SAU324I7G,A
FM_PVNN_MAIN_CPU0_EN     C1307            1        Q_CAP_0402-1000PF,50V,5%,EMPTYA
FM_PVNN_MAIN_CPU0_EN     PU81             5        MPQ8626GDZ-MPQ8626GD-Z,SMLF,ICA
FM_PVNN_MAIN_CPU0_EN     R1445            1        Q_RES_0402LF-2K,1%,1/16W,CHIP,A
FM_PVNN_MAIN_CPU0_EN     R2338            2        Q_RES_0402LF-10K,1%,1/16W,EMPTA
FM_PVNN_MAIN_CPU0_EN     U122             A16      10M04SAU324I7G-10M04SAU324I7G,A
FM_PVNN_MAIN_CPU1_EN     C1308            1        Q_CAP_0402-1000PF,50V,5%,EMPTYA
FM_PVNN_MAIN_CPU1_EN     PU82             5        MPQ8626GDZ-MPQ8626GD-Z,SMLF,ICA
FM_PVNN_MAIN_CPU1_EN     R2384            2        Q_RES_0402LF-10K,1%,1/16W,EMPTA
FM_PVNN_MAIN_CPU1_EN     R2385            1        Q_RES_0402LF-2K,1%,1/16W,CHIP,A
FM_PVNN_MAIN_CPU1_EN     U122             C16      10M04SAU324I7G-10M04SAU324I7G,A
FM_PVPP_HBM_CPU0_EN      C1300            1        Q_CAP_0402-1000PF,50V,5%,EMPTYA
FM_PVPP_HBM_CPU0_EN      PU79             8        MPQ8633AGLEC807Z-MPQ8633AGLE-CA
FM_PVPP_HBM_CPU0_EN      R2330            2        Q_RES_0402LF-10K,1%,1/16W,EMPTA
FM_PVPP_HBM_CPU0_EN      R2332            1        Q_RES_0402LF-2K,1%,1/16W,EMPTYA
FM_PVPP_HBM_CPU0_EN      U122             C4       10M04SAU324I7G-10M04SAU324I7G,A
FM_PVPP_HBM_CPU1_EN      C2445            1        Q_CAP_0402-1000PF,50V,5%,EMPTYA
FM_PVPP_HBM_CPU1_EN      PU80             8        MPQ8633AGLEC807Z-MPQ8633AGLE-CB
FM_PVPP_HBM_CPU1_EN      R2367            2        Q_RES_0402LF-10K,1%,1/16W,EMPTA
FM_PVPP_HBM_CPU1_EN      R2374            1        Q_RES_0402LF-2K,1%,1/16W,CHIP,A
FM_PVPP_HBM_CPU1_EN      U122             C5       10M04SAU324I7G-10M04SAU324I7G,A
FM_REMOTE_DEBUG_DET_R    R1370            2        Q_RES_0402LF-100,1%,1/16W,EMPTA
FM_REMOTE_DEBUG_DET_R    R1372            1        Q_RES_0402LF-1K,1%,1/16W,CHIP,A
FM_REMOTE_DEBUG_DET_R    U87              G        MOSFET_N_SMLF-BSS138K,BSS138K,A
FM_RISER1_JTAG_SEL_PLD_N R2185            2        Q_RES_0402LF-0,5%,1/16W,CHIP,CA
FM_RISER1_JTAG_SEL_PLD_N U122             J18      10M04SAU324I7G-10M04SAU324I7G,A
FM_RISER1_PWRBRK_N       J55              A8       SCONN140_G64V3431BHR-SCONN140_A
FM_RISER1_PWRBRK_N       R2169            2        Q_RES_0402LF-0,5%,1/16W,CHIP,CA
FM_RISER2_JTAG_SEL_N     J89              A22      SCONN280_ME1028040102011-SCONNA
FM_RISER2_JTAG_SEL_N     R2139            2        Q_RES_0402LF-0,5%,1/16W,CHIP,CA
FM_RISER2_JTAG_SEL_N     R2140            2        Q_RES_0402LF-10K,5%,1/16W,CHIPA
FM_RISER2_JTAG_SEL_PLD_N R2139            1        Q_RES_0402LF-0,5%,1/16W,CHIP,CA
FM_RISER2_JTAG_SEL_PLD_N U122             B14      10M04SAU324I7G-10M04SAU324I7G,A
FM_RISER2_PWRBRK_N       J89              B28      SCONN280_ME1028040102011-SCONNA
FM_RISER2_PWRBRK_N       R1573            2        Q_RES_0402LF-0,5%,1/16W,CHIP,CA
FM_RISER3_PWRBRK_N       J57              A8       SCONN140_G64V3431BHR-SCONN140_A
FM_RISER3_PWRBRK_N       R1577            2        Q_RES_0402LF-0,5%,1/16W,CHIP,CA
FM_RST_PERST_BIT0        R1741            1        Q_RES_0402LF-1K,1%,1/16W,CHIP,A
FM_RST_PERST_BIT0        R1742            1        Q_RES_0402LF-10K,1%,1/16W,EMPTA
FM_RST_PERST_BIT0        U122             E17      10M04SAU324I7G-10M04SAU324I7G,A
FM_RST_PERST_BIT1        R1308            1        Q_RES_0402LF-10K,1%,1/16W,EMPTA
FM_RST_PERST_BIT1        R1473            1        Q_RES_0402LF-1K,1%,1/16W,CHIP,A
FM_RST_PERST_BIT1        U122             E16      10M04SAU324I7G-10M04SAU324I7G,A
FM_RST_PERST_BIT2        R1312            1        Q_RES_0402LF-10K,1%,1/16W,EMPTA
FM_RST_PERST_BIT2        R1474            1        Q_RES_0402LF-1K,1%,1/16W,CHIP,A
FM_RST_PERST_BIT2        U122             E15      10M04SAU324I7G-10M04SAU324I7G,A
FM_S3M_CPU0_CPLD_CONFIG_N R321             2        Q_RES_0402LF-10K,1%,1/16W,CHIPA
FM_S3M_CPU0_CPLD_CONFIG_N U2               CK65     SOCKET4677_AZIFS054P001C01-SOCA
FM_S3M_CPU0_CPLD_CONFIG_N U122             K15      10M04SAU324I7G-10M04SAU324I7G,A
FM_S3M_CPU0_CPLD_CRC_ERROR R1216            2        Q_RES_0402LF-10K,1%,1/16W,CHIPA
FM_S3M_CPU0_CPLD_CRC_ERROR U2               CY20     SOCKET4677_AZIFS054P001C01-SOCA
FM_S3M_CPU0_CPLD_CRC_ERROR U122             L1       10M04SAU324I7G-10M04SAU324I7G,A
FM_S3M_CPU0_LVC1_GPIO_0  R249             2        Q_RES_0402LF-240,1%,1/16W,EMPTA
FM_S3M_CPU0_LVC1_GPIO_0  U2               BA70     SOCKET4677_AZIFS054P001C01-SOCA
FM_S3M_CPU0_LVC1_GPIO_1  R250             2        Q_RES_0402LF-240,1%,1/16W,EMPTA
FM_S3M_CPU0_LVC1_GPIO_1  U2               AV71     SOCKET4677_AZIFS054P001C01-SOCA
FM_S3M_CPU0_LVC1_GPIO_2  R253             2        Q_RES_0402LF-240,1%,1/16W,CHIPA
FM_S3M_CPU0_LVC1_GPIO_2  R1391            2        Q_RES_0402LF-240,1%,1/16W,EMPTA
FM_S3M_CPU0_LVC1_GPIO_2  U2               AV69     SOCKET4677_AZIFS054P001C01-SOCA
FM_S3M_CPU0_LVC1_GPIO_3  R254             2        Q_RES_0402LF-240,1%,1/16W,CHIPA
FM_S3M_CPU0_LVC1_GPIO_3  R1392            2        Q_RES_0402LF-240,1%,1/16W,EMPTA
FM_S3M_CPU0_LVC1_GPIO_3  U2               AY69     SOCKET4677_AZIFS054P001C01-SOCA
FM_S3M_CPU0_LVC1_GPIO_4  R251             2        Q_RES_0402LF-240,1%,1/16W,EMPTA
FM_S3M_CPU0_LVC1_GPIO_4  U2               AW70     SOCKET4677_AZIFS054P001C01-SOCA
FM_S3M_CPU1_CPLD_CONFIG_N R327             2        Q_RES_0402LF-10K,1%,1/16W,CHIPA
FM_S3M_CPU1_CPLD_CONFIG_N U1               CK65     SOCKET4677_AZIFS054P001C01-SOCA
FM_S3M_CPU1_CPLD_CONFIG_N U122             K16      10M04SAU324I7G-10M04SAU324I7G,A
FM_S3M_CPU1_CPLD_CRC_ERROR R1217            2        Q_RES_0402LF-10K,1%,1/16W,CHIPA
FM_S3M_CPU1_CPLD_CRC_ERROR U1               CY20     SOCKET4677_AZIFS054P001C01-SOCA
FM_S3M_CPU1_CPLD_CRC_ERROR U122             L2       10M04SAU324I7G-10M04SAU324I7G,A
FM_S3M_CPU1_LVC1_GPIO_0  R255             2        Q_RES_0402LF-240,1%,1/16W,EMPTA
FM_S3M_CPU1_LVC1_GPIO_0  U1               BA70     SOCKET4677_AZIFS054P001C01-SOCA
FM_S3M_CPU1_LVC1_GPIO_1  R256             2        Q_RES_0402LF-240,1%,1/16W,EMPTA
FM_S3M_CPU1_LVC1_GPIO_1  U1               AV71     SOCKET4677_AZIFS054P001C01-SOCA
FM_S3M_CPU1_LVC1_GPIO_2  R259             2        Q_RES_0402LF-240,1%,1/16W,CHIPA
FM_S3M_CPU1_LVC1_GPIO_2  R1393            2        Q_RES_0402LF-240,1%,1/16W,EMPTA
FM_S3M_CPU1_LVC1_GPIO_2  U1               AV69     SOCKET4677_AZIFS054P001C01-SOCA
FM_S3M_CPU1_LVC1_GPIO_3  R260             2        Q_RES_0402LF-240,1%,1/16W,CHIPA
FM_S3M_CPU1_LVC1_GPIO_3  R1394            2        Q_RES_0402LF-240,1%,1/16W,EMPTA
FM_S3M_CPU1_LVC1_GPIO_3  U1               AY69     SOCKET4677_AZIFS054P001C01-SOCA
FM_S3M_CPU1_LVC1_GPIO_4  R257             2        Q_RES_0402LF-240,1%,1/16W,EMPTA
FM_S3M_CPU1_LVC1_GPIO_4  U1               AW70     SOCKET4677_AZIFS054P001C01-SOCA
FM_SCM_PRSNT1_N          J41              A57      SCONN168_623403212-SCONN168_6-A
FM_SCM_PRSNT1_N          R1854            2        Q_RES_0402LF-10K,1%,1/16W,CHIPA
FM_SCM_PRSNT1_N          R1856            1        Q_RES_0402LF-100,1%,1/16W,CHIPA
FM_SCM_PRSNT1_R_N        Q39              5        MOSFET_NCH_DUAL-2N7002KDW,SMLFA
FM_SCM_PRSNT1_R_N        R1856            2        Q_RES_0402LF-100,1%,1/16W,CHIPA
FM_SLPS3_PLD_N           R1995            2        Q_RES_0402LF-33,5%,1/16W,CHIP,A
FM_SLPS3_PLD_N           U122             L17      10M04SAU324I7G-10M04SAU324I7G,A
FM_SLPS4_PLD_N           R1996            2        Q_RES_0402LF-33,5%,1/16W,CHIP,A
FM_SLPS4_PLD_N           U122             L18      10M04SAU324I7G-10M04SAU324I7G,A
FM_SLP_SUS_RSM_RST_N     R1660            1        Q_RES_0402LF-10K,1%,1/16W,EMPTA
FM_SLP_SUS_RSM_RST_N     R1736            2        Q_RES_0402LF-0,5%,1/16W,CHIP,CA
FM_SLP_SUS_RSM_RST_N     U122             G12      10M04SAU324I7G-10M04SAU324I7G,A
FM_SMB_CPU0_ALERT        R1921            1        Q_RES_0402LF-33,5%,1/16W,CHIP,A
FM_SMB_CPU0_ALERT        U51              1        PCA9555PW_SMLF-PCA9555PW,IC,TMA
FM_SMB_CPU0_ALERT_R1     Q15              5        MOSFET_NCH_DUAL-2N7002KDW,SMLFA
FM_SMB_CPU0_ALERT_R1     Q15              6        MOSFET_NCH_DUAL-2N7002KDW,SMLFA
FM_SMB_CPU0_ALERT_R1     R1002            2        Q_RES_0402LF-4.7K,5%,1/16W,CHIA
FM_SMB_CPU1_ALERT_R1     Q16              5        MOSFET_NCH_DUAL-2N7002KDW,SMLFA
FM_SMB_CPU1_ALERT_R1     Q16              6        MOSFET_NCH_DUAL-2N7002KDW,SMLFA
FM_SMB_CPU1_ALERT_R1     R1003            2        Q_RES_0402LF-4.7K,5%,1/16W,CHIA
FM_SMB_PEHPCPU0_PCIE_ALERT_N JP7              1        CONN3_210HP1030BR1-CONN3_210-HA
FM_SMB_PEHPCPU0_PCIE_ALERT_N R998             1        Q_RES_0402LF-0,5%,1/16W,CHIP,CA
FM_SMB_PEHPCPU0_PCIE_ALERT_N R1921            2        Q_RES_0402LF-33,5%,1/16W,CHIP,A
FM_SMB_PEHPCPU0_PCIE_ALERT_R_N Q15              2        MOSFET_NCH_DUAL-2N7002KDW,SMLFA
FM_SMB_PEHPCPU0_PCIE_ALERT_R_N R998             2        Q_RES_0402LF-0,5%,1/16W,CHIP,CA
FM_SMB_PEHPCPU0_PCIE_ALERT_R_N R1000            2        Q_RES_0402LF-4.7K,5%,1/16W,CHIA
FM_SMB_PEHPCPU1_PCIE_ALERT_N JP7              3        CONN3_210HP1030BR1-CONN3_210-HA
FM_SMB_PEHPCPU1_PCIE_ALERT_N R999             1        Q_RES_0402LF-0,5%,1/16W,CHIP,CA
FM_SMB_PEHPCPU1_PCIE_ALERT_R_N Q16              2        MOSFET_NCH_DUAL-2N7002KDW,SMLFA
FM_SMB_PEHPCPU1_PCIE_ALERT_R_N R999             2        Q_RES_0402LF-0,5%,1/16W,CHIP,CA
FM_SMB_PEHPCPU1_PCIE_ALERT_R_N R1001            2        Q_RES_0402LF-4.7K,5%,1/16W,CHIA
FM_SPD_REMOTE_EN         R87              2        Q_RES_0402LF-1K,5%,1/16W,EMPTYA
FM_SPD_REMOTE_EN         R318             1        Q_RES_0402LF-10K,1%,1/16W,CHIPA
FM_SPD_REMOTE_EN         R1821            2        Q_RES_0402LF-0,5%,1/16W,EMPTY,A
FM_SPD_REMOTE_EN         U14              1        IDTQS3VH257QG_SMLF-IDTQS3VH257A
FM_SPD_REMOTE_EN         U15              1        IDTQS3VH257QG_SMLF-IDTQS3VH257A
FM_SPD_REMOTE_EN_R       R1821            1        Q_RES_0402LF-0,5%,1/16W,EMPTY,A
FM_SPD_REMOTE_EN_R       U122             A7       10M04SAU324I7G-10M04SAU324I7G,A
FM_SPI_3V3_1V8_VOLTAGE   R374             2        Q_RES_0402LF-1K,5%,1/16W,EMPTYA
FM_SPI_3V3_1V8_VOLTAGE   R375             1        Q_RES_0402LF-10K,1%,1/16W,CHIPA
FM_SPI_3V3_1V8_VOLTAGE   U4               AU13     EMMITSBURG_REV0P9-GFNOCPU04302A
FM_SUSACK_N              R1461            2        Q_RES_0402LF-0,5%,1/16W,CHIP,CA
FM_SUSACK_N              R2071            2        Q_RES_0402LF-0,5%,1/16W,EMPTY,A
FM_SUSACK_N              U4               BA7      EMMITSBURG_REV0P9-GFNOCPU04302A
FM_SYS_THROTTLE_R_N      R85              2        Q_RES_0402LF-10K,5%,1/16W,EMPTA
FM_SYS_THROTTLE_R_N      R86              2        Q_RES_0402LF-10K,5%,1/16W,EMPTA
FM_SYS_THROTTLE_R_N      R1434            1        Q_RES_0402LF-10K,1%,1/16W,CHIPA
FM_SYS_THROTTLE_R_N      R1573            1        Q_RES_0402LF-0,5%,1/16W,CHIP,CA
FM_SYS_THROTTLE_R_N      R1577            1        Q_RES_0402LF-0,5%,1/16W,CHIP,CA
FM_SYS_THROTTLE_R_N      R1584            2        Q_RES_0402LF-10K,5%,1/16W,EMPTA
FM_SYS_THROTTLE_R_N      R1585            1        Q_RES_0402LF-0,5%,1/16W,CHIP,CA
FM_SYS_THROTTLE_R_N      R1586            2        Q_RES_0402LF-10K,5%,1/16W,EMPTA
FM_SYS_THROTTLE_R_N      R1587            1        Q_RES_0402LF-0,5%,1/16W,CHIP,CA
FM_SYS_THROTTLE_R_N      R1588            2        Q_RES_0402LF-10K,5%,1/16W,EMPTA
FM_SYS_THROTTLE_R_N      R1589            1        Q_RES_0402LF-0,5%,1/16W,CHIP,CA
FM_SYS_THROTTLE_R_N      R1964            2        Q_RES_0402LF-10K,5%,1/16W,EMPTA
FM_SYS_THROTTLE_R_N      R1965            1        Q_RES_0402LF-0,5%,1/16W,CHIP,CA
FM_SYS_THROTTLE_R_N      R1974            2        Q_RES_0402LF-10K,5%,1/16W,EMPTA
FM_SYS_THROTTLE_R_N      R1975            1        Q_RES_0402LF-0,5%,1/16W,CHIP,CA
FM_SYS_THROTTLE_R_N      R1984            2        Q_RES_0402LF-10K,5%,1/16W,EMPTA
FM_SYS_THROTTLE_R_N      R1985            1        Q_RES_0402LF-0,5%,1/16W,CHIP,CA
FM_SYS_THROTTLE_R_N      R2168            2        Q_RES_0402LF-10K,5%,1/16W,EMPTA
FM_SYS_THROTTLE_R_N      R2169            1        Q_RES_0402LF-0,5%,1/16W,CHIP,CA
FM_SYS_THROTTLE_R_N      U104             2        74LVC1G07GV-74LVC1G07GV,SMLF,IA
FM_SYS_THROTTLE_R_N      U122             G18      10M04SAU324I7G-10M04SAU324I7G,A
FM_THERMTRIP_DLY_LVC1_N  R1249            1        Q_RES_0402LF-0,5%,1/16W,CHIP,CA
FM_THERMTRIP_DLY_LVC1_N  R1318            2        Q_RES_0402LF-33.2,1%,1/16W,CHIA
FM_THERMTRIP_DLY_LVC1_R_N R1318            1        Q_RES_0402LF-33.2,1%,1/16W,CHIA
FM_THERMTRIP_DLY_LVC1_R_N U122             T4       10M04SAU324I7G-10M04SAU324I7G,A
FM_THROTTLE_N            R1307            1        Q_RES_0402LF-33.2,1%,1/16W,CHIA
FM_THROTTLE_N            R1450            2        Q_RES_0402LF-10K,1%,1/16W,CHIPA
FM_THROTTLE_N            U4               AW2      EMMITSBURG_REV0P9-GFNOCPU04302A
FM_THROTTLE_R_N          R1307            2        Q_RES_0402LF-33.2,1%,1/16W,CHIA
FM_THROTTLE_R_N          U122             E18      10M04SAU324I7G-10M04SAU324I7G,A
FM_TPM_PRSNT_N           R1547            2        Q_RES_0402LF-0,5%,1/16W,CHIP,CA
FM_TPM_PRSNT_N           U4               BB31     EMMITSBURG_REV0P9-GFNOCPU04302A
FM_TPM_PRSNT_R_N         R1547            1        Q_RES_0402LF-0,5%,1/16W,CHIP,CA
FM_TPM_PRSNT_R_N         U122             J6       10M04SAU324I7G-10M04SAU324I7G,A
FM_UV_ADR_TRIGGER_N      J44              11       CONN24_52SH90245BRD-CONN24_52SA
FM_UV_ADR_TRIGGER_N      R948             2        Q_RES_0402LF-0,5%,1/16W,CHIP,CA
FM_UV_ADR_TRIGGER_N      U122             G10      10M04SAU324I7G-10M04SAU324I7G,A
FM_XTAL_INPUT_FREQUENCY_0_MGPIO R382             2        Q_RES_0402LF-1K,5%,1/16W,EMPTYA
FM_XTAL_INPUT_FREQUENCY_0_MGPIO R1311            1        Q_RES_0402LF-10K,1%,1/16W,CHIPA
FM_XTAL_INPUT_FREQUENCY_0_MGPIO U4               BB18     EMMITSBURG_REV0P9-GFNOCPU04302A
FM_XTAL_INPUT_FREQUENCY_1_MGPIO R1315            2        Q_RES_0402LF-1K,5%,1/16W,EMPTYA
FM_XTAL_INPUT_FREQUENCY_1_MGPIO R1457            1        Q_RES_0402LF-10K,1%,1/16W,CHIPA
FM_XTAL_INPUT_FREQUENCY_1_MGPIO U4               AR16     EMMITSBURG_REV0P9-GFNOCPU04302A
FP_DPLD_ANAIN1           R509             1        Q_RES_0402LF-0,5%,1/16W,CHIP,CA
FP_DPLD_ANAIN1           U122             E2       10M04SAU324I7G-10M04SAU324I7G,A
GND                      BT1              2        CONN2_AAABAT029P15-CONN2_AAA-BA
GND                      C1               2        Q_CAP_C0402-10UF,6.3V,20%,X6S,A
GND                      C2               2        Q_CAP_C0402-2.2UF,6.3V,20%,X6SA
GND                      C3               2        Q_CAP_C0805-10UF,16V,10%,X7R,CA
GND                      C4               2        Q_CAP_C0805-10UF,16V,10%,X7R,CA
GND                      C5               2        Q_CAP_C0402-2.2UF,6.3V,20%,X6SA
GND                      C6               2        Q_CAP_C0805-10UF,16V,10%,X7R,CA
GND                      C7               2        Q_CAP_C0805-10UF,16V,10%,X7R,CA
GND                      C8               2        Q_CAP_C0402-2.2UF,6.3V,20%,X6SA
GND                      C9               2        Q_CAP_C0805-10UF,16V,10%,X7R,CA
GND                      C10              2        Q_CAP_C0805-10UF,16V,10%,X7R,CA
GND                      C11              2        Q_CAP_C0402-2.2UF,6.3V,20%,X6SA
GND                      C12              2        Q_CAP_C0805-10UF,16V,10%,X7R,CA
GND                      C13              2        Q_CAP_C0805-10UF,16V,10%,X7R,CA
GND                      C14              2        Q_CAP_C0402-2.2UF,6.3V,20%,X6SA
GND                      C15              2        Q_CAP_C0805-10UF,16V,10%,X7R,CA
GND                      C16              2        Q_CAP_C0805-10UF,16V,10%,X7R,CA
GND                      C17              2        Q_CAP_C0402-2.2UF,6.3V,20%,X6SA
GND                      C18              2        Q_CAP_C0805-10UF,16V,10%,X7R,CA
GND                      C19              2        Q_CAP_C0805-10UF,16V,10%,X7R,CA
GND                      C20              2        Q_CAP_C0402-2.2UF,6.3V,20%,X6SA
GND                      C21              2        Q_CAP_C0805-10UF,16V,10%,X7R,CA
GND                      C22              2        Q_CAP_C0805-10UF,16V,10%,X7R,CA
GND                      C23              2        Q_CAP_C0402-2.2UF,6.3V,20%,X6SA
GND                      C24              2        Q_CAP_C0805-10UF,16V,10%,X7R,CA
GND                      C25              2        Q_CAP_C0805-22UF,16V,20%,X6S,CA
GND                      C26              2        Q_CAP_C0402-2.2UF,6.3V,20%,X6SA
GND                      C27              2        Q_CAP_C0805-10UF,16V,10%,X7R,CA
GND                      C28              2        Q_CAP_C0805-10UF,16V,10%,X7R,CA
GND                      C29              2        Q_CAP_C0402-2.2UF,6.3V,20%,X6SA
GND                      C30              2        Q_CAP_C0805-10UF,16V,10%,X7R,CA
GND                      C31              2        Q_CAP_C0805-10UF,16V,10%,X7R,CA
GND                      C32              2        Q_CAP_C0402-2.2UF,6.3V,20%,X6SA
GND                      C33              2        Q_CAP_C0805-10UF,16V,10%,X7R,CA
GND                      C34              2        Q_CAP_C0805-10UF,16V,10%,X7R,CA
GND                      C35              2        Q_CAP_C0402-2.2UF,6.3V,20%,X6SA
GND                      C36              2        Q_CAP_C0805-10UF,16V,10%,X7R,CA
GND                      C37              2        Q_CAP_C0805-10UF,16V,10%,X7R,CA
GND                      C38              2        Q_CAP_C0402-2.2UF,6.3V,20%,X6SA
GND                      C39              2        Q_CAP_C0805-10UF,16V,10%,X7R,CA
GND                      C40              2        Q_CAP_C0805-10UF,16V,10%,X7R,CA
GND                      C41              2        Q_CAP_C0402-2.2UF,6.3V,20%,X6SA
GND                      C42              2        Q_CAP_C0805-10UF,16V,10%,X7R,CA
GND                      C43              2        Q_CAP_C0805-10UF,16V,10%,X7R,CA
GND                      C44              2        Q_CAP_C0402-2.2UF,6.3V,20%,X6SA
GND                      C45              2        Q_CAP_C0805-10UF,16V,10%,X7R,CA
GND                      C46              2        Q_CAP_C0805-10UF,16V,10%,X7R,CA
GND                      C47              2        Q_CAP_C0402-2.2UF,6.3V,20%,X6SA
GND                      C48              2        Q_CAP_C0805-10UF,16V,10%,X7R,CA
GND                      C49              2        Q_CAP_C0805-10UF,16V,10%,X7R,CA
GND                      C50              2        Q_CAP_C0402-2.2UF,6.3V,20%,X6SA
GND                      C51              2        Q_CAP_C0805-10UF,16V,10%,X7R,CA
GND                      C52              2        Q_CAP_C0805-10UF,16V,10%,X7R,CA
GND                      C53              2        Q_CAP_C0402-2.2UF,6.3V,20%,X6SA
GND                      C54              2        Q_CAP_C0805-10UF,16V,10%,X7R,CA
GND                      C55              2        Q_CAP_C0805-10UF,16V,10%,X7R,CA
GND                      C56              2        Q_CAP_C0402-2.2UF,6.3V,20%,X6SA
GND                      C57              2        Q_CAP_C0805-10UF,16V,10%,X7R,CA
GND                      C58              2        Q_CAP_C0805-10UF,16V,10%,X7R,CA
GND                      C59              2        Q_CAP_C0402-2.2UF,6.3V,20%,X6SA
GND                      C60              2        Q_CAP_C0805-10UF,16V,10%,X7R,CA
GND                      C61              2        Q_CAP_C0805-10UF,16V,10%,X7R,CA
GND                      C62              2        Q_CAP_C0402-2.2UF,6.3V,20%,X6SA
GND                      C63              2        Q_CAP_C0805-10UF,16V,10%,X7R,CA
GND                      C64              2        Q_CAP_C0805-10UF,16V,10%,X7R,CA
GND                      C65              2        Q_CAP_C0402-2.2UF,6.3V,20%,X6SA
GND                      C66              2        Q_CAP_C0805-10UF,16V,10%,X7R,CA
GND                      C67              2        Q_CAP_C0805-10UF,16V,10%,X7R,CA
GND                      C68              2        Q_CAP_C0402-2.2UF,6.3V,20%,X6SA
GND                      C69              2        Q_CAP_C0805-10UF,16V,10%,X7R,CA
GND                      C70              2        Q_CAP_C0805-10UF,16V,10%,X7R,CA
GND                      C71              2        Q_CAP_C0402-10UF,6.3V,20%,X6S,A
GND                      C72              2        Q_CAP_C0402-2.2UF,6.3V,20%,X6SA
GND                      C73              2        Q_CAP_C0805-10UF,16V,10%,X7R,CA
GND                      C74              2        Q_CAP_C0805-10UF,16V,10%,X7R,CA
GND                      C75              2        Q_CAP_C0402-2.2UF,6.3V,20%,X6SA
GND                      C76              2        Q_CAP_C0805-10UF,16V,10%,X7R,CA
GND                      C77              2        Q_CAP_C0805-10UF,16V,10%,X7R,CA
GND                      C78              2        Q_CAP_C0402-2.2UF,6.3V,20%,X6SA
GND                      C79              2        Q_CAP_C0805-10UF,16V,10%,X7R,CA
GND                      C80              2        Q_CAP_C0805-10UF,16V,10%,X7R,CA
GND                      C81              2        Q_CAP_C0402-2.2UF,6.3V,20%,X6SA
GND                      C82              2        Q_CAP_C0805-10UF,16V,10%,X7R,CA
GND                      C83              2        Q_CAP_C0805-10UF,16V,10%,X7R,CA
GND                      C84              2        Q_CAP_C0402-2.2UF,6.3V,20%,X6SA
GND                      C85              2        Q_CAP_C0805-10UF,16V,10%,X7R,CA
GND                      C86              2        Q_CAP_C0805-10UF,16V,10%,X7R,CA
GND                      C87              2        Q_CAP_C0402-2.2UF,6.3V,20%,X6SA
GND                      C88              2        Q_CAP_C0805-10UF,16V,10%,X7R,CA
GND                      C89              2        Q_CAP_C0805-10UF,16V,10%,X7R,CA
GND                      C90              2        Q_CAP_C0402-2.2UF,6.3V,20%,X6SA
GND                      C91              2        Q_CAP_C0805-10UF,16V,10%,X7R,CA
GND                      C92              2        Q_CAP_C0805-10UF,16V,10%,X7R,CA
GND                      C93              2        Q_CAP_C0402-2.2UF,6.3V,20%,X6SA
GND                      C94              2        Q_CAP_C0805-10UF,16V,10%,X7R,CA
GND                      C95              2        Q_CAP_C0805-10UF,16V,10%,X7R,CA
GND                      C96              2        Q_CAP_C0402-2.2UF,6.3V,20%,X6SA
GND                      C97              2        Q_CAP_C0805-10UF,16V,10%,X7R,CA
GND                      C98              2        Q_CAP_C0805-10UF,16V,10%,X7R,CA
GND                      C101             2        Q_CAP_0805-47UF,4V,20%,X6S,CH6A
GND                      C103             2        Q_CAP_0402-27PF  ,50V ,5% ,EMPA
GND                      C104             2        Q_CAP_0402-27PF  ,50V ,5% ,EMPA
GND                      C108             2        Q_CAP_C0603-10UF,6.3V,20%,X6S,A
GND                      C109             2        Q_CAP_C0402-1UF,25V,10%,X6S,CHA
GND                      C110             2        Q_CAP_0402-0.1UF,25V,10%,X7R,CA
GND                      C111             2        Q_CAP_0402-0.1UF,25V,10%,X7R,CA
GND                      C112             2        Q_CAP_0402-0.1UF,25V,10%,X7R,CA
GND                      C113             2        Q_CAP_0402-15PF,50V,5%,C0G,CH0A
GND                      C114             2        Q_CAP_0402-0.1UF,25V,10%,X7R,CA
GND                      C115             2        Q_CAP_0402-0.1UF,25V,10%,X7R,CA
GND                      C116             2        Q_CAP_0402-0.1UF,25V,10%,X7R,CA
GND                      C117             2        Q_CAP_0402-0.1UF,25V,10%,X7R,CA
GND                      C118             2        Q_CAP_0402-15PF,50V,5%,C0G,CH0A
GND                      C119             2        Q_CAP_0402-0.1UF,25V,10%,X7R,CA
GND                      C120             2        Q_CAP_0402-0.1UF,25V,10%,X7R,CA
GND                      C127             2        Q_CAPP_RDLLF-270UF,16V,20%,OSCA
GND                      C128             2        Q_CAP_0402-0.1UF,25V,10%,X7R,CA
GND                      C129             2        Q_CAPP_SMLF-100UF,16V,20%,POSCA
GND                      C130             2        Q_CAP_0402-0.1UF,25V,10%,X7R,CA
GND                      C131             2        Q_CAP_C0402-1UF,25V,10%,X6S,CHA
GND                      C132             2        Q_CAP_0402-0.1UF,25V,10%,X7R,CA
GND                      C133             2        Q_CAPP_SMLF-100UF,16V,20%,POSCA
GND                      C134             2        Q_CAP_0402-0.1UF,25V,10%,X7R,CA
GND                      C135             2        Q_CAPP_SMLF-100UF,16V,20%,POSCA
GND                      C136             2        Q_CAP_0402-0.1UF,25V,10%,X7R,CA
GND                      C137             2        Q_CAP_C0402-1UF,25V,10%,X6S,CHA
GND                      C138             2        Q_CAP_0402-0.1UF,25V,10%,X7R,CA
GND                      C171             2        Q_CAP_0402-0.1UF,25V,10%,X7R,CA
GND                      C172             2        Q_CAP_C0603-10UF,6.3V,20%,X6S,A
GND                      C173             2        Q_CAP_0402-0.1UF,25V,10%,X7R,CA
GND                      C174             2        Q_CAP_0402-0.1UF,25V,10%,X7R,CA
GND                      C179             2        Q_CAP_C0402-100NF,50V,10%,X7R,A
GND                      C180             2        Q_CAP_0402-0.1UF,25V,10%,X7R,CA
GND                      C184             2        Q_CAP_C0805-10UF,25V,10%,X6S,CA
GND                      C188             2        Q_CAP_0402-0.1UF,25V,10%,X7R,CA
GND                      C204             2        Q_CAP_0402-0.1UF,25V,10%,X7R,CA
GND                      C205             2        Q_CAP_0402-0.1UF,25V,10%,X7R,CA
GND                      C206             2        Q_CAP_0402-0.1UF,25V,10%,X7R,CA
GND                      C207             2        Q_CAP_0402-0.1UF,25V,10%,X7R,CA
GND                      C208             2        Q_CAP_C0603-10UF,6.3V,20%,X6S,A
GND                      C209             2        Q_CAP_C0603-10UF,6.3V,20%,X6S,A
GND                      C210             2        Q_CAP_0402-0.1UF,25V,10%,X7R,CA
GND                      C211             2        Q_CAP_0402-0.1UF,25V,10%,X7R,CA
GND                      C212             2        Q_CAP_0805-47UF,4V,20%,X6S,CH6A
GND                      C213             2        Q_CAP_0805-47UF,4V,20%,X6S,CH6A
GND                      C214             2        Q_CAP_0805-47UF,4V,20%,X6S,CH6A
GND                      C215             2        Q_CAP_0805-47UF,4V,20%,X6S,CH6A
GND                      C216             2        Q_CAP_0805-47UF,4V,20%,X6S,CH6A
GND                      C217             2        Q_CAP_0805-47UF,4V,20%,X6S,CH6A
GND                      C218             2        Q_CAP_0805-47UF,4V,20%,X6S,CH6A
GND                      C219             2        Q_CAP_0805-47UF,4V,20%,X6S,CH6A
GND                      C220             2        Q_CAP_0805-47UF,4V,20%,X6S,CH6A
GND                      C221             2        Q_CAP_C0402-22UF,4V,20%,X6S,CHA
GND                      C222             2        Q_CAP_C0402-22UF,4V,20%,X6S,CHA
GND                      C223             2        Q_CAP_C0402-22UF,4V,20%,X6S,CHA
GND                      C224             2        Q_CAP_C0402-22UF,4V,20%,X6S,CHA
GND                      C225             2        Q_CAP_0805-47UF,4V,20%,X6S,CH6A
GND                      C226             2        Q_CAP_C0402-22UF,4V,20%,X6S,CHA
GND                      C227             2        Q_CAP_C0402-22UF,4V,20%,X6S,CHA
GND                      C228             2        Q_CAP_C0402-22UF,4V,20%,X6S,CHA
GND                      C229             2        Q_CAP_C0402-22UF,4V,20%,X6S,CHA
GND                      C230             2        Q_CAP_0805-47UF,4V,20%,X6S,CH6A
GND                      C231             2        Q_CAP_C0402-22UF,4V,20%,X6S,CHA
GND                      C232             2        Q_CAP_C0402-22UF,4V,20%,X6S,CHA
GND                      C233             2        Q_CAP_C0402-22UF,4V,20%,X6S,CHA
GND                      C234             2        Q_CAP_C0402-22UF,4V,20%,X6S,CHA
GND                      C235             2        Q_CAP_0805-47UF,4V,20%,X6S,CH6A
GND                      C236             2        Q_CAP_C0402-22UF,4V,20%,X6S,CHA
GND                      C237             2        Q_CAP_C0402-22UF,4V,20%,X6S,CHA
GND                      C238             2        Q_CAP_C0402-22UF,4V,20%,X6S,CHA
GND                      C239             2        Q_CAP_C0402-22UF,4V,20%,X6S,CHA
GND                      C240             2        Q_CAP_0805-47UF,4V,20%,X6S,CH6A
GND                      C241             2        Q_CAP_C0402-22UF,4V,20%,X6S,CHA
GND                      C242             2        Q_CAP_C0402-22UF,4V,20%,X6S,CHA
GND                      C243             2        Q_CAP_C0402-22UF,4V,20%,X6S,CHA
GND                      C244             2        Q_CAP_C0402-22UF,4V,20%,X6S,CHA
GND                      C245             2        Q_CAP_0805-47UF,4V,20%,X6S,CH6A
GND                      C246             2        Q_CAP_C0402-22UF,4V,20%,X6S,CHA
GND                      C247             2        Q_CAP_C0402-22UF,4V,20%,X6S,CHA
GND                      C248             2        Q_CAP_C0402-22UF,4V,20%,X6S,CHA
GND                      C249             2        Q_CAP_C0402-22UF,4V,20%,X6S,CHA
GND                      C250             2        Q_CAP_0805-47UF,4V,20%,X6S,CH6A
GND                      C251             2        Q_CAP_C0402-22UF,4V,20%,X6S,CHA
GND                      C252             2        Q_CAP_C0402-22UF,4V,20%,X6S,CHA
GND                      C253             2        Q_CAP_C0402-22UF,4V,20%,X6S,CHA
GND                      C254             2        Q_CAP_C0402-22UF,4V,20%,X6S,CHA
GND                      C255             2        Q_CAP_0805-47UF,4V,20%,X6S,CH6A
GND                      C256             2        Q_CAP_C0402-22UF,4V,20%,X6S,CHA
GND                      C257             2        Q_CAP_C0402-22UF,4V,20%,X6S,CHA
GND                      C258             2        Q_CAP_C0402-22UF,4V,20%,X6S,CHA
GND                      C259             2        Q_CAP_C0402-22UF,4V,20%,X6S,CHA
GND                      C260             2        Q_CAP_0805-47UF,4V,20%,X6S,CH6A
GND                      C261             2        Q_CAP_C0402-22UF,4V,20%,X6S,CHA
GND                      C262             2        Q_CAP_C0402-22UF,4V,20%,X6S,CHA
GND                      C263             2        Q_CAP_C0402-22UF,4V,20%,X6S,CHA
GND                      C264             2        Q_CAP_C0402-22UF,4V,20%,X6S,CHA
GND                      C265             2        Q_CAP_0805-47UF,4V,20%,X6S,CH6A
GND                      C266             2        Q_CAP_C0402-22UF,4V,20%,X6S,CHA
GND                      C267             2        Q_CAP_C0402-22UF,4V,20%,X6S,CHA
GND                      C268             2        Q_CAP_C0402-22UF,4V,20%,X6S,CHA
GND                      C269             2        Q_CAP_C0402-22UF,4V,20%,X6S,CHA
GND                      C270             2        Q_CAP_0805-47UF,4V,20%,X6S,CH6A
GND                      C271             2        Q_CAP_C0402-22UF,4V,20%,X6S,CHA
GND                      C272             2        Q_CAP_C0402-22UF,4V,20%,X6S,CHA
GND                      C273             2        Q_CAP_C0402-22UF,4V,20%,X6S,CHA
GND                      C274             2        Q_CAP_C0402-22UF,4V,20%,X6S,CHA
GND                      C275             2        Q_CAP_C0402-22UF,4V,20%,X6S,CHA
GND                      C276             2        Q_CAP_C0402-22UF,4V,20%,X6S,CHA
GND                      C277             2        Q_CAP_C0402-22UF,4V,20%,X6S,CHA
GND                      C278             2        Q_CAP_C0402-22UF,4V,20%,X6S,CHA
GND                      C279             2        Q_CAP_C0402-22UF,4V,20%,X6S,CHA
GND                      C280             2        Q_CAP_C0402-22UF,4V,20%,X6S,CHA
GND                      C281             2        Q_CAP_C0402-22UF,4V,20%,X6S,CHA
GND                      C282             2        Q_CAP_C0402-22UF,4V,20%,X6S,CHA
GND                      C283             2        Q_CAP_C0402-22UF,4V,20%,X6S,CHA
GND                      C284             2        Q_CAP_C0402-22UF,4V,20%,X6S,CHA
GND                      C285             2        Q_CAP_C0402-22UF,4V,20%,X6S,CHA
GND                      C286             2        Q_CAP_C0402-22UF,4V,20%,X6S,CHA
GND                      C287             2        Q_CAP_C0402-22UF,4V,20%,X6S,CHA
GND                      C288             2        Q_CAP_C0402-22UF,4V,20%,X6S,CHA
GND                      C289             2        Q_CAP_C0402-22UF,4V,20%,X6S,CHA
GND                      C290             2        Q_CAP_C0402-22UF,4V,20%,X6S,CHA
GND                      C291             2        Q_CAP_C0402-22UF,4V,20%,X6S,CHA
GND                      C292             2        Q_CAP_C0402-22UF,4V,20%,X6S,CHA
GND                      C293             2        Q_CAP_C0402-22UF,4V,20%,X6S,CHA
GND                      C294             2        Q_CAP_C0402-22UF,4V,20%,X6S,CHA
GND                      C295             2        Q_CAP_C0402-22UF,4V,20%,X6S,CHA
GND                      C296             2        Q_CAP_C0402-22UF,4V,20%,X6S,CHA
GND                      C297             2        Q_CAP_C0402-22UF,4V,20%,X6S,CHA
GND                      C298             2        Q_CAP_C0402-22UF,4V,20%,X6S,CHA
GND                      C299             2        Q_CAP_C0402-22UF,4V,20%,X6S,CHA
GND                      C300             2        Q_CAP_C0402-22UF,4V,20%,X6S,CHA
GND                      C301             2        Q_CAP_C0402-22UF,4V,20%,X6S,CHA
GND                      C302             2        Q_CAP_C0402-22UF,4V,20%,X6S,CHA
GND                      C303             2        Q_CAP_C0402-22UF,4V,20%,X6S,CHA
GND                      C304             2        Q_CAP_C0402-22UF,4V,20%,X6S,CHA
GND                      C305             2        Q_CAP_C0402-22UF,4V,20%,X6S,CHA
GND                      C306             2        Q_CAP_C0402-22UF,4V,20%,X6S,CHA
GND                      C307             2        Q_CAP_C0402-22UF,4V,20%,X6S,CHA
GND                      C308             2        Q_CAP_C0402-22UF,4V,20%,X6S,CHA
GND                      C309             2        Q_CAP_C0402-22UF,4V,20%,X6S,CHA
GND                      C310             2        Q_CAP_C0402-22UF,4V,20%,X6S,CHA
GND                      C311             2        Q_CAP_C0805-100UF,4V,20%,X6S,CA
GND                      C312             2        Q_CAP_C0805-100UF,4V,20%,X6S,CA
GND                      C313             2        Q_CAP_C0805-100UF,4V,20%,X6S,CA
GND                      C314             2        Q_CAP_C0805-100UF,4V,20%,X6S,CA
GND                      C315             2        Q_CAP_C0805-100UF,4V,20%,X6S,CA
GND                      C316             2        Q_CAP_C0805-100UF,4V,20%,X6S,CA
GND                      C317             2        Q_CAP_C0805-100UF,4V,20%,X6S,CA
GND                      C318             2        Q_CAP_C0805-100UF,4V,20%,X6S,CA
GND                      C319             2        Q_CAP_C0805-22UF,16V,20%,X6S,CA
GND                      C320             2        Q_CAP_C0805-100UF,4V,20%,X6S,CA
GND                      C321             2        Q_CAP_C0805-100UF,4V,20%,X6S,CA
GND                      C322             2        Q_CAP_C0805-100UF,4V,20%,X6S,CA
GND                      C323             2        Q_CAP_C0805-100UF,4V,20%,X6S,CA
GND                      C324             2        Q_CAP_C0805-100UF,4V,20%,X6S,CA
GND                      C325             2        Q_CAP_C0805-100UF,4V,20%,X6S,CA
GND                      C326             2        Q_CAP_C0805-100UF,4V,20%,X6S,CA
GND                      C327             2        Q_CAP_C0805-100UF,4V,20%,X6S,CA
GND                      C328             2        Q_CAP_C0805-100UF,4V,20%,X6S,CA
GND                      C329             2        Q_CAP_C0805-100UF,4V,20%,X6S,CA
GND                      C330             2        Q_CAP_C0805-100UF,4V,20%,X6S,CA
GND                      C331             2        Q_CAP_C0805-22UF,16V,20%,X6S,CA
GND                      C332             2        Q_CAP_C0805-100UF,4V,20%,X6S,CA
GND                      C333             2        Q_CAP_C0805-100UF,4V,20%,X6S,CA
GND                      C335             2        Q_CAP_C0805-100UF,4V,20%,X6S,CA
GND                      C336             2        Q_CAP_C0805-100UF,4V,20%,X6S,CA
GND                      C337             2        Q_CAP_C0603-47UF,2.5V,20%,X6S,A
GND                      C338             2        Q_CAP_C0805-100UF,4V,20%,X6S,CA
GND                      C339             2        Q_CAP_C0805-100UF,4V,20%,X6S,CA
GND                      C340             2        Q_CAP_C0603-47UF,2.5V,20%,X6S,A
GND                      C341             2        Q_CAP_C0805-100UF,4V,20%,X6S,CA
GND                      C342             2        Q_CAP_C0805-100UF,4V,20%,X6S,CA
GND                      C343             2        Q_CAP_C0805-100UF,4V,20%,X6S,CA
GND                      C344             2        Q_CAP_C0805-100UF,4V,20%,X6S,CA
GND                      C345             2        Q_CAP_C0805-100UF,4V,20%,X6S,CA
GND                      C346             2        Q_CAP_C0805-100UF,4V,20%,X6S,CA
GND                      C347             2        Q_CAP_C0805-100UF,4V,20%,X6S,CA
GND                      C348             2        Q_CAP_C0805-100UF,4V,20%,X6S,CA
GND                      C349             2        Q_CAP_C0805-100UF,4V,20%,X6S,CA
GND                      C350             2        Q_CAP_C0805-100UF,4V,20%,X6S,CA
GND                      C351             2        Q_CAP_C0805-100UF,4V,20%,X6S,CA
GND                      C352             2        Q_CAP_C0805-100UF,4V,20%,X6S,CA
GND                      C353             2        Q_CAP_C0805-100UF,4V,20%,X6S,CA
GND                      C354             2        Q_CAP_C0805-100UF,4V,20%,X6S,CA
GND                      C355             2        Q_CAP_C0805-100UF,4V,20%,X6S,CA
GND                      C356             2        Q_CAP_C0805-100UF,4V,20%,X6S,CA
GND                      C357             2        Q_CAP_C0805-100UF,4V,20%,X6S,CA
GND                      C358             2        Q_CAP_C0805-100UF,4V,20%,X6S,CA
GND                      C359             2        Q_CAP_C0805-100UF,4V,20%,X6S,CA
GND                      C360             2        Q_CAP_C0805-100UF,4V,20%,X6S,CA
GND                      C361             2        Q_CAP_C0805-100UF,4V,20%,X6S,CA
GND                      C362             2        Q_CAP_C0805-100UF,4V,20%,X6S,CA
GND                      C363             2        Q_CAP_C0805-100UF,4V,20%,X6S,CA
GND                      C364             2        Q_CAP_C0805-100UF,4V,20%,X6S,CA
GND                      C365             2        Q_CAP_C0805-100UF,4V,20%,X6S,CA
GND                      C366             2        Q_CAP_C0805-100UF,4V,20%,X6S,CA
GND                      C367             2        Q_CAP_C0805-100UF,4V,20%,X6S,CA
GND                      C368             2        Q_CAP_C0805-100UF,4V,20%,X6S,CA
GND                      C369             2        Q_CAP_C0805-100UF,4V,20%,X6S,CA
GND                      C370             2        Q_CAP_C0805-100UF,4V,20%,X6S,CA
GND                      C371             2        Q_CAP_C0805-100UF,4V,20%,X6S,CA
GND                      C372             2        Q_CAP_C0805-100UF,4V,20%,X6S,CA
GND                      C373             2        Q_CAP_C0805-100UF,4V,20%,X6S,CA
GND                      C374             2        Q_CAP_C0805-100UF,4V,20%,X6S,CA
GND                      C376             2        Q_CAP_C0805-100UF,4V,20%,X6S,CA
GND                      C377             2        Q_CAP_C0805-100UF,4V,20%,X6S,CA
GND                      C379             2        Q_CAP_C0805-100UF,4V,20%,X6S,CA
GND                      C380             2        Q_CAP_C0805-100UF,4V,20%,X6S,CA
GND                      C381             2        Q_CAP_C0603-47UF,2.5V,20%,X6S,A
GND                      C382             2        Q_CAP_C0805-100UF,4V,20%,X6S,CA
GND                      C383             2        Q_CAP_C0805-100UF,4V,20%,X6S,CA
GND                      C384             2        Q_CAP_C0603-47UF,2.5V,20%,X6S,A
GND                      C385             2        Q_CAP_C0805-100UF,4V,20%,X6S,CA
GND                      C386             2        Q_CAP_C0805-100UF,4V,20%,X6S,CA
GND                      C387             2        Q_CAP_C0805-100UF,4V,20%,X6S,CA
GND                      C388             2        Q_CAP_C0805-100UF,4V,20%,X6S,CA
GND                      C389             2        Q_CAP_C0805-100UF,4V,20%,X6S,CA
GND                      C390             2        Q_CAP_C0805-100UF,4V,20%,X6S,CA
GND                      C391             2        Q_CAP_C0805-100UF,4V,20%,X6S,CA
GND                      C392             2        Q_CAP_C0805-100UF,4V,20%,X6S,CA
GND                      C393             2        Q_CAP_C0805-100UF,4V,20%,X6S,CA
GND                      C394             2        Q_CAP_C0805-100UF,4V,20%,X6S,CA
GND                      C395             2        Q_CAP_C0805-100UF,4V,20%,X6S,CA
GND                      C396             2        Q_CAP_C0805-100UF,4V,20%,X6S,CA
GND                      C397             2        Q_CAP_C0805-100UF,4V,20%,X6S,CA
GND                      C398             2        Q_CAP_C0805-100UF,4V,20%,X6S,CA
GND                      C399             2        Q_CAP_C0402-22UF,4V,20%,X6S,CHA
GND                      C400             2        Q_CAP_C0402-22UF,4V,20%,X6S,CHA
GND                      C401             2        Q_CAP_C0402-22UF,4V,20%,X6S,CHA
GND                      C402             2        Q_CAP_C0402-22UF,4V,20%,X6S,CHA
GND                      C403             2        Q_CAP_C0402-22UF,4V,20%,X6S,CHA
GND                      C404             2        Q_CAP_C0402-22UF,4V,20%,X6S,CHA
GND                      C405             2        Q_CAP_C0402-22UF,4V,20%,X6S,CHA
GND                      C406             2        Q_CAP_C0402-22UF,4V,20%,X6S,CHA
GND                      C407             2        Q_CAP_C0402-22UF,4V,20%,X6S,CHA
GND                      C408             2        Q_CAP_C0402-22UF,4V,20%,X6S,CHA
GND                      C409             2        Q_CAP_C0402-22UF,4V,20%,X6S,CHA
GND                      C410             2        Q_CAP_C0402-22UF,4V,20%,X6S,CHA
GND                      C411             2        Q_CAP_C0402-22UF,4V,20%,X6S,CHA
GND                      C412             2        Q_CAP_C0402-22UF,4V,20%,X6S,CHA
GND                      C413             2        Q_CAP_C0402-22UF,4V,20%,X6S,CHA
GND                      C414             2        Q_CAP_C0402-22UF,4V,20%,X6S,CHA
GND                      C415             2        Q_CAP_C0402-22UF,4V,20%,X6S,CHA
GND                      C416             2        Q_CAP_C0402-22UF,4V,20%,X6S,CHA
GND                      C417             2        Q_CAP_C0402-22UF,4V,20%,X6S,CHA
GND                      C418             2        Q_CAP_C0402-22UF,4V,20%,X6S,CHA
GND                      C419             2        Q_CAP_C0402-22UF,4V,20%,X6S,CHA
GND                      C420             2        Q_CAP_C0402-22UF,4V,20%,X6S,CHA
GND                      C421             2        Q_CAP_C0402-22UF,4V,20%,X6S,CHA
GND                      C422             2        Q_CAP_C0402-22UF,4V,20%,X6S,CHA
GND                      C423             2        Q_CAP_C0402-22UF,4V,20%,X6S,CHA
GND                      C424             2        Q_CAP_C0402-22UF,4V,20%,X6S,CHA
GND                      C425             2        Q_CAP_C0402-22UF,4V,20%,X6S,CHA
GND                      C426             2        Q_CAP_C0402-22UF,4V,20%,X6S,CHA
GND                      C427             2        Q_CAP_C0402-22UF,4V,20%,X6S,CHA
GND                      C428             2        Q_CAP_C0402-22UF,4V,20%,X6S,CHA
GND                      C429             2        Q_CAP_C0402-22UF,4V,20%,X6S,CHA
GND                      C430             2        Q_CAP_C0402-22UF,4V,20%,X6S,CHA
GND                      C431             2        Q_CAP_C0402-22UF,4V,20%,X6S,CHA
GND                      C432             2        Q_CAP_C0402-22UF,4V,20%,X6S,CHA
GND                      C433             2        Q_CAP_C0402-22UF,4V,20%,X6S,CHA
GND                      C434             2        Q_CAP_C0402-22UF,4V,20%,X6S,CHA
GND                      C435             2        Q_CAP_C0402-22UF,4V,20%,X6S,CHA
GND                      C436             2        Q_CAP_C0402-22UF,4V,20%,X6S,CHA
GND                      C437             2        Q_CAP_C0402-22UF,4V,20%,X6S,CHA
GND                      C438             2        Q_CAP_C0402-22UF,4V,20%,X6S,CHA
GND                      C439             2        Q_CAP_C0402-22UF,4V,20%,X6S,CHA
GND                      C440             2        Q_CAP_C0402-22UF,4V,20%,X6S,CHA
GND                      C441             2        Q_CAP_C0402-22UF,4V,20%,X6S,CHA
GND                      C442             2        Q_CAP_C0402-22UF,4V,20%,X6S,CHA
GND                      C443             2        Q_CAP_C0402-22UF,4V,20%,X6S,CHA
GND                      C444             2        Q_CAP_C0402-22UF,4V,20%,X6S,CHA
GND                      C445             2        Q_CAP_C0402-22UF,4V,20%,X6S,CHA
GND                      C446             2        Q_CAP_C0402-22UF,4V,20%,X6S,CHA
GND                      C447             2        Q_CAP_C0805-100UF,4V,20%,X6S,CA
GND                      C448             2        Q_CAP_C0805-100UF,4V,20%,X6S,CA
GND                      C449             2        Q_CAP_C0805-100UF,4V,20%,X6S,CA
GND                      C450             2        Q_CAP_C0805-100UF,4V,20%,X6S,CA
GND                      C451             2        Q_CAP_C0805-100UF,4V,20%,X6S,CA
GND                      C452             2        Q_CAP_C0805-100UF,4V,20%,X6S,CA
GND                      C453             2        Q_CAP_C0805-100UF,4V,20%,X6S,CA
GND                      C454             2        Q_CAP_C0805-100UF,4V,20%,X6S,CA
GND                      C455             2        Q_CAP_C0805-100UF,4V,20%,X6S,CA
GND                      C456             2        Q_CAP_C0805-100UF,4V,20%,X6S,CA
GND                      C457             2        Q_CAP_C0805-100UF,4V,20%,X6S,CA
GND                      C458             2        Q_CAP_C0805-100UF,4V,20%,X6S,CA
GND                      C459             2        Q_CAP_C0805-100UF,4V,20%,X6S,CA
GND                      C460             2        Q_CAP_C0805-100UF,4V,20%,X6S,CA
GND                      C461             2        Q_CAP_C0805-100UF,4V,20%,X6S,CA
GND                      C462             2        Q_CAP_C0805-100UF,4V,20%,X6S,CA
GND                      C463             2        Q_CAP_C0805-100UF,4V,20%,X6S,CA
GND                      C464             2        Q_CAP_C0805-100UF,4V,20%,X6S,CA
GND                      C465             2        Q_CAP_C0603-47UF,2.5V,20%,X6S,A
GND                      C466             2        Q_CAP_C0805-100UF,4V,20%,X6S,CA
GND                      C467             2        Q_CAP_C0805-100UF,4V,20%,X6S,CA
GND                      C468             2        Q_CAP_C0805-100UF,4V,20%,X6S,CA
GND                      C470             2        Q_CAP_C0805-100UF,4V,20%,X6S,CA
GND                      C471             2        Q_CAP_C0603-47UF,2.5V,20%,X6S,A
GND                      C472             2        Q_CAP_C0603-47UF,2.5V,20%,X6S,A
GND                      C473             2        Q_CAP_C0805-100UF,4V,20%,X6S,CA
GND                      C474             2        Q_CAP_C0603-47UF,2.5V,20%,X6S,A
GND                      C475             2        Q_CAP_C0603-47UF,2.5V,20%,X6S,A
GND                      C476             2        Q_CAP_C0805-100UF,4V,20%,X6S,CA
GND                      C477             2        Q_CAP_C0805-100UF,4V,20%,X6S,CA
GND                      C478             2        Q_CAP_C0805-100UF,4V,20%,X6S,CA
GND                      C479             2        Q_CAP_C0805-100UF,4V,20%,X6S,CA
GND                      C480             2        Q_CAP_C0603-47UF,2.5V,20%,X6S,A
GND                      C481             2        Q_CAP_C0805-100UF,4V,20%,X6S,CA
GND                      C482             2        Q_CAP_C0805-100UF,4V,20%,X6S,CA
GND                      C483             2        Q_CAP_C0603-47UF,2.5V,20%,X6S,A
GND                      C484             2        Q_CAP_C0805-100UF,4V,20%,X6S,CA
GND                      C485             2        Q_CAP_C0805-100UF,4V,20%,X6S,CA
GND                      C486             2        Q_CAP_C0805-100UF,4V,20%,X6S,CA
GND                      C487             2        Q_CAP_C0805-100UF,4V,20%,X6S,CA
GND                      C488             2        Q_CAP_C0603-47UF,2.5V,20%,X6S,A
GND                      C489             2        Q_CAP_C0603-47UF,2.5V,20%,X6S,A
GND                      C490             2        Q_CAP_C0402-22UF,4V,20%,X6S,CHA
GND                      C491             2        Q_CAP_C0805-100UF,4V,20%,X6S,CA
GND                      C492             2        Q_CAP_C0805-100UF,4V,20%,X6S,CA
GND                      C493             2        Q_CAP_C0805-100UF,4V,20%,X6S,CA
GND                      C494             2        Q_CAP_C0805-100UF,4V,20%,X6S,CA
GND                      C495             2        Q_CAP_C0805-100UF,4V,20%,X6S,CA
GND                      C496             2        Q_CAP_C0805-100UF,4V,20%,X6S,CA
GND                      C497             2        Q_CAP_C0805-100UF,4V,20%,X6S,CA
GND                      C498             2        Q_CAP_C0805-100UF,4V,20%,X6S,CA
GND                      C499             2        Q_CAP_C0805-100UF,4V,20%,X6S,CA
GND                      C500             2        Q_CAP_C0805-100UF,4V,20%,X6S,CA
GND                      C501             2        Q_CAP_C0805-100UF,4V,20%,X6S,CA
GND                      C502             2        Q_CAP_C0805-100UF,4V,20%,X6S,CA
GND                      C503             2        Q_CAP_C0805-100UF,4V,20%,X6S,CA
GND                      C504             2        Q_CAP_C0805-100UF,4V,20%,X6S,CA
GND                      C505             2        Q_CAP_C0805-100UF,4V,20%,X6S,CA
GND                      C506             2        Q_CAP_C0805-100UF,4V,20%,X6S,CA
GND                      C507             2        Q_CAP_C0805-100UF,4V,20%,X6S,CA
GND                      C508             2        Q_CAP_C0805-100UF,4V,20%,X6S,CA
GND                      C509             2        Q_CAP_C0603-47UF,2.5V,20%,X6S,A
GND                      C510             2        Q_CAP_C0805-100UF,4V,20%,X6S,CA
GND                      C511             2        Q_CAP_C0805-100UF,4V,20%,X6S,CA
GND                      C512             2        Q_CAP_C0805-100UF,4V,20%,X6S,CA
GND                      C513             2        Q_CAP_C0805-22UF,16V,20%,X6S,CA
GND                      C514             2        Q_CAP_C0805-100UF,4V,20%,X6S,CA
GND                      C515             2        Q_CAP_C0603-47UF,2.5V,20%,X6S,A
GND                      C516             2        Q_CAP_C0603-47UF,2.5V,20%,X6S,A
GND                      C517             2        Q_CAP_C0805-100UF,4V,20%,X6S,CA
GND                      C518             2        Q_CAP_C0603-47UF,2.5V,20%,X6S,A
GND                      C519             2        Q_CAP_C0603-47UF,2.5V,20%,X6S,A
GND                      C520             2        Q_CAP_C0805-100UF,4V,20%,X6S,CA
GND                      C521             2        Q_CAP_C0805-100UF,4V,20%,X6S,CA
GND                      C522             2        Q_CAP_C0805-100UF,4V,20%,X6S,CA
GND                      C523             2        Q_CAP_C0805-100UF,4V,20%,X6S,CA
GND                      C524             2        Q_CAP_C0603-47UF,2.5V,20%,X6S,A
GND                      C525             2        Q_CAP_C0805-100UF,4V,20%,X6S,CA
GND                      C526             2        Q_CAP_C0805-100UF,4V,20%,X6S,CA
GND                      C527             2        Q_CAP_C0603-47UF,2.5V,20%,X6S,A
GND                      C528             2        Q_CAP_C0805-100UF,4V,20%,X6S,CA
GND                      C529             2        Q_CAP_C0805-100UF,4V,20%,X6S,CA
GND                      C530             2        Q_CAP_C0805-100UF,4V,20%,X6S,CA
GND                      C531             2        Q_CAP_C0805-100UF,4V,20%,X6S,CA
GND                      C532             2        Q_CAP_C0603-47UF,2.5V,20%,X6S,A
GND                      C533             2        Q_CAP_C0603-47UF,2.5V,20%,X6S,A
GND                      C534             2        Q_CAP_C0402-22UF,4V,20%,X6S,CHA
GND                      C535             2        Q_CAP_C0805-22UF,16V,20%,X6S,CA
GND                      C536             2        Q_CAP_0402-0.1UF,25V,10%,X7R,CA
GND                      C537             2        Q_CAP_0402-0.1UF,25V,10%,X7R,CA
GND                      C538             2        Q_CAP_0402-0.1UF,25V,10%,X7R,CA
GND                      C539             2        Q_CAP_0402-0.1UF,25V,10%,X7R,CA
GND                      C540             2        Q_CAP_0402-0.1UF,25V,10%,X7R,CA
GND                      C541             2        Q_CAP_C0402-1UF,25V,10%,X6S,CHA
GND                      C542             2        Q_CAP_C0402-1UF,25V,10%,X6S,CHA
GND                      C543             2        Q_CAP_0402-0.1UF,25V,10%,X7R,CA
GND                      C544             2        Q_CAP_0402-0.1UF,25V,10%,X7R,CA
GND                      C545             2        Q_CAP_C0402-1UF,25V,10%,X6S,CHA
GND                      C546             2        Q_CAP_C0402-1UF,25V,10%,X6S,CHA
GND                      C547             2        Q_CAP_C0402-1UF,25V,10%,X6S,CHA
GND                      C548             2        Q_CAP_0402-0.1UF,25V,10%,X7R,CA
GND                      C549             2        Q_CAP_0402-0.1UF,25V,10%,X7R,CA
GND                      C550             2        Q_CAP_C0402-1UF,25V,10%,X6S,CHA
GND                      C551             2        Q_CAP_C0402-1UF,25V,10%,X6S,CHA
GND                      C552             2        Q_CAP_0402-0.1UF,25V,10%,X7R,CA
GND                      C553             2        Q_CAP_0402-0.1UF,25V,10%,X7R,CA
GND                      C554             2        Q_CAP_0402-0.1UF,25V,10%,X7R,CA
GND                      C559             2        Q_CAP_0402-0.1UF,25V,10%,X7R,CA
GND                      C560             2        Q_CAP_0402-0.1UF,25V,10%,X7R,CA
GND                      C561             2        Q_CAP_0402-0.1UF,25V,10%,X7R,CA
GND                      C562             2        Q_CAP_0402-0.1UF,25V,10%,X7R,CA
GND                      C563             2        Q_CAP_C0805-10UF,25V,10%,X6S,CA
GND                      C564             2        Q_CAP_0402-0.1UF,25V,10%,X7R,CA
GND                      C567             2        Q_CAP_0402-0.1UF,25V,10%,X7R,CA
GND                      C568             2        Q_CAP_0402-0.1UF,25V,10%,X7R,CA
GND                      C569             2        Q_CAP_0402-0.1UF,25V,10%,X7R,CA
GND                      C570             2        Q_CAP_0402-0.1UF,25V,10%,X7R,CA
GND                      C575             2        Q_CAP_C0402-100NF,50V,10%,X7R,A
GND                      C578             2        Q_CAP_0402-0.1UF,25V,10%,X7R,CA
GND                      C579             2        Q_CAP_0402-0.1UF,25V,10%,X7R,CA
GND                      C580             2        Q_CAP_0402-0.1UF,25V,10%,X7R,CA
GND                      C581             2        Q_CAP_0402-0.1UF,25V,10%,X7R,CA
GND                      C582             2        Q_CAP_C0402-100NF,50V,10%,X7R,A
GND                      C583             2        Q_CAP_C0402-1UF,16V,10%,X6S,CHA
GND                      C586             2        Q_CAP_0402-0.1UF,25V,10%,X7R,CA
GND                      C587             2        Q_CAP_C0805-10UF,25V,10%,X6S,CA
GND                      C588             2        Q_CAP_C0402-3900PF,50V,10%,X7RA
GND                      C589             2        Q_CAP_C0402-1UF,16V,10%,X6S,CHA
GND                      C590             2        Q_CAP_C0402-22UF,4V,20%,X6S,CHA
GND                      C591             2        Q_CAP_0402-3300PF,50V,10%,X7R,A
GND                      C592             2        Q_CAP_0402-0.1UF,25V,10%,X7R,CA
GND                      C593             2        Q_CAP_0402-0.1UF,25V,10%,X7R,CA
GND                      C605             2        Q_CAP_C0402-1UF,25V,10%,X6S,CHA
GND                      C606             2        Q_CAP_C0402-1UF,25V,10%,X6S,CHA
GND                      C607             2        Q_CAP_0402-0.1UF,25V,10%,X7R,CA
GND                      C608             2        Q_CAP_0402-0.1UF,25V,10%,X7R,CA
GND                      C609             2        Q_CAP_0402-0.1UF,25V,10%,X7R,CA
GND                      C610             2        Q_CAP_C0402-1UF,25V,10%,X6S,CHA
GND                      C611             2        Q_CAP_C0402-1UF,25V,10%,X6S,CHA
GND                      C613             2        Q_CAP_C0402-1UF,25V,10%,EMPTY,A
GND                      C614             2        Q_CAP_C0402-1UF,25V,10%,EMPTY,A
GND                      C615             2        Q_CAP_C0402-1UF,25V,10%,EMPTY,A
GND                      C616             2        Q_CAP_C0402-1UF,25V,10%,EMPTY,A
GND                      C621             2        Q_CAP_C0402-1UF,25V,10%,EMPTY,A
GND                      C622             2        Q_CAP_C0402-1UF,25V,10%,EMPTY,A
GND                      C623             2        Q_CAP_C0402-1UF,25V,10%,EMPTY,A
GND                      C624             2        Q_CAP_C0402-1UF,25V,10%,EMPTY,A
GND                      C629             2        Q_CAP_0402-0.1UF,25V,10%,X7R,CA
GND                      C630             2        Q_CAP_0402-0.1UF,25V,10%,X7R,CA
GND                      C631             2        Q_CAP_0402-0.1UF,25V,10%,X7R,CA
GND                      C632             2        Q_CAP_C0805-10UF,25V,10%,X6S,CA
GND                      C633             2        Q_CAP_C0805-22UF,25V,20%,X5R,CA
GND                      C638             2        Q_CAP_0402-0.1UF,25V,10%,X7R,CA
GND                      C639             2        Q_CAP_0402-0.1UF,25V,10%,X7R,CA
GND                      C640             2        Q_CAP_0402-0.1UF,25V,10%,X7R,CA
GND                      C641             2        Q_CAP_0402-0.1UF,25V,10%,X7R,CA
GND                      C966             2        Q_CAP_C0402-22UF,4V,20%,X6S,CHA
GND                      C967             2        Q_CAP_C0402-22UF,4V,20%,X6S,CHA
GND                      C968             2        Q_CAP_C0402-22UF,4V,20%,X6S,CHA
GND                      C969             2        Q_CAP_C0402-22UF,4V,20%,X6S,CHA
GND                      C970             2        Q_CAP_C0402-22UF,4V,20%,X6S,CHA
GND                      C971             2        Q_CAP_C0402-22UF,4V,20%,X6S,CHA
GND                      C972             2        Q_CAP_C0402-22UF,4V,20%,X6S,CHA
GND                      C973             2        Q_CAP_C0402-22UF,4V,20%,X6S,CHA
GND                      C974             2        Q_CAP_C0402-22UF,4V,20%,X6S,CHA
GND                      C975             2        Q_CAP_C0402-22UF,4V,20%,X6S,CHA
GND                      C976             2        Q_CAP_C0402-22UF,4V,20%,X6S,CHA
GND                      C977             2        Q_CAP_C0402-22UF,4V,20%,X6S,CHA
GND                      C978             2        Q_CAP_C0402-22UF,4V,20%,X6S,CHA
GND                      C979             2        Q_CAP_C0402-22UF,4V,20%,X6S,CHA
GND                      C980             2        Q_CAP_C0402-22UF,4V,20%,X6S,CHA
GND                      C981             2        Q_CAP_C0402-22UF,4V,20%,X6S,CHA
GND                      C982             2        Q_CAP_C0402-22UF,4V,20%,X6S,CHA
GND                      C983             2        Q_CAP_C0402-22UF,4V,20%,X6S,CHA
GND                      C984             2        Q_CAP_C0402-22UF,4V,20%,X6S,CHA
GND                      C985             2        Q_CAP_C0402-22UF,4V,20%,X6S,CHA
GND                      C986             2        Q_CAP_C0402-22UF,4V,20%,X6S,CHA
GND                      C987             2        Q_CAP_C0402-22UF,4V,20%,X6S,CHA
GND                      C988             2        Q_CAP_C0402-22UF,4V,20%,X6S,CHA
GND                      C989             2        Q_CAP_C0402-22UF,4V,20%,X6S,CHA
GND                      C990             2        Q_CAP_C0402-22UF,4V,20%,X6S,CHA
GND                      C991             2        Q_CAP_C0402-22UF,4V,20%,X6S,CHA
GND                      C992             2        Q_CAP_C0402-22UF,4V,20%,X6S,CHA
GND                      C993             2        Q_CAP_C0402-22UF,4V,20%,X6S,CHA
GND                      C994             2        Q_CAP_C0402-22UF,4V,20%,X6S,CHA
GND                      C995             2        Q_CAP_C0402-22UF,4V,20%,X6S,CHA
GND                      C996             2        Q_CAP_C0402-22UF,4V,20%,X6S,CHA
GND                      C997             2        Q_CAP_C0402-22UF,4V,20%,X6S,CHA
GND                      C998             2        Q_CAP_C0402-22UF,4V,20%,X6S,CHA
GND                      C999             2        Q_CAP_C0402-22UF,4V,20%,X6S,CHA
GND                      C1000            2        Q_CAP_C0402-22UF,4V,20%,X6S,CHA
GND                      C1001            2        Q_CAP_C0402-22UF,4V,20%,X6S,CHA
GND                      C1002            2        Q_CAP_C0402-22UF,4V,20%,X6S,CHA
GND                      C1003            2        Q_CAP_C0402-22UF,4V,20%,X6S,CHA
GND                      C1004            2        Q_CAP_C0402-22UF,4V,20%,X6S,CHA
GND                      C1005            2        Q_CAP_C0402-22UF,4V,20%,X6S,CHA
GND                      C1006            2        Q_CAP_C0402-22UF,4V,20%,X6S,CHA
GND                      C1007            2        Q_CAP_C0402-22UF,4V,20%,X6S,CHA
GND                      C1008            2        Q_CAP_C0402-22UF,4V,20%,X6S,CHA
GND                      C1009            2        Q_CAP_C0402-22UF,4V,20%,X6S,CHA
GND                      C1010            2        Q_CAP_C0402-22UF,4V,20%,X6S,CHA
GND                      C1011            2        Q_CAP_C0402-22UF,4V,20%,X6S,CHA
GND                      C1012            2        Q_CAP_C0402-22UF,4V,20%,X6S,CHA
GND                      C1013            2        Q_CAP_C0402-22UF,4V,20%,X6S,CHA
GND                      C1014            2        Q_CAP_C0402-22UF,4V,20%,X6S,CHA
GND                      C1015            2        Q_CAP_C0402-22UF,4V,20%,X6S,CHA
GND                      C1016            2        Q_CAP_C0402-22UF,4V,20%,X6S,CHA
GND                      C1017            2        Q_CAP_C0402-22UF,4V,20%,X6S,CHA
GND                      C1018            2        Q_CAP_C0402-22UF,4V,20%,X6S,CHA
GND                      C1019            2        Q_CAP_C0402-22UF,4V,20%,X6S,CHA
GND                      C1020            2        Q_CAP_C0402-22UF,4V,20%,X6S,CHA
GND                      C1021            2        Q_CAP_C0402-22UF,4V,20%,X6S,CHA
GND                      C1022            2        Q_CAP_C0402-22UF,4V,20%,X6S,CHA
GND                      C1023            2        Q_CAP_C0402-22UF,4V,20%,X6S,CHA
GND                      C1024            2        Q_CAP_C0402-22UF,4V,20%,X6S,CHA
GND                      C1025            2        Q_CAP_C0402-22UF,4V,20%,X6S,CHA
GND                      C1026            2        Q_CAP_C0402-22UF,4V,20%,X6S,CHA
GND                      C1027            2        Q_CAP_C0402-22UF,4V,20%,X6S,CHA
GND                      C1028            2        Q_CAP_C0402-22UF,4V,20%,X6S,CHA
GND                      C1029            2        Q_CAP_C0402-22UF,4V,20%,X6S,CHA
GND                      C1030            2        Q_CAP_C0402-22UF,4V,20%,X6S,CHA
GND                      C1031            2        Q_CAP_C0402-22UF,4V,20%,X6S,CHA
GND                      C1032            2        Q_CAP_C0402-22UF,4V,20%,X6S,CHA
GND                      C1033            2        Q_CAP_C0402-22UF,4V,20%,X6S,CHA
GND                      C1034            2        Q_CAP_C0402-22UF,4V,20%,X6S,CHA
GND                      C1035            2        Q_CAP_C0402-22UF,4V,20%,X6S,CHA
GND                      C1036            2        Q_CAP_C0402-22UF,4V,20%,X6S,CHA
GND                      C1037            2        Q_CAP_C0402-22UF,4V,20%,X6S,CHA
GND                      C1038            2        Q_CAP_C0402-22UF,4V,20%,X6S,CHA
GND                      C1039            2        Q_CAP_C0402-22UF,4V,20%,X6S,CHA
GND                      C1040            2        Q_CAP_C0402-22UF,4V,20%,X6S,CHA
GND                      C1041            2        Q_CAP_C0402-22UF,4V,20%,X6S,CHA
GND                      C1042            2        Q_CAP_C0402-100NF,50V,10%,X7R,A
GND                      C1043            2        Q_CAP_C0402-22UF,4V,20%,X6S,CHA
GND                      C1044            2        Q_CAP_C0402-22UF,4V,20%,X6S,CHA
GND                      C1045            2        Q_CAP_C0402-22UF,4V,20%,X6S,CHA
GND                      C1046            2        Q_CAP_C0805-22UF,16V,20%,X6S,CA
GND                      C1047            2        Q_CAP_C0805-22UF,16V,20%,X6S,CA
GND                      C1048            2        Q_CAP_0402-0.1UF,25V,10%,X7R,CA
GND                      C1049            2        Q_CAP_0402-0.1UF,25V,10%,X7R,CA
GND                      C1050            2        Q_CAP_0402-0.1UF,25V,10%,X7R,CA
GND                      C1051            2        Q_CAP_0402-0.1UF,25V,10%,X7R,CA
GND                      C1052            2        Q_CAP_0402-0.1UF,25V,10%,X7R,CA
GND                      C1053            2        Q_CAP_C0805-22UF,16V,20%,X6S,CA
GND                      C1054            2        Q_CAP_C0805-22UF,16V,20%,X6S,CA
GND                      C1055            2        Q_CAP_C0805-22UF,16V,20%,X6S,CA
GND                      C1056            2        Q_CAP_0402-0.1UF,25V,10%,X7R,CA
GND                      C1057            2        Q_CAP_0402-0.1UF,25V,10%,X7R,CA
GND                      C1058            2        Q_CAP_0402-0.1UF,25V,10%,X7R,CA
GND                      C1059            2        Q_CAP_0402-0.1UF,25V,10%,X7R,CA
GND                      C1060            2        Q_CAP_0402-0.1UF,25V,10%,X7R,CA
GND                      C1061            2        Q_CAP_C0805-22UF,16V,20%,X6S,CA
GND                      C1063            2        Q_CAP_C0805-22UF,16V,20%,X6S,CA
GND                      C1064            2        Q_CAP_0402-0.1UF,25V,10%,X7R,CA
GND                      C1065            2        Q_CAP_0402-0.1UF,25V,10%,X7R,CA
GND                      C1066            2        Q_CAP_0402-0.1UF,25V,10%,X7R,CA
GND                      C1067            2        Q_CAP_0402-0.1UF,25V,10%,X7R,CA
GND                      C1068            2        Q_CAP_0402-0.1UF,25V,10%,X7R,CA
GND                      C1069            2        Q_CAP_C0805-22UF,16V,20%,X6S,CA
GND                      C1078            2        Q_CAP_C0603-22UF,6.3V,20%,X6S,A
GND                      C1080            2        Q_CAP_C0603-22UF,6.3V,20%,X6S,A
GND                      C1082            2        Q_CAP_C0603-22UF,6.3V,20%,X6S,A
GND                      C1084            2        Q_CAP_0402-0.1UF,25V,10%,X7R,CA
GND                      C1086            2        Q_CAP_0402-0.1UF,25V,10%,X7R,CA
GND                      C1088            2        Q_CAP_0402-0.1UF,25V,10%,X7R,CA
GND                      C1107            2        Q_CAP_0402-0.1UF,25V,10%,X7R,CA
GND                      C1108            2        Q_CAP_0402-0.1UF,25V,10%,X7R,CA
GND                      C1110            2        Q_CAP_0402-0.1UF,25V,10%,X7R,CA
GND                      C1111            2        Q_CAP_0402-0.1UF,25V,10%,X7R,CA
GND                      C1113            2        Q_CAP_0402-0.1UF,25V,10%,X7R,CA
GND                      C1114            2        Q_CAP_0402-0.1UF,25V,10%,X7R,CA
GND                      C1115            2        Q_CAP_C0402-2.2UF,6.3V,20%,EMPA
GND                      C1118            2        Q_CAP_0402-0.1UF,25V,10%,X7R,CA
GND                      C1119            2        Q_CAP_0402-0.1UF,25V,10%,X7R,CA
GND                      C1120            2        Q_CAP_0402-0.1UF,25V,10%,X7R,CA
GND                      C1122            2        Q_CAP_0402-0.1UF,25V,10%,X7R,CA
GND                      C1123            2        Q_CAP_0402-0.1UF,25V,10%,X7R,CA
GND                      C1124            2        Q_CAP_0402-0.1UF,25V,10%,EMPTYA
GND                      C1127            2        Q_CAP_0402-0.1UF,25V,10%,X7R,CA
GND                      C1128            2        Q_CAP_0402-0.1UF,25V,10%,X7R,CA
GND                      C1129            2        Q_CAP_0402-0.1UF,25V,10%,X7R,CA
GND                      C1130            2        Q_CAP_0402-0.1UF,25V,10%,EMPTYA
GND                      C1133            2        Q_CAP_0402-0.1UF,25V,10%,X7R,CA
GND                      C1134            2        Q_CAP_0402-0.1UF,25V,10%,X7R,CA
GND                      C1135            2        Q_CAP_0402-0.1UF,25V,10%,X7R,CA
GND                      C1136            2        Q_CAP_0402-0.1UF,25V,10%,EMPTYA
GND                      C1138            2        Q_CAP_0402-0.1UF,25V,10%,X7R,CA
GND                      C1139            2        Q_CAP_0402-0.1UF,25V,10%,X7R,CA
GND                      C1140            2        Q_CAP_0402-0.1UF,25V,10%,EMPTYA
GND                      C1142            2        Q_CAP_0402-0.1UF,25V,10%,X7R,CA
GND                      C1143            2        Q_CAP_0402-0.1UF,25V,10%,X7R,CA
GND                      C1144            2        Q_CAP_0402-0.1UF,25V,10%,EMPTYA
GND                      C1146            2        Q_CAP_0402-0.1UF,25V,10%,X7R,CA
GND                      C1147            2        Q_CAP_0402-0.1UF,25V,10%,X7R,CA
GND                      C1148            2        Q_CAP_0402-0.1UF,25V,10%,EMPTYA
GND                      C1150            2        Q_CAP_0402-0.1UF,25V,10%,X7R,CA
GND                      C1151            2        Q_CAP_0402-0.1UF,25V,10%,X7R,CA
GND                      C1152            2        Q_CAP_0402-0.1UF,25V,10%,X7R,CA
GND                      C1153            2        Q_CAP_0402-0.1UF,25V,10%,X7R,CA
GND                      C1154            2        Q_CAP_0402-0.1UF,25V,10%,X7R,CA
GND                      C1155            2        Q_CAP_0402-0.1UF,25V,10%,X7R,CA
GND                      C1156            2        Q_CAP_0402-0.1UF,25V,10%,X7R,CA
GND                      C1157            2        Q_CAP_0402-0.1UF,25V,10%,X7R,CA
GND                      C1158            2        Q_CAP_0402-0.1UF,25V,10%,X7R,CA
GND                      C1159            2        Q_CAP_0402-0.1UF,25V,10%,X7R,CA
GND                      C1160            2        Q_CAP_0402-0.1UF,25V,10%,X7R,CA
GND                      C1161            2        Q_CAP_0402-0.1UF,25V,10%,X7R,CA
GND                      C1162            2        Q_CAP_0402-0.1UF,25V,10%,X7R,CA
GND                      C1163            2        Q_CAP_0402-0.1UF,25V,10%,X7R,CA
GND                      C1164            2        Q_CAP_0402-0.1UF,25V,10%,X7R,CA
GND                      C1165            2        Q_CAP_0402-0.1UF,25V,10%,X7R,CA
GND                      C1166            2        Q_CAP_0402-0.1UF,25V,10%,X7R,CA
GND                      C1167            2        Q_CAP_0402-0.1UF,25V,10%,X7R,CA
GND                      C1168            2        Q_CAP_0402-0.1UF,25V,10%,X7R,CA
GND                      C1169            2        Q_CAP_0402-0.1UF,25V,10%,X7R,CA
GND                      C1170            2        Q_CAP_C0805-10UF,16V,10%,X6S,CA
GND                      C1171            2        Q_CAP_C0805-10UF,16V,10%,EMPTYA
GND                      C1172            2        Q_CAP_C0402-100NF,50V,10%,X7R,A
GND                      C1173            2        Q_CAP_0402-0.1UF,25V,10%,X7R,CA
GND                      C1175            2        Q_CAP_0402-0.1UF,25V,10%,X7R,CA
GND                      C1177            2        Q_CAP_C0402-1UF,25V,10%,X6S,CHA
GND                      C1178            2        Q_CAP_C0603-22UF,4V,20%,X6S,CHA
GND                      C1181            2        Q_CAP_C0603-22UF,4V,20%,X6S,CHA
GND                      C1182            2        Q_CAP_C0603-22UF,4V,20%,X6S,CHA
GND                      C1183            2        Q_CAP_C0402-2.2UF,10V,10%,X6S,A
GND                      C1184            2        Q_CAP_C0603-22UF,4V,20%,X6S,CHA
GND                      C1185            2        Q_CAP_C0603-22UF,4V,20%,X6S,CHA
GND                      C1186            2        Q_CAP_C0603-22UF,4V,20%,X6S,CHA
GND                      C1187            2        Q_CAP_C0603-22UF,4V,20%,X6S,CHA
GND                      C1189            2        Q_CAP_C0402-2.2UF,10V,10%,X6S,A
GND                      C1191            2        Q_CAP_C0603-22UF,4V,20%,X6S,CHA
GND                      C1192            2        Q_CAP_C0603-22UF,4V,20%,X6S,CHA
GND                      C1197            2        Q_CAP_C0603-22UF,4V,20%,X6S,CHA
GND                      C1198            2        Q_CAP_C0603-22UF,4V,20%,X6S,CHA
GND                      C1200            2        Q_CAP_C0402-2.2UF,10V,10%,X6S,A
GND                      C1201            2        Q_CAP_C0603-22UF,4V,20%,X6S,CHA
GND                      C1202            2        Q_CAP_C0603-22UF,4V,20%,X6S,CHA
GND                      C1203            2        Q_CAP_C0402-10UF,6.3V,20%,X6S,A
GND                      C1204            2        Q_CAP_C0402-2.2UF,10V,10%,X6S,A
GND                      C1205            2        Q_CAP_C0402-10UF,6.3V,20%,X6S,A
GND                      C1206            2        Q_CAP_C0402-10UF,6.3V,20%,X6S,A
GND                      C1207            2        Q_CAP_C0402-10UF,6.3V,20%,X6S,A
GND                      C1208            2        Q_CAP_0402-0.1UF,25V,10%,X7R,CA
GND                      C1209            2        Q_CAP_0402-100PF,50V,5%,X7R,CHA
GND                      C1210            2        Q_CAP_C0402-10UF,6.3V,20%,X6S,A
GND                      C1211            2        Q_CAP_0402-100PF,50V,5%,X7R,CHA
GND                      C1213            2        Q_CAP_C0805-22UF,16V,20%,X6S,CA
GND                      C1214            2        Q_CAP_C0402-2.2UF,10V,10%,X6S,A
GND                      C1215            2        Q_CAP_0402-0.1UF,25V,10%,X7R,CA
GND                      C1216            2        Q_CAP_0402-0.1UF,25V,10%,X7R,CA
GND                      C1217            2        Q_CAP_0402-0.1UF,25V,10%,X7R,CA
GND                      C1218            2        Q_CAP_0402-0.1UF,25V,10%,X7R,CA
GND                      C1219            2        Q_CAP_0402-0.1UF,25V,10%,X7R,CA
GND                      C1226            2        Q_CAP_0402-0.22UF,16V,10%,X7R,A
GND                      C1227            2        Q_CAP_C0402-100NF,50V,10%,X7R,A
GND                      C1228            2        Q_CAP_C0402-10UF,6.3V,20%,X6S,A
GND                      C1229            2        Q_CAP_0402-0.1UF,25V,10%,X7R,CA
GND                      C1231            2        Q_CAP_C0402-10UF,6.3V,20%,X6S,A
GND                      C1232            2        Q_CAP_C0805-22UF,16V,20%,X6S,CA
GND                      C1233            2        Q_CAP_0402-0.1UF,25V,10%,X7R,CA
GND                      C1234            2        Q_CAP_0402-0.1UF,25V,10%,X7R,CA
GND                      C1235            2        Q_CAP_0402-0.1UF,25V,10%,X7R,CA
GND                      C1236            2        Q_CAP_0402-0.1UF,25V,10%,X7R,CA
GND                      C1237            2        Q_CAP_0402-0.1UF,25V,10%,X7R,CA
GND                      C1238            2        Q_CAP_0402-0.1UF,25V,10%,X7R,CA
GND                      C1239            2        Q_CAP_0402-0.1UF,25V,10%,X7R,CA
GND                      C1240            2        Q_CAP_0402-0.1UF,25V,10%,X7R,CA
GND                      C1241            2        Q_CAP_0402-0.1UF,25V,10%,X7R,CA
GND                      C1242            2        Q_CAP_C0402-2.2UF,10V,10%,X6S,A
GND                      C1243            2        Q_CAP_0805-47UF,4V,20%,X6S,CH6A
GND                      C1244            2        Q_CAP_0805-47UF,4V,20%,X6S,CH6A
GND                      C1245            2        Q_CAP_0805-47UF,4V,20%,X6S,CH6A
GND                      C1246            2        Q_CAP_0805-47UF,4V,20%,X6S,CH6A
GND                      C1247            2        Q_CAP_0805-47UF,4V,20%,X6S,CH6A
GND                      C1248            2        Q_CAP_0805-47UF,4V,20%,X6S,CH6A
GND                      C1249            2        Q_CAP_0805-47UF,4V,20%,X6S,CH6A
GND                      C1250            2        Q_CAP_0402-1UF,6.3V,10%,EMPTY,A
GND                      C1251            2        Q_CAP_C0603-10UF,6.3V,20%,X6S,A
GND                      C1252            2        Q_CAP_C0603-10UF,6.3V,20%,X6S,A
GND                      C1253            2        Q_CAP_0402-1UF,6.3V,10%,EMPTY,A
GND                      C1254            2        Q_CAP_C0603-10UF,6.3V,20%,X6S,A
GND                      C1255            2        Q_CAP_C0603-10UF,6.3V,20%,X6S,A
GND                      C1256            2        Q_CAP_0402-1UF,6.3V,10%,EMPTY,A
GND                      C1257            2        Q_CAP_0402-1UF,6.3V,10%,EMPTY,A
GND                      C1258            2        Q_CAP_0805-47UF,4V,20%,X6S,CH6A
GND                      C1259            2        Q_CAP_0805-47UF,4V,20%,X6S,CH6A
GND                      C1260            2        Q_CAP_C0603-10UF,6.3V,20%,X6S,A
GND                      C1261            2        Q_CAP_C0603-10UF,6.3V,20%,X6S,A
GND                      C1262            2        Q_CAP_C0402-10UF,6.3V,20%,X6S,A
GND                      C1263            2        Q_CAP_C0402-10UF,6.3V,20%,X6S,A
GND                      C1264            2        Q_CAP_0402-1UF,6.3V,10%,EMPTY,A
GND                      C1265            2        Q_CAP_0402-1UF,6.3V,10%,EMPTY,A
GND                      C1266            2        Q_CAP_C0402-10UF,6.3V,20%,X6S,A
GND                      C1272            2        Q_CAP_0805-47UF,4V,20%,X6S,CH6A
GND                      C1273            2        Q_CAP_0805-47UF,4V,20%,X6S,CH6A
GND                      C1274            2        Q_CAP_0402-0.1UF,25V,10%,X7R,CA
GND                      C1275            2        Q_CAP_0402-0.1UF,25V,10%,X7R,CA
GND                      C1276            2        Q_CAP_C0805-22UF,16V,20%,X6S,CA
GND                      C1277            2        Q_CAP_C0805-22UF,16V,20%,X6S,CA
GND                      C1278            2        Q_CAP_0402-0.1UF,25V,10%,X7R,CA
GND                      C1279            2        Q_CAP_0402-0.1UF,25V,10%,X7R,CA
GND                      C1280            2        Q_CAP_0402-0.1UF,25V,10%,X7R,CA
GND                      C1281            2        Q_CAP_0402-0.1UF,25V,10%,X7R,CA
GND                      C1282            2        Q_CAP_0402-0.1UF,25V,10%,X7R,CA
GND                      C1283            2        Q_CAP_0402-0.1UF,25V,10%,X7R,CA
GND                      C1284            2        Q_CAP_0402-0.1UF,25V,10%,X7R,CA
GND                      C1285            2        Q_CAP_0402-0.1UF,25V,10%,X7R,CA
GND                      C1286            2        Q_CAP_0402-1000PF,50V,5%,EMPTYA
GND                      C1288            2        Q_CAP_0402-0.1UF,25V,10%,X7R,CA
GND                      C1289            2        Q_CAP_C0402-1UF,25V,10%,X6S,CHA
GND                      C1290            2        Q_CAP_C0402-1UF,25V,10%,X6S,CHA
GND                      C1291            2        Q_CAP_C0402-1UF,25V,10%,X6S,CHA
GND                      C1292            2        Q_CAP_0402-0.1UF,25V,10%,X7R,CA
GND                      C1293            2        Q_CAP_C0402-1UF,25V,10%,X6S,CHA
GND                      C1296            2        Q_CAP_0402-1000PF,50V,5%,X7R,TA
GND                      C1297            2        Q_CAP_0402-1000PF,50V,5%,X7R,TA
GND                      C1300            2        Q_CAP_0402-1000PF,50V,5%,EMPTYA
GND                      C1301            2        Q_CAP_0402-1000PF,50V,5%,EMPTYA
GND                      C1302            2        Q_CAP_C0402-22UF,4V,20%,X6S,CHA
GND                      C1305            2        Q_CAP_0402-0.1UF,25V,10%,X7R,CA
GND                      C1307            2        Q_CAP_0402-1000PF,50V,5%,EMPTYA
GND                      C1308            2        Q_CAP_0402-1000PF,50V,5%,EMPTYA
GND                      C1309            2        Q_CAP_C0603-10UF,6.3V,20%,X6S,A
GND                      C1310            2        Q_CAP_C0603-10UF,6.3V,20%,X6S,A
GND                      C1311            2        Q_CAP_C0402-1UF,25V,10%,X6S,CHA
GND                      C1312            2        Q_CAP_C0402-1UF,25V,10%,X6S,CHA
GND                      C1313            2        Q_CAP_C0603-10UF,6.3V,20%,X6S,A
GND                      C1314            2        Q_CAP_C0603-10UF,6.3V,20%,X6S,A
GND                      C1315            2        Q_CAP_C0402-1UF,25V,10%,X6S,CHA
GND                      C1316            2        Q_CAP_C0402-0.047UF,25V,10%,X7A
GND                      C1317            2        Q_CAP_0402-0.1UF,25V,10%,X7R,CA
GND                      C1318            2        Q_CAP_C0402-1UF,25V,10%,EMPTY,A
GND                      C1319            2        Q_CAP_C0402-1UF,25V,10%,X6S,CHA
GND                      C1320            2        Q_CAP_0402-0.1UF,25V,10%,X7R,CA
GND                      C1321            2        Q_CAP_0402-0.1UF,25V,10%,X7R,CA
GND                      C1322            2        Q_CAP_0402-0.1UF,25V,10%,X7R,CA
GND                      C1323            2        Q_CAP_0402-0.1UF,25V,10%,X7R,CA
GND                      C1324            2        Q_CAP_0402-0.1UF,25V,10%,EMPTYA
GND                      C1325            2        Q_CAP_0402-0.1UF,25V,10%,X7R,CA
GND                      C1326            2        Q_CAP_C0402-100NF,50V,10%,X7R,A
GND                      C1331            2        Q_CAP_C0805-10UF,16V,10%,X6S,CA
GND                      C1332            2        Q_CAP_C0402-100NF,50V,10%,X7R,A
GND                      C1333            2        Q_CAP_C0805-10UF,16V,10%,X6S,CA
GND                      C1337            2        Q_CAP_C0603-22UF,6.3V,20%,X6S,A
GND                      C1338            2        Q_CAP_C0805-10UF,16V,10%,EMPTYA
GND                      C1339            2        Q_CAP_C0402-100NF,50V,10%,X7R,A
GND                      C1340            2        Q_CAP_C0805-10UF,16V,10%,X6S,CA
GND                      C1341            2        Q_CAP_C0603-22UF,6.3V,20%,X6S,A
GND                      C1342            2        Q_CAP_C0603-22UF,6.3V,20%,X6S,A
GND                      C1343            2        Q_CAP_C0603-22UF,6.3V,20%,X6S,A
GND                      C1344            2        Q_CAP_0402-0.1UF,25V,10%,X7R,CA
GND                      C1345            2        Q_CAP_0402-0.1UF,25V,10%,X7R,CA
GND                      C1346            2        Q_CAP_0402-0.1UF,25V,10%,X7R,CA
GND                      C1347            2        Q_CAP_0402-0.1UF,25V,10%,X7R,CA
GND                      C1351            2        Q_CAP_0402-0.1UF,25V,10%,X7R,CA
GND                      C1353            2        Q_CAP_C0402-22UF,4V,20%,X6S,CHA
GND                      C1358            2        Q_CAP_0402-0.1UF,25V,10%,X7R,CA
GND                      C1359            2        Q_CAP_C0805-10UF,25V,10%,X6S,CA
GND                      C1360            2        Q_CAP_0402-0.1UF,25V,10%,X7R,CA
GND                      C1361            2        Q_CAP_C0805-10UF,25V,10%,X6S,CA
GND                      C1362            2        Q_CAP_C0402-22UF,4V,20%,X6S,CHA
GND                      C1363            2        Q_CAP_C0402-22UF,4V,20%,X6S,CHA
GND                      C1364            2        Q_CAP_C0402-22UF,4V,20%,X6S,CHA
GND                      C1365            2        Q_CAP_C0402-22UF,4V,20%,X6S,CHA
GND                      C1366            2        Q_CAP_C0402-22UF,4V,20%,X6S,CHA
GND                      C1387            2        Q_CAP_C0805-100UF,4V,20%,X6S,CA
GND                      C1388            2        Q_CAP_C0805-100UF,4V,20%,X6S,CA
GND                      C1389            2        Q_CAP_C0603-47UF,2.5V,20%,X6S,A
GND                      C1390            2        Q_CAP_C0805-100UF,4V,20%,X6S,CA
GND                      C1391            2        Q_CAP_C0603-47UF,2.5V,20%,X6S,A
GND                      C1392            2        Q_CAP_C0805-100UF,4V,20%,X6S,CA
GND                      C1393            2        Q_CAP_C0603-47UF,2.5V,20%,X6S,A
GND                      C1396            2        Q_CAP_C0805-100UF,4V,20%,X6S,CA
GND                      C1397            2        Q_CAP_C0805-100UF,4V,20%,X6S,CA
GND                      C1398            2        Q_CAP_C0805-100UF,4V,20%,X6S,CA
GND                      C1399            2        Q_CAP_C0805-100UF,4V,20%,X6S,CA
GND                      C1400            2        Q_CAP_C0805-100UF,4V,20%,X6S,CA
GND                      C1403            2        Q_CAP_C0805-100UF,4V,20%,X6S,CA
GND                      C1404            2        Q_CAP_C0805-100UF,4V,20%,X6S,CA
GND                      C1405            2        Q_CAP_C0603-47UF,2.5V,20%,X6S,A
GND                      C1406            2        Q_CAP_C0603-47UF,2.5V,20%,X6S,A
GND                      C1407            2        Q_CAP_C0603-47UF,2.5V,20%,X6S,A
GND                      C1408            2        Q_CAP_0402-0.1UF,25V,10%,X7R,CA
GND                      C1409            2        Q_CAP_C0603-10UF,6.3V,20%,X6S,A
GND                      C1430            2        Q_CAP_0402-0.1UF,25V,10%,X7R,CA
GND                      C1431            2        Q_CAP_C0805-10UF,25V,10%,X6S,CA
GND                      C1432            2        Q_CAP_0402-0.1UF,25V,10%,X7R,CA
GND                      C1433            2        Q_CAP_C0805-10UF,25V,10%,X6S,CA
GND                      C1436            2        Q_CAP_C0201-0.22UF,6.3V,10%,X6A
GND                      C1437            2        Q_CAP_C0201-0.22UF,6.3V,10%,X6A
GND                      C1438            2        Q_CAP_C0805-22UF,16V,20%,X6S,CA
GND                      C1439            2        Q_CAP_C0805-22UF,16V,20%,X6S,CA
GND                      C1440            2        Q_CAP_0402-0.1UF,25V,10%,X7R,CA
GND                      C1441            2        Q_CAP_0402-0.1UF,25V,10%,X7R,CA
GND                      C1442            2        Q_CAP_0402-0.1UF,25V,10%,X7R,CA
GND                      C1443            2        Q_CAP_0402-0.1UF,25V,10%,X7R,CA
GND                      C1444            2        Q_CAP_0402-0.1UF,25V,10%,X7R,CA
GND                      C1445            2        Q_CAP_C0805-22UF,16V,20%,X6S,CA
GND                      C1446            2        Q_CAP_0402-0.1UF,25V,10%,X7R,CA
GND                      C1447            2        Q_CAP_0402-0.1UF,25V,10%,X7R,CA
GND                      C1448            2        Q_CAP_C0805-22UF,16V,20%,X6S,CA
GND                      C1449            2        Q_CAP_C0805-22UF,16V,20%,X6S,CA
GND                      C1450            2        Q_CAP_0402-0.1UF,25V,10%,X7R,CA
GND                      C1451            2        Q_CAP_0402-0.1UF,25V,10%,X7R,CA
GND                      C1452            2        Q_CAP_0402-0.1UF,25V,10%,X7R,CA
GND                      C1453            2        Q_CAP_0402-0.1UF,25V,10%,X7R,CA
GND                      C1454            2        Q_CAP_0402-0.1UF,25V,10%,X7R,CA
GND                      C1455            2        Q_CAP_C0805-22UF,16V,20%,X6S,CA
GND                      C1456            2        Q_CAP_0402-0.1UF,25V,10%,X7R,CA
GND                      C1457            2        Q_CAP_0402-0.1UF,25V,10%,X7R,CA
GND                      C1459            2        Q_CAP_C0805-22UF,16V,20%,X6S,CA
GND                      C1460            2        Q_CAP_0402-0.1UF,25V,10%,X7R,CA
GND                      C1461            2        Q_CAP_0402-0.1UF,25V,10%,X7R,CA
GND                      C1462            2        Q_CAP_0402-0.1UF,25V,10%,X7R,CA
GND                      C1463            2        Q_CAP_0402-0.1UF,25V,10%,X7R,CA
GND                      C1464            2        Q_CAP_0402-0.1UF,25V,10%,X7R,CA
GND                      C1465            2        Q_CAP_C0805-22UF,16V,20%,X6S,CA
GND                      C1466            2        Q_CAP_0402-0.1UF,25V,10%,X7R,CA
GND                      C1467            2        Q_CAP_0402-0.1UF,25V,10%,X7R,CA
GND                      C1469            2        Q_CAP_C0805-22UF,16V,20%,X6S,CA
GND                      C1470            2        Q_CAP_0402-0.1UF,25V,10%,X7R,CA
GND                      C1471            2        Q_CAP_0402-0.1UF,25V,10%,X7R,CA
GND                      C1472            2        Q_CAP_0402-0.1UF,25V,10%,X7R,CA
GND                      C1473            2        Q_CAP_0402-0.1UF,25V,10%,X7R,CA
GND                      C1474            2        Q_CAP_0402-0.1UF,25V,10%,X7R,CA
GND                      C1475            2        Q_CAP_C0805-22UF,16V,20%,X6S,CA
GND                      C1476            2        Q_CAP_0402-0.1UF,25V,10%,X7R,CA
GND                      C1477            2        Q_CAP_0402-0.1UF,25V,10%,X7R,CA
GND                      C1480            2        Q_CAP_C0402-100NF,50V,10%,X7R,A
GND                      C1481            2        Q_CAP_0402-0.1UF,25V,10%,X7R,CA
GND                      C1482            2        Q_CAP_0402-0.1UF,25V,10%,X7R,CA
GND                      C1483            2        Q_CAP_C0805-10UF,25V,10%,X6S,CA
GND                      C1484            2        Q_CAP_C0402-100NF,50V,10%,X7R,A
GND                      C1485            2        Q_CAP_0402-0.1UF,25V,10%,X7R,CA
GND                      C1486            2        Q_CAP_0402-0.1UF,25V,10%,X7R,CA
GND                      C1487            2        Q_CAP_C0805-10UF,25V,10%,X6S,CA
GND                      C1488            2        Q_CAP_C0805-10UF,25V,10%,X6S,CA
GND                      C1489            2        Q_CAP_C0805-22UF,16V,20%,X6S,CA
GND                      C1490            2        Q_CAP_C0805-22UF,16V,20%,X6S,CA
GND                      C1491            2        Q_CAP_C0805-22UF,16V,20%,X6S,CA
GND                      C1492            2        Q_CAP_C0805-22UF,16V,20%,X6S,CA
GND                      C1493            2        Q_CAP_C0805-22UF,16V,20%,X6S,CA
GND                      C1494            2        Q_CAP_C0805-22UF,16V,20%,X6S,CA
GND                      C1495            2        Q_CAP_0402-0.1UF,25V,10%,X7R,CA
GND                      C1496            2        Q_CAP_0402-0.1UF,25V,10%,X7R,CA
GND                      C1497            2        Q_CAP_0402-0.1UF,25V,10%,X7R,CA
GND                      C1498            2        Q_CAP_0402-0.1UF,25V,10%,X7R,CA
GND                      C1499            2        Q_CAP_0402-0.1UF,25V,10%,X7R,CA
GND                      C1500            2        Q_CAP_0402-0.1UF,25V,10%,X7R,CA
GND                      C1501            2        Q_CAP_0402-0.1UF,25V,10%,X7R,CA
GND                      C1502            2        Q_CAP_0402-0.1UF,25V,10%,X7R,CA
GND                      C1503            2        Q_CAP_C0402-0.047UF,25V,10%,X7A
GND                      C1504            2        Q_CAP_C0402-0.047UF,25V,10%,X7A
GND                      C1505            2        Q_CAP_0402-0.1UF,25V,10%,X7R,CA
GND                      C1506            2        Q_CAP_C0805-10UF,25V,10%,X6S,CA
GND                      C1507            2        Q_CAP_0402-27PF  ,50V ,5% ,NPOA
GND                      C1508            2        Q_CAP_0402-27PF  ,50V ,5% ,NPOA
GND                      C1509            2        Q_CAP_C0805-10UF,25V,10%,X6S,CA
GND                      C1510            2        Q_CAP_C0402-0.047UF,25V,10%,X7A
GND                      C1511            2        Q_CAP_C0402-0.047UF,25V,10%,X7A
GND                      C1512            2        Q_CAP_0402-0.1UF,25V,10%,X7R,CA
GND                      C1513            2        Q_CAP_0402-0.1UF,25V,10%,X7R,CA
GND                      C1514            2        Q_CAP_C0805-10UF,25V,10%,X6S,CA
GND                      C1515            2        Q_CAP_C0805-10UF,25V,10%,X6S,CA
GND                      C1580            2        Q_CAP_0402-1NF,50V,10%,X7R,CH2A
GND                      C1581            2        Q_CAP_C0402-1UF,25V,10%,EMPTY,A
GND                      C1582            2        Q_CAP_C0402-100NF,50V,10%,X7R,A
GND                      C1583            2        Q_CAP_C0402-100NF,50V,10%,X7R,A
GND                      C1584            2        Q_CAP_C0402-100NF,50V,10%,X7R,A
GND                      C1585            2        Q_CAP_0402-1NF,50V,10%,X7R,CH2A
GND                      C1586            2        Q_CAP_C0402-100NF,50V,10%,X7R,A
GND                      C1587            2        Q_CAP_C0402-1UF,25V,10%,EMPTY,A
GND                      C1588            2        Q_CAP_0402-0.1UF,25V,10%,X7R,CA
GND                      C1589            2        Q_CAP_0402-0.1UF,25V,10%,X7R,CA
GND                      C1590            2        Q_CAP_0402-0.1UF,25V,10%,X7R,CA
GND                      C1591            2        Q_CAP_0402-0.1UF,25V,10%,X7R,CA
GND                      C1592            2        Q_CAP_0402-0.1UF,25V,10%,X7R,CA
GND                      C1593            2        Q_CAP_0402-0.1UF,25V,10%,X7R,CA
GND                      C1594            2        Q_CAP_0402-0.1UF,25V,10%,X7R,CA
GND                      C1595            2        Q_CAP_0402-0.1UF,25V,10%,X7R,CA
GND                      C1596            2        Q_CAP_C0402-0.047UF,25V,10%,X7A
GND                      C1597            2        Q_CAP_0402-0.1UF,25V,10%,X7R,CA
GND                      C1598            2        Q_CAP_C0805-10UF,25V,10%,X6S,CA
GND                      C1599            2        Q_CAP_C0805-22UF,10V,20%,X6S,CA
GND                      C1600            2        Q_CAP_C0805-22UF,10V,20%,X6S,CA
GND                      C1601            2        Q_CAPP_SMLF-100UF,16V,20%,POSCA
GND                      C1602            2        Q_CAP_0402-0.1UF,25V,10%,X7R,CA
GND                      C1603            2        Q_CAPP_SMLF-100UF,16V,20%,POSCA
GND                      C1604            2        Q_CAP_0402-0.1UF,25V,10%,X7R,CA
GND                      C1605            2        Q_CAP_C0402-1UF,25V,10%,X6S,CHA
GND                      C1606            2        Q_CAP_0402-0.1UF,25V,10%,X7R,CA
GND                      C1607            2        Q_CAP_0402-0.1UF,25V,10%,X7R,CA
GND                      C2443            2        Q_CAP_C0402-10UF,6.3V,20%,X6S,A
GND                      C2444            2        Q_CAP_0402-0.1UF,25V,10%,X7R,CA
GND                      C2445            2        Q_CAP_0402-1000PF,50V,5%,EMPTYA
GND                      C2446            2        Q_CAP_0402-1000PF,50V,5%,X7R,TA
GND                      D4               A        SCHOTTKY_AC-SX34F,SMLF,IC,BC00A
GND                      D6               C        Q_LED_SMLF-LED_RED,19-217/R6C-A
GND                      D8               A        DIODE_TVS-SMF14A,SMLF,IC,BCSMFA
GND                      D9               A        DIODE_TVS-SMF14A,SMLF,IC,BCSMFA
GND                      D10              A        DIODE_TVS-SMF14A,SMLF,IC,BCSMFA
GND                      D11              A        DIODE_TVS-SMF14A,SMLF,IC,BCSMFA
GND                      D12              A        DIODE_TVS-SMF14A,SMLF,IC,BCSMFA
GND                      H1               1        HOLE_TH-EMPTY,HOLE1087
GND                      H2               1        HOLE_TH-EMPTY,HOLE1087
GND                      H3               1        HOLE_TH-EMPTY,HOLE1087
GND                      H4               1        HOLE_TH-EMPTY,HOLE1087
GND                      H5               1        HOLE_TH-EMPTY,HOLE1087
GND                      H6               1        HOLE_TH-EMPTY,HOLE1087
GND                      H7               1        HOLE_TH-EMPTY,HOLE1087
GND                      H8               1        HOLE_TH-EMPTY,HOLE1087
GND                      H9               1        HOLE_TH-EMPTY,HOLE1087
GND                      H10              1        HOLE_TH-EMPTY,HOLE1087
GND                      H11              1        HOLE_TH-EMPTY,HOLE1087
GND                      H12              1        HOLE_TH-EMPTY,HOLE1087
GND                      H13              1        HOLE_TH-EMPTY,HOLE1087
GND                      H31              1        HOLE_TH-EMPTY,HOLE1214
GND                      H32              1        HOLE_TH-EMPTY,HOLE1214
GND                      H35              1        HOLE_TH-EMPTY,HOLE1098
GND                      H37              1        HOLE_TH-EMPTY,HOLE1098
GND                      H39              1        HOLE_TH-EMPTY,HOLE1222
GND                      H40              1        HOLE_TH-EMPTY,HOLE1222
GND                      H44              1        HOLE_TH-EMPTY,HOLE1212
GND                      H45              1        HOLE_TH-EMPTY,HOLE1212
GND                      H47              1        HOLE_TH-EMPTY,HOLE1212
GND                      H49              1        HOLE_TH-EMPTY,HOLE1212
GND                      H54              1        HOLE_TH-EMPTY,HOLE1087
GND                      H55              1        HOLE_TH-EMPTY,HOLE1087
GND                      J1               6        SCONN288_ADR50001P013C01-SCONNA
GND                      J1               8        SCONN288_ADR50001P013C01-SCONNA
GND                      J1               10       SCONN288_ADR50001P013C01-SCONNA
GND                      J1               13       SCONN288_ADR50001P013C01-SCONNA
GND                      J1               15       SCONN288_ADR50001P013C01-SCONNA
GND                      J1               17       SCONN288_ADR50001P013C01-SCONNA
GND                      J1               19       SCONN288_ADR50001P013C01-SCONNA
GND                      J1               21       SCONN288_ADR50001P013C01-SCONNA
GND                      J1               24       SCONN288_ADR50001P013C01-SCONNA
GND                      J1               26       SCONN288_ADR50001P013C01-SCONNA
GND                      J1               28       SCONN288_ADR50001P013C01-SCONNA
GND                      J1               30       SCONN288_ADR50001P013C01-SCONNA
GND                      J1               32       SCONN288_ADR50001P013C01-SCONNA
GND                      J1               35       SCONN288_ADR50001P013C01-SCONNA
GND                      J1               37       SCONN288_ADR50001P013C01-SCONNA
GND                      J1               39       SCONN288_ADR50001P013C01-SCONNA
GND                      J1               41       SCONN288_ADR50001P013C01-SCONNA
GND                      J1               43       SCONN288_ADR50001P013C01-SCONNA
GND                      J1               46       SCONN288_ADR50001P013C01-SCONNA
GND                      J1               48       SCONN288_ADR50001P013C01-SCONNA
GND                      J1               50       SCONN288_ADR50001P013C01-SCONNA
GND                      J1               52       SCONN288_ADR50001P013C01-SCONNA
GND                      J1               54       SCONN288_ADR50001P013C01-SCONNA
GND                      J1               57       SCONN288_ADR50001P013C01-SCONNA
GND                      J1               59       SCONN288_ADR50001P013C01-SCONNA
GND                      J1               61       SCONN288_ADR50001P013C01-SCONNA
GND                      J1               63       SCONN288_ADR50001P013C01-SCONNA
GND                      J1               65       SCONN288_ADR50001P013C01-SCONNA
GND                      J1               67       SCONN288_ADR50001P013C01-SCONNA
GND                      J1               69       SCONN288_ADR50001P013C01-SCONNA
GND                      J1               71       SCONN288_ADR50001P013C01-SCONNA
GND                      J1               73       SCONN288_ADR50001P013C01-SCONNA
GND                      J1               75       SCONN288_ADR50001P013C01-SCONNA
GND                      J1               77       SCONN288_ADR50001P013C01-SCONNA
GND                      J1               79       SCONN288_ADR50001P013C01-SCONNA
GND                      J1               81       SCONN288_ADR50001P013C01-SCONNA
GND                      J1               83       SCONN288_ADR50001P013C01-SCONNA
GND                      J1               85       SCONN288_ADR50001P013C01-SCONNA
GND                      J1               88       SCONN288_ADR50001P013C01-SCONNA
GND                      J1               90       SCONN288_ADR50001P013C01-SCONNA
GND                      J1               92       SCONN288_ADR50001P013C01-SCONNA
GND                      J1               95       SCONN288_ADR50001P013C01-SCONNA
GND                      J1               97       SCONN288_ADR50001P013C01-SCONNA
GND                      J1               99       SCONN288_ADR50001P013C01-SCONNA
GND                      J1               101      SCONN288_ADR50001P013C01-SCONNA
GND                      J1               103      SCONN288_ADR50001P013C01-SCONNA
GND                      J1               106      SCONN288_ADR50001P013C01-SCONNA
GND                      J1               108      SCONN288_ADR50001P013C01-SCONNA
GND                      J1               110      SCONN288_ADR50001P013C01-SCONNA
GND                      J1               112      SCONN288_ADR50001P013C01-SCONNA
GND                      J1               114      SCONN288_ADR50001P013C01-SCONNA
GND                      J1               117      SCONN288_ADR50001P013C01-SCONNA
GND                      J1               119      SCONN288_ADR50001P013C01-SCONNA
GND                      J1               121      SCONN288_ADR50001P013C01-SCONNA
GND                      J1               123      SCONN288_ADR50001P013C01-SCONNA
GND                      J1               125      SCONN288_ADR50001P013C01-SCONNA
GND                      J1               128      SCONN288_ADR50001P013C01-SCONNA
GND                      J1               130      SCONN288_ADR50001P013C01-SCONNA
GND                      J1               132      SCONN288_ADR50001P013C01-SCONNA
GND                      J1               134      SCONN288_ADR50001P013C01-SCONNA
GND                      J1               136      SCONN288_ADR50001P013C01-SCONNA
GND                      J1               139      SCONN288_ADR50001P013C01-SCONNA
GND                      J1               141      SCONN288_ADR50001P013C01-SCONNA
GND                      J1               143      SCONN288_ADR50001P013C01-SCONNA
GND                      J1               151      SCONN288_ADR50001P013C01-SCONNA
GND                      J1               153      SCONN288_ADR50001P013C01-SCONNA
GND                      J1               155      SCONN288_ADR50001P013C01-SCONNA
GND                      J1               158      SCONN288_ADR50001P013C01-SCONNA
GND                      J1               160      SCONN288_ADR50001P013C01-SCONNA
GND                      J1               162      SCONN288_ADR50001P013C01-SCONNA
GND                      J1               164      SCONN288_ADR50001P013C01-SCONNA
GND                      J1               166      SCONN288_ADR50001P013C01-SCONNA
GND                      J1               169      SCONN288_ADR50001P013C01-SCONNA
GND                      J1               171      SCONN288_ADR50001P013C01-SCONNA
GND                      J1               173      SCONN288_ADR50001P013C01-SCONNA
GND                      J1               175      SCONN288_ADR50001P013C01-SCONNA
GND                      J1               177      SCONN288_ADR50001P013C01-SCONNA
GND                      J1               180      SCONN288_ADR50001P013C01-SCONNA
GND                      J1               182      SCONN288_ADR50001P013C01-SCONNA
GND                      J1               184      SCONN288_ADR50001P013C01-SCONNA
GND                      J1               186      SCONN288_ADR50001P013C01-SCONNA
GND                      J1               188      SCONN288_ADR50001P013C01-SCONNA
GND                      J1               191      SCONN288_ADR50001P013C01-SCONNA
GND                      J1               193      SCONN288_ADR50001P013C01-SCONNA
GND                      J1               195      SCONN288_ADR50001P013C01-SCONNA
GND                      J1               197      SCONN288_ADR50001P013C01-SCONNA
GND                      J1               199      SCONN288_ADR50001P013C01-SCONNA
GND                      J1               202      SCONN288_ADR50001P013C01-SCONNA
GND                      J1               204      SCONN288_ADR50001P013C01-SCONNA
GND                      J1               206      SCONN288_ADR50001P013C01-SCONNA
GND                      J1               208      SCONN288_ADR50001P013C01-SCONNA
GND                      J1               210      SCONN288_ADR50001P013C01-SCONNA
GND                      J1               212      SCONN288_ADR50001P013C01-SCONNA
GND                      J1               214      SCONN288_ADR50001P013C01-SCONNA
GND                      J1               216      SCONN288_ADR50001P013C01-SCONNA
GND                      J1               219      SCONN288_ADR50001P013C01-SCONNA
GND                      J1               222      SCONN288_ADR50001P013C01-SCONNA
GND                      J1               224      SCONN288_ADR50001P013C01-SCONNA
GND                      J1               226      SCONN288_ADR50001P013C01-SCONNA
GND                      J1               228      SCONN288_ADR50001P013C01-SCONNA
GND                      J1               230      SCONN288_ADR50001P013C01-SCONNA
GND                      J1               233      SCONN288_ADR50001P013C01-SCONNA
GND                      J1               235      SCONN288_ADR50001P013C01-SCONNA
GND                      J1               237      SCONN288_ADR50001P013C01-SCONNA
GND                      J1               240      SCONN288_ADR50001P013C01-SCONNA
GND                      J1               242      SCONN288_ADR50001P013C01-SCONNA
GND                      J1               244      SCONN288_ADR50001P013C01-SCONNA
GND                      J1               246      SCONN288_ADR50001P013C01-SCONNA
GND                      J1               248      SCONN288_ADR50001P013C01-SCONNA
GND                      J1               251      SCONN288_ADR50001P013C01-SCONNA
GND                      J1               253      SCONN288_ADR50001P013C01-SCONNA
GND                      J1               255      SCONN288_ADR50001P013C01-SCONNA
GND                      J1               257      SCONN288_ADR50001P013C01-SCONNA
GND                      J1               259      SCONN288_ADR50001P013C01-SCONNA
GND                      J1               262      SCONN288_ADR50001P013C01-SCONNA
GND                      J1               264      SCONN288_ADR50001P013C01-SCONNA
GND                      J1               266      SCONN288_ADR50001P013C01-SCONNA
GND                      J1               268      SCONN288_ADR50001P013C01-SCONNA
GND                      J1               270      SCONN288_ADR50001P013C01-SCONNA
GND                      J1               273      SCONN288_ADR50001P013C01-SCONNA
GND                      J1               275      SCONN288_ADR50001P013C01-SCONNA
GND                      J1               277      SCONN288_ADR50001P013C01-SCONNA
GND                      J1               279      SCONN288_ADR50001P013C01-SCONNA
GND                      J1               281      SCONN288_ADR50001P013C01-SCONNA
GND                      J1               284      SCONN288_ADR50001P013C01-SCONNA
GND                      J1               286      SCONN288_ADR50001P013C01-SCONNA
GND                      J1               288      SCONN288_ADR50001P013C01-SCONNA
GND                      J1               G1       SCONN288_ADR50001P013C01-SCONNA
GND                      J1               G2       SCONN288_ADR50001P013C01-SCONNA
GND                      J1               G3       SCONN288_ADR50001P013C01-SCONNA
GND                      J2               6        SCONN288_ADR50001P003C01-SCONNA
GND                      J2               8        SCONN288_ADR50001P003C01-SCONNA
GND                      J2               10       SCONN288_ADR50001P003C01-SCONNA
GND                      J2               13       SCONN288_ADR50001P003C01-SCONNA
GND                      J2               15       SCONN288_ADR50001P003C01-SCONNA
GND                      J2               17       SCONN288_ADR50001P003C01-SCONNA
GND                      J2               19       SCONN288_ADR50001P003C01-SCONNA
GND                      J2               21       SCONN288_ADR50001P003C01-SCONNA
GND                      J2               24       SCONN288_ADR50001P003C01-SCONNA
GND                      J2               26       SCONN288_ADR50001P003C01-SCONNA
GND                      J2               28       SCONN288_ADR50001P003C01-SCONNA
GND                      J2               30       SCONN288_ADR50001P003C01-SCONNA
GND                      J2               32       SCONN288_ADR50001P003C01-SCONNA
GND                      J2               35       SCONN288_ADR50001P003C01-SCONNA
GND                      J2               37       SCONN288_ADR50001P003C01-SCONNA
GND                      J2               39       SCONN288_ADR50001P003C01-SCONNA
GND                      J2               41       SCONN288_ADR50001P003C01-SCONNA
GND                      J2               43       SCONN288_ADR50001P003C01-SCONNA
GND                      J2               46       SCONN288_ADR50001P003C01-SCONNA
GND                      J2               48       SCONN288_ADR50001P003C01-SCONNA
GND                      J2               50       SCONN288_ADR50001P003C01-SCONNA
GND                      J2               52       SCONN288_ADR50001P003C01-SCONNA
GND                      J2               54       SCONN288_ADR50001P003C01-SCONNA
GND                      J2               57       SCONN288_ADR50001P003C01-SCONNA
GND                      J2               59       SCONN288_ADR50001P003C01-SCONNA
GND                      J2               61       SCONN288_ADR50001P003C01-SCONNA
GND                      J2               63       SCONN288_ADR50001P003C01-SCONNA
GND                      J2               65       SCONN288_ADR50001P003C01-SCONNA
GND                      J2               67       SCONN288_ADR50001P003C01-SCONNA
GND                      J2               69       SCONN288_ADR50001P003C01-SCONNA
GND                      J2               71       SCONN288_ADR50001P003C01-SCONNA
GND                      J2               73       SCONN288_ADR50001P003C01-SCONNA
GND                      J2               75       SCONN288_ADR50001P003C01-SCONNA
GND                      J2               77       SCONN288_ADR50001P003C01-SCONNA
GND                      J2               79       SCONN288_ADR50001P003C01-SCONNA
GND                      J2               81       SCONN288_ADR50001P003C01-SCONNA
GND                      J2               83       SCONN288_ADR50001P003C01-SCONNA
GND                      J2               85       SCONN288_ADR50001P003C01-SCONNA
GND                      J2               88       SCONN288_ADR50001P003C01-SCONNA
GND                      J2               90       SCONN288_ADR50001P003C01-SCONNA
GND                      J2               92       SCONN288_ADR50001P003C01-SCONNA
GND                      J2               95       SCONN288_ADR50001P003C01-SCONNA
GND                      J2               97       SCONN288_ADR50001P003C01-SCONNA
GND                      J2               99       SCONN288_ADR50001P003C01-SCONNA
GND                      J2               101      SCONN288_ADR50001P003C01-SCONNA
GND                      J2               103      SCONN288_ADR50001P003C01-SCONNA
GND                      J2               106      SCONN288_ADR50001P003C01-SCONNA
GND                      J2               108      SCONN288_ADR50001P003C01-SCONNA
GND                      J2               110      SCONN288_ADR50001P003C01-SCONNA
GND                      J2               112      SCONN288_ADR50001P003C01-SCONNA
GND                      J2               114      SCONN288_ADR50001P003C01-SCONNA
GND                      J2               117      SCONN288_ADR50001P003C01-SCONNA
GND                      J2               119      SCONN288_ADR50001P003C01-SCONNA
GND                      J2               121      SCONN288_ADR50001P003C01-SCONNA
GND                      J2               123      SCONN288_ADR50001P003C01-SCONNA
GND                      J2               125      SCONN288_ADR50001P003C01-SCONNA
GND                      J2               128      SCONN288_ADR50001P003C01-SCONNA
GND                      J2               130      SCONN288_ADR50001P003C01-SCONNA
GND                      J2               132      SCONN288_ADR50001P003C01-SCONNA
GND                      J2               134      SCONN288_ADR50001P003C01-SCONNA
GND                      J2               136      SCONN288_ADR50001P003C01-SCONNA
GND                      J2               139      SCONN288_ADR50001P003C01-SCONNA
GND                      J2               141      SCONN288_ADR50001P003C01-SCONNA
GND                      J2               143      SCONN288_ADR50001P003C01-SCONNA
GND                      J2               151      SCONN288_ADR50001P003C01-SCONNA
GND                      J2               153      SCONN288_ADR50001P003C01-SCONNA
GND                      J2               155      SCONN288_ADR50001P003C01-SCONNA
GND                      J2               158      SCONN288_ADR50001P003C01-SCONNA
GND                      J2               160      SCONN288_ADR50001P003C01-SCONNA
GND                      J2               162      SCONN288_ADR50001P003C01-SCONNA
GND                      J2               164      SCONN288_ADR50001P003C01-SCONNA
GND                      J2               166      SCONN288_ADR50001P003C01-SCONNA
GND                      J2               169      SCONN288_ADR50001P003C01-SCONNA
GND                      J2               171      SCONN288_ADR50001P003C01-SCONNA
GND                      J2               173      SCONN288_ADR50001P003C01-SCONNA
GND                      J2               175      SCONN288_ADR50001P003C01-SCONNA
GND                      J2               177      SCONN288_ADR50001P003C01-SCONNA
GND                      J2               180      SCONN288_ADR50001P003C01-SCONNA
GND                      J2               182      SCONN288_ADR50001P003C01-SCONNA
GND                      J2               184      SCONN288_ADR50001P003C01-SCONNA
GND                      J2               186      SCONN288_ADR50001P003C01-SCONNA
GND                      J2               188      SCONN288_ADR50001P003C01-SCONNA
GND                      J2               191      SCONN288_ADR50001P003C01-SCONNA
GND                      J2               193      SCONN288_ADR50001P003C01-SCONNA
GND                      J2               195      SCONN288_ADR50001P003C01-SCONNA
GND                      J2               197      SCONN288_ADR50001P003C01-SCONNA
GND                      J2               199      SCONN288_ADR50001P003C01-SCONNA
GND                      J2               202      SCONN288_ADR50001P003C01-SCONNA
GND                      J2               204      SCONN288_ADR50001P003C01-SCONNA
GND                      J2               206      SCONN288_ADR50001P003C01-SCONNA
GND                      J2               208      SCONN288_ADR50001P003C01-SCONNA
GND                      J2               210      SCONN288_ADR50001P003C01-SCONNA
GND                      J2               212      SCONN288_ADR50001P003C01-SCONNA
GND                      J2               214      SCONN288_ADR50001P003C01-SCONNA
GND                      J2               216      SCONN288_ADR50001P003C01-SCONNA
GND                      J2               219      SCONN288_ADR50001P003C01-SCONNA
GND                      J2               222      SCONN288_ADR50001P003C01-SCONNA
GND                      J2               224      SCONN288_ADR50001P003C01-SCONNA
GND                      J2               226      SCONN288_ADR50001P003C01-SCONNA
GND                      J2               228      SCONN288_ADR50001P003C01-SCONNA
GND                      J2               230      SCONN288_ADR50001P003C01-SCONNA
GND                      J2               233      SCONN288_ADR50001P003C01-SCONNA
GND                      J2               235      SCONN288_ADR50001P003C01-SCONNA
GND                      J2               237      SCONN288_ADR50001P003C01-SCONNA
GND                      J2               240      SCONN288_ADR50001P003C01-SCONNA
GND                      J2               242      SCONN288_ADR50001P003C01-SCONNA
GND                      J2               244      SCONN288_ADR50001P003C01-SCONNA
GND                      J2               246      SCONN288_ADR50001P003C01-SCONNA
GND                      J2               248      SCONN288_ADR50001P003C01-SCONNA
GND                      J2               251      SCONN288_ADR50001P003C01-SCONNA
GND                      J2               253      SCONN288_ADR50001P003C01-SCONNA
GND                      J2               255      SCONN288_ADR50001P003C01-SCONNA
GND                      J2               257      SCONN288_ADR50001P003C01-SCONNA
GND                      J2               259      SCONN288_ADR50001P003C01-SCONNA
GND                      J2               262      SCONN288_ADR50001P003C01-SCONNA
GND                      J2               264      SCONN288_ADR50001P003C01-SCONNA
GND                      J2               266      SCONN288_ADR50001P003C01-SCONNA
GND                      J2               268      SCONN288_ADR50001P003C01-SCONNA
GND                      J2               270      SCONN288_ADR50001P003C01-SCONNA
GND                      J2               273      SCONN288_ADR50001P003C01-SCONNA
GND                      J2               275      SCONN288_ADR50001P003C01-SCONNA
GND                      J2               277      SCONN288_ADR50001P003C01-SCONNA
GND                      J2               279      SCONN288_ADR50001P003C01-SCONNA
GND                      J2               281      SCONN288_ADR50001P003C01-SCONNA
GND                      J2               284      SCONN288_ADR50001P003C01-SCONNA
GND                      J2               286      SCONN288_ADR50001P003C01-SCONNA
GND                      J2               288      SCONN288_ADR50001P003C01-SCONNA
GND                      J2               G1       SCONN288_ADR50001P003C01-SCONNA
GND                      J2               G2       SCONN288_ADR50001P003C01-SCONNA
GND                      J2               G3       SCONN288_ADR50001P003C01-SCONNA
GND                      J3               6        SCONN288_ADR50001P013C01-SCONNA
GND                      J3               8        SCONN288_ADR50001P013C01-SCONNA
GND                      J3               10       SCONN288_ADR50001P013C01-SCONNA
GND                      J3               13       SCONN288_ADR50001P013C01-SCONNA
GND                      J3               15       SCONN288_ADR50001P013C01-SCONNA
GND                      J3               17       SCONN288_ADR50001P013C01-SCONNA
GND                      J3               19       SCONN288_ADR50001P013C01-SCONNA
GND                      J3               21       SCONN288_ADR50001P013C01-SCONNA
GND                      J3               24       SCONN288_ADR50001P013C01-SCONNA
GND                      J3               26       SCONN288_ADR50001P013C01-SCONNA
GND                      J3               28       SCONN288_ADR50001P013C01-SCONNA
GND                      J3               30       SCONN288_ADR50001P013C01-SCONNA
GND                      J3               32       SCONN288_ADR50001P013C01-SCONNA
GND                      J3               35       SCONN288_ADR50001P013C01-SCONNA
GND                      J3               37       SCONN288_ADR50001P013C01-SCONNA
GND                      J3               39       SCONN288_ADR50001P013C01-SCONNA
GND                      J3               41       SCONN288_ADR50001P013C01-SCONNA
GND                      J3               43       SCONN288_ADR50001P013C01-SCONNA
GND                      J3               46       SCONN288_ADR50001P013C01-SCONNA
GND                      J3               48       SCONN288_ADR50001P013C01-SCONNA
GND                      J3               50       SCONN288_ADR50001P013C01-SCONNA
GND                      J3               52       SCONN288_ADR50001P013C01-SCONNA
GND                      J3               54       SCONN288_ADR50001P013C01-SCONNA
GND                      J3               57       SCONN288_ADR50001P013C01-SCONNA
GND                      J3               59       SCONN288_ADR50001P013C01-SCONNA
GND                      J3               61       SCONN288_ADR50001P013C01-SCONNA
GND                      J3               63       SCONN288_ADR50001P013C01-SCONNA
GND                      J3               65       SCONN288_ADR50001P013C01-SCONNA
GND                      J3               67       SCONN288_ADR50001P013C01-SCONNA
GND                      J3               69       SCONN288_ADR50001P013C01-SCONNA
GND                      J3               71       SCONN288_ADR50001P013C01-SCONNA
GND                      J3               73       SCONN288_ADR50001P013C01-SCONNA
GND                      J3               75       SCONN288_ADR50001P013C01-SCONNA
GND                      J3               77       SCONN288_ADR50001P013C01-SCONNA
GND                      J3               79       SCONN288_ADR50001P013C01-SCONNA
GND                      J3               81       SCONN288_ADR50001P013C01-SCONNA
GND                      J3               83       SCONN288_ADR50001P013C01-SCONNA
GND                      J3               85       SCONN288_ADR50001P013C01-SCONNA
GND                      J3               88       SCONN288_ADR50001P013C01-SCONNA
GND                      J3               90       SCONN288_ADR50001P013C01-SCONNA
GND                      J3               92       SCONN288_ADR50001P013C01-SCONNA
GND                      J3               95       SCONN288_ADR50001P013C01-SCONNA
GND                      J3               97       SCONN288_ADR50001P013C01-SCONNA
GND                      J3               99       SCONN288_ADR50001P013C01-SCONNA
GND                      J3               101      SCONN288_ADR50001P013C01-SCONNA
GND                      J3               103      SCONN288_ADR50001P013C01-SCONNA
GND                      J3               106      SCONN288_ADR50001P013C01-SCONNA
GND                      J3               108      SCONN288_ADR50001P013C01-SCONNA
GND                      J3               110      SCONN288_ADR50001P013C01-SCONNA
GND                      J3               112      SCONN288_ADR50001P013C01-SCONNA
GND                      J3               114      SCONN288_ADR50001P013C01-SCONNA
GND                      J3               117      SCONN288_ADR50001P013C01-SCONNA
GND                      J3               119      SCONN288_ADR50001P013C01-SCONNA
GND                      J3               121      SCONN288_ADR50001P013C01-SCONNA
GND                      J3               123      SCONN288_ADR50001P013C01-SCONNA
GND                      J3               125      SCONN288_ADR50001P013C01-SCONNA
GND                      J3               128      SCONN288_ADR50001P013C01-SCONNA
GND                      J3               130      SCONN288_ADR50001P013C01-SCONNA
GND                      J3               132      SCONN288_ADR50001P013C01-SCONNA
GND                      J3               134      SCONN288_ADR50001P013C01-SCONNA
GND                      J3               136      SCONN288_ADR50001P013C01-SCONNA
GND                      J3               139      SCONN288_ADR50001P013C01-SCONNA
GND                      J3               141      SCONN288_ADR50001P013C01-SCONNA
GND                      J3               143      SCONN288_ADR50001P013C01-SCONNA
GND                      J3               151      SCONN288_ADR50001P013C01-SCONNA
GND                      J3               153      SCONN288_ADR50001P013C01-SCONNA
GND                      J3               155      SCONN288_ADR50001P013C01-SCONNA
GND                      J3               158      SCONN288_ADR50001P013C01-SCONNA
GND                      J3               160      SCONN288_ADR50001P013C01-SCONNA
GND                      J3               162      SCONN288_ADR50001P013C01-SCONNA
GND                      J3               164      SCONN288_ADR50001P013C01-SCONNA
GND                      J3               166      SCONN288_ADR50001P013C01-SCONNA
GND                      J3               169      SCONN288_ADR50001P013C01-SCONNA
GND                      J3               171      SCONN288_ADR50001P013C01-SCONNA
GND                      J3               173      SCONN288_ADR50001P013C01-SCONNA
GND                      J3               175      SCONN288_ADR50001P013C01-SCONNA
GND                      J3               177      SCONN288_ADR50001P013C01-SCONNA
GND                      J3               180      SCONN288_ADR50001P013C01-SCONNA
GND                      J3               182      SCONN288_ADR50001P013C01-SCONNA
GND                      J3               184      SCONN288_ADR50001P013C01-SCONNA
GND                      J3               186      SCONN288_ADR50001P013C01-SCONNA
GND                      J3               188      SCONN288_ADR50001P013C01-SCONNA
GND                      J3               191      SCONN288_ADR50001P013C01-SCONNA
GND                      J3               193      SCONN288_ADR50001P013C01-SCONNA
GND                      J3               195      SCONN288_ADR50001P013C01-SCONNA
GND                      J3               197      SCONN288_ADR50001P013C01-SCONNA
GND                      J3               199      SCONN288_ADR50001P013C01-SCONNA
GND                      J3               202      SCONN288_ADR50001P013C01-SCONNA
GND                      J3               204      SCONN288_ADR50001P013C01-SCONNA
GND                      J3               206      SCONN288_ADR50001P013C01-SCONNA
GND                      J3               208      SCONN288_ADR50001P013C01-SCONNA
GND                      J3               210      SCONN288_ADR50001P013C01-SCONNA
GND                      J3               212      SCONN288_ADR50001P013C01-SCONNA
GND                      J3               214      SCONN288_ADR50001P013C01-SCONNA
GND                      J3               216      SCONN288_ADR50001P013C01-SCONNA
GND                      J3               219      SCONN288_ADR50001P013C01-SCONNA
GND                      J3               222      SCONN288_ADR50001P013C01-SCONNA
GND                      J3               224      SCONN288_ADR50001P013C01-SCONNA
GND                      J3               226      SCONN288_ADR50001P013C01-SCONNA
GND                      J3               228      SCONN288_ADR50001P013C01-SCONNA
GND                      J3               230      SCONN288_ADR50001P013C01-SCONNA
GND                      J3               233      SCONN288_ADR50001P013C01-SCONNA
GND                      J3               235      SCONN288_ADR50001P013C01-SCONNA
GND                      J3               237      SCONN288_ADR50001P013C01-SCONNA
GND                      J3               240      SCONN288_ADR50001P013C01-SCONNA
GND                      J3               242      SCONN288_ADR50001P013C01-SCONNA
GND                      J3               244      SCONN288_ADR50001P013C01-SCONNA
GND                      J3               246      SCONN288_ADR50001P013C01-SCONNA
GND                      J3               248      SCONN288_ADR50001P013C01-SCONNA
GND                      J3               251      SCONN288_ADR50001P013C01-SCONNA
GND                      J3               253      SCONN288_ADR50001P013C01-SCONNA
GND                      J3               255      SCONN288_ADR50001P013C01-SCONNA
GND                      J3               257      SCONN288_ADR50001P013C01-SCONNA
GND                      J3               259      SCONN288_ADR50001P013C01-SCONNA
GND                      J3               262      SCONN288_ADR50001P013C01-SCONNA
GND                      J3               264      SCONN288_ADR50001P013C01-SCONNA
GND                      J3               266      SCONN288_ADR50001P013C01-SCONNA
GND                      J3               268      SCONN288_ADR50001P013C01-SCONNA
GND                      J3               270      SCONN288_ADR50001P013C01-SCONNA
GND                      J3               273      SCONN288_ADR50001P013C01-SCONNA
GND                      J3               275      SCONN288_ADR50001P013C01-SCONNA
GND                      J3               277      SCONN288_ADR50001P013C01-SCONNA
GND                      J3               279      SCONN288_ADR50001P013C01-SCONNA
GND                      J3               281      SCONN288_ADR50001P013C01-SCONNA
GND                      J3               284      SCONN288_ADR50001P013C01-SCONNA
GND                      J3               286      SCONN288_ADR50001P013C01-SCONNA
GND                      J3               288      SCONN288_ADR50001P013C01-SCONNA
GND                      J3               G1       SCONN288_ADR50001P013C01-SCONNA
GND                      J3               G2       SCONN288_ADR50001P013C01-SCONNA
GND                      J3               G3       SCONN288_ADR50001P013C01-SCONNA
GND                      J4               6        SCONN288_ADR50001P003C01-SCONNA
GND                      J4               8        SCONN288_ADR50001P003C01-SCONNA
GND                      J4               10       SCONN288_ADR50001P003C01-SCONNA
GND                      J4               13       SCONN288_ADR50001P003C01-SCONNA
GND                      J4               15       SCONN288_ADR50001P003C01-SCONNA
GND                      J4               17       SCONN288_ADR50001P003C01-SCONNA
GND                      J4               19       SCONN288_ADR50001P003C01-SCONNA
GND                      J4               21       SCONN288_ADR50001P003C01-SCONNA
GND                      J4               24       SCONN288_ADR50001P003C01-SCONNA
GND                      J4               26       SCONN288_ADR50001P003C01-SCONNA
GND                      J4               28       SCONN288_ADR50001P003C01-SCONNA
GND                      J4               30       SCONN288_ADR50001P003C01-SCONNA
GND                      J4               32       SCONN288_ADR50001P003C01-SCONNA
GND                      J4               35       SCONN288_ADR50001P003C01-SCONNA
GND                      J4               37       SCONN288_ADR50001P003C01-SCONNA
GND                      J4               39       SCONN288_ADR50001P003C01-SCONNA
GND                      J4               41       SCONN288_ADR50001P003C01-SCONNA
GND                      J4               43       SCONN288_ADR50001P003C01-SCONNA
GND                      J4               46       SCONN288_ADR50001P003C01-SCONNA
GND                      J4               48       SCONN288_ADR50001P003C01-SCONNA
GND                      J4               50       SCONN288_ADR50001P003C01-SCONNA
GND                      J4               52       SCONN288_ADR50001P003C01-SCONNA
GND                      J4               54       SCONN288_ADR50001P003C01-SCONNA
GND                      J4               57       SCONN288_ADR50001P003C01-SCONNA
GND                      J4               59       SCONN288_ADR50001P003C01-SCONNA
GND                      J4               61       SCONN288_ADR50001P003C01-SCONNA
GND                      J4               63       SCONN288_ADR50001P003C01-SCONNA
GND                      J4               65       SCONN288_ADR50001P003C01-SCONNA
GND                      J4               67       SCONN288_ADR50001P003C01-SCONNA
GND                      J4               69       SCONN288_ADR50001P003C01-SCONNA
GND                      J4               71       SCONN288_ADR50001P003C01-SCONNA
GND                      J4               73       SCONN288_ADR50001P003C01-SCONNA
GND                      J4               75       SCONN288_ADR50001P003C01-SCONNA
GND                      J4               77       SCONN288_ADR50001P003C01-SCONNA
GND                      J4               79       SCONN288_ADR50001P003C01-SCONNA
GND                      J4               81       SCONN288_ADR50001P003C01-SCONNA
GND                      J4               83       SCONN288_ADR50001P003C01-SCONNA
GND                      J4               85       SCONN288_ADR50001P003C01-SCONNA
GND                      J4               88       SCONN288_ADR50001P003C01-SCONNA
GND                      J4               90       SCONN288_ADR50001P003C01-SCONNA
GND                      J4               92       SCONN288_ADR50001P003C01-SCONNA
GND                      J4               95       SCONN288_ADR50001P003C01-SCONNA
GND                      J4               97       SCONN288_ADR50001P003C01-SCONNA
GND                      J4               99       SCONN288_ADR50001P003C01-SCONNA
GND                      J4               101      SCONN288_ADR50001P003C01-SCONNA
GND                      J4               103      SCONN288_ADR50001P003C01-SCONNA
GND                      J4               106      SCONN288_ADR50001P003C01-SCONNA
GND                      J4               108      SCONN288_ADR50001P003C01-SCONNA
GND                      J4               110      SCONN288_ADR50001P003C01-SCONNA
GND                      J4               112      SCONN288_ADR50001P003C01-SCONNA
GND                      J4               114      SCONN288_ADR50001P003C01-SCONNA
GND                      J4               117      SCONN288_ADR50001P003C01-SCONNA
GND                      J4               119      SCONN288_ADR50001P003C01-SCONNA
GND                      J4               121      SCONN288_ADR50001P003C01-SCONNA
GND                      J4               123      SCONN288_ADR50001P003C01-SCONNA
GND                      J4               125      SCONN288_ADR50001P003C01-SCONNA
GND                      J4               128      SCONN288_ADR50001P003C01-SCONNA
GND                      J4               130      SCONN288_ADR50001P003C01-SCONNA
GND                      J4               132      SCONN288_ADR50001P003C01-SCONNA
GND                      J4               134      SCONN288_ADR50001P003C01-SCONNA
GND                      J4               136      SCONN288_ADR50001P003C01-SCONNA
GND                      J4               139      SCONN288_ADR50001P003C01-SCONNA
GND                      J4               141      SCONN288_ADR50001P003C01-SCONNA
GND                      J4               143      SCONN288_ADR50001P003C01-SCONNA
GND                      J4               151      SCONN288_ADR50001P003C01-SCONNA
GND                      J4               153      SCONN288_ADR50001P003C01-SCONNA
GND                      J4               155      SCONN288_ADR50001P003C01-SCONNA
GND                      J4               158      SCONN288_ADR50001P003C01-SCONNA
GND                      J4               160      SCONN288_ADR50001P003C01-SCONNA
GND                      J4               162      SCONN288_ADR50001P003C01-SCONNA
GND                      J4               164      SCONN288_ADR50001P003C01-SCONNA
GND                      J4               166      SCONN288_ADR50001P003C01-SCONNA
GND                      J4               169      SCONN288_ADR50001P003C01-SCONNA
GND                      J4               171      SCONN288_ADR50001P003C01-SCONNA
GND                      J4               173      SCONN288_ADR50001P003C01-SCONNA
GND                      J4               175      SCONN288_ADR50001P003C01-SCONNA
GND                      J4               177      SCONN288_ADR50001P003C01-SCONNA
GND                      J4               180      SCONN288_ADR50001P003C01-SCONNA
GND                      J4               182      SCONN288_ADR50001P003C01-SCONNA
GND                      J4               184      SCONN288_ADR50001P003C01-SCONNA
GND                      J4               186      SCONN288_ADR50001P003C01-SCONNA
GND                      J4               188      SCONN288_ADR50001P003C01-SCONNA
GND                      J4               191      SCONN288_ADR50001P003C01-SCONNA
GND                      J4               193      SCONN288_ADR50001P003C01-SCONNA
GND                      J4               195      SCONN288_ADR50001P003C01-SCONNA
GND                      J4               197      SCONN288_ADR50001P003C01-SCONNA
GND                      J4               199      SCONN288_ADR50001P003C01-SCONNA
GND                      J4               202      SCONN288_ADR50001P003C01-SCONNA
GND                      J4               204      SCONN288_ADR50001P003C01-SCONNA
GND                      J4               206      SCONN288_ADR50001P003C01-SCONNA
GND                      J4               208      SCONN288_ADR50001P003C01-SCONNA
GND                      J4               210      SCONN288_ADR50001P003C01-SCONNA
GND                      J4               212      SCONN288_ADR50001P003C01-SCONNA
GND                      J4               214      SCONN288_ADR50001P003C01-SCONNA
GND                      J4               216      SCONN288_ADR50001P003C01-SCONNA
GND                      J4               219      SCONN288_ADR50001P003C01-SCONNA
GND                      J4               222      SCONN288_ADR50001P003C01-SCONNA
GND                      J4               224      SCONN288_ADR50001P003C01-SCONNA
GND                      J4               226      SCONN288_ADR50001P003C01-SCONNA
GND                      J4               228      SCONN288_ADR50001P003C01-SCONNA
GND                      J4               230      SCONN288_ADR50001P003C01-SCONNA
GND                      J4               233      SCONN288_ADR50001P003C01-SCONNA
GND                      J4               235      SCONN288_ADR50001P003C01-SCONNA
GND                      J4               237      SCONN288_ADR50001P003C01-SCONNA
GND                      J4               240      SCONN288_ADR50001P003C01-SCONNA
GND                      J4               242      SCONN288_ADR50001P003C01-SCONNA
GND                      J4               244      SCONN288_ADR50001P003C01-SCONNA
GND                      J4               246      SCONN288_ADR50001P003C01-SCONNA
GND                      J4               248      SCONN288_ADR50001P003C01-SCONNA
GND                      J4               251      SCONN288_ADR50001P003C01-SCONNA
GND                      J4               253      SCONN288_ADR50001P003C01-SCONNA
GND                      J4               255      SCONN288_ADR50001P003C01-SCONNA
GND                      J4               257      SCONN288_ADR50001P003C01-SCONNA
GND                      J4               259      SCONN288_ADR50001P003C01-SCONNA
GND                      J4               262      SCONN288_ADR50001P003C01-SCONNA
GND                      J4               264      SCONN288_ADR50001P003C01-SCONNA
GND                      J4               266      SCONN288_ADR50001P003C01-SCONNA
GND                      J4               268      SCONN288_ADR50001P003C01-SCONNA
GND                      J4               270      SCONN288_ADR50001P003C01-SCONNA
GND                      J4               273      SCONN288_ADR50001P003C01-SCONNA
GND                      J4               275      SCONN288_ADR50001P003C01-SCONNA
GND                      J4               277      SCONN288_ADR50001P003C01-SCONNA
GND                      J4               279      SCONN288_ADR50001P003C01-SCONNA
GND                      J4               281      SCONN288_ADR50001P003C01-SCONNA
GND                      J4               284      SCONN288_ADR50001P003C01-SCONNA
GND                      J4               286      SCONN288_ADR50001P003C01-SCONNA
GND                      J4               288      SCONN288_ADR50001P003C01-SCONNA
GND                      J4               G1       SCONN288_ADR50001P003C01-SCONNA
GND                      J4               G2       SCONN288_ADR50001P003C01-SCONNA
GND                      J4               G3       SCONN288_ADR50001P003C01-SCONNA
GND                      J5               6        SCONN288_ADR50001P013C01-SCONNA
GND                      J5               8        SCONN288_ADR50001P013C01-SCONNA
GND                      J5               10       SCONN288_ADR50001P013C01-SCONNA
GND                      J5               13       SCONN288_ADR50001P013C01-SCONNA
GND                      J5               15       SCONN288_ADR50001P013C01-SCONNA
GND                      J5               17       SCONN288_ADR50001P013C01-SCONNA
GND                      J5               19       SCONN288_ADR50001P013C01-SCONNA
GND                      J5               21       SCONN288_ADR50001P013C01-SCONNA
GND                      J5               24       SCONN288_ADR50001P013C01-SCONNA
GND                      J5               26       SCONN288_ADR50001P013C01-SCONNA
GND                      J5               28       SCONN288_ADR50001P013C01-SCONNA
GND                      J5               30       SCONN288_ADR50001P013C01-SCONNA
GND                      J5               32       SCONN288_ADR50001P013C01-SCONNA
GND                      J5               35       SCONN288_ADR50001P013C01-SCONNA
GND                      J5               37       SCONN288_ADR50001P013C01-SCONNA
GND                      J5               39       SCONN288_ADR50001P013C01-SCONNA
GND                      J5               41       SCONN288_ADR50001P013C01-SCONNA
GND                      J5               43       SCONN288_ADR50001P013C01-SCONNA
GND                      J5               46       SCONN288_ADR50001P013C01-SCONNA
GND                      J5               48       SCONN288_ADR50001P013C01-SCONNA
GND                      J5               50       SCONN288_ADR50001P013C01-SCONNA
GND                      J5               52       SCONN288_ADR50001P013C01-SCONNA
GND                      J5               54       SCONN288_ADR50001P013C01-SCONNA
GND                      J5               57       SCONN288_ADR50001P013C01-SCONNA
GND                      J5               59       SCONN288_ADR50001P013C01-SCONNA
GND                      J5               61       SCONN288_ADR50001P013C01-SCONNA
GND                      J5               63       SCONN288_ADR50001P013C01-SCONNA
GND                      J5               65       SCONN288_ADR50001P013C01-SCONNA
GND                      J5               67       SCONN288_ADR50001P013C01-SCONNA
GND                      J5               69       SCONN288_ADR50001P013C01-SCONNA
GND                      J5               71       SCONN288_ADR50001P013C01-SCONNA
GND                      J5               73       SCONN288_ADR50001P013C01-SCONNA
GND                      J5               75       SCONN288_ADR50001P013C01-SCONNA
GND                      J5               77       SCONN288_ADR50001P013C01-SCONNA
GND                      J5               79       SCONN288_ADR50001P013C01-SCONNA
GND                      J5               81       SCONN288_ADR50001P013C01-SCONNA
GND                      J5               83       SCONN288_ADR50001P013C01-SCONNA
GND                      J5               85       SCONN288_ADR50001P013C01-SCONNA
GND                      J5               88       SCONN288_ADR50001P013C01-SCONNA
GND                      J5               90       SCONN288_ADR50001P013C01-SCONNA
GND                      J5               92       SCONN288_ADR50001P013C01-SCONNA
GND                      J5               95       SCONN288_ADR50001P013C01-SCONNA
GND                      J5               97       SCONN288_ADR50001P013C01-SCONNA
GND                      J5               99       SCONN288_ADR50001P013C01-SCONNA
GND                      J5               101      SCONN288_ADR50001P013C01-SCONNA
GND                      J5               103      SCONN288_ADR50001P013C01-SCONNA
GND                      J5               106      SCONN288_ADR50001P013C01-SCONNA
GND                      J5               108      SCONN288_ADR50001P013C01-SCONNA
GND                      J5               110      SCONN288_ADR50001P013C01-SCONNA
GND                      J5               112      SCONN288_ADR50001P013C01-SCONNA
GND                      J5               114      SCONN288_ADR50001P013C01-SCONNA
GND                      J5               117      SCONN288_ADR50001P013C01-SCONNA
GND                      J5               119      SCONN288_ADR50001P013C01-SCONNA
GND                      J5               121      SCONN288_ADR50001P013C01-SCONNA
GND                      J5               123      SCONN288_ADR50001P013C01-SCONNA
GND                      J5               125      SCONN288_ADR50001P013C01-SCONNA
GND                      J5               128      SCONN288_ADR50001P013C01-SCONNA
GND                      J5               130      SCONN288_ADR50001P013C01-SCONNA
GND                      J5               132      SCONN288_ADR50001P013C01-SCONNA
GND                      J5               134      SCONN288_ADR50001P013C01-SCONNA
GND                      J5               136      SCONN288_ADR50001P013C01-SCONNA
GND                      J5               139      SCONN288_ADR50001P013C01-SCONNA
GND                      J5               141      SCONN288_ADR50001P013C01-SCONNA
GND                      J5               143      SCONN288_ADR50001P013C01-SCONNA
GND                      J5               151      SCONN288_ADR50001P013C01-SCONNA
GND                      J5               153      SCONN288_ADR50001P013C01-SCONNA
GND                      J5               155      SCONN288_ADR50001P013C01-SCONNA
GND                      J5               158      SCONN288_ADR50001P013C01-SCONNA
GND                      J5               160      SCONN288_ADR50001P013C01-SCONNA
GND                      J5               162      SCONN288_ADR50001P013C01-SCONNA
GND                      J5               164      SCONN288_ADR50001P013C01-SCONNA
GND                      J5               166      SCONN288_ADR50001P013C01-SCONNA
GND                      J5               169      SCONN288_ADR50001P013C01-SCONNA
GND                      J5               171      SCONN288_ADR50001P013C01-SCONNA
GND                      J5               173      SCONN288_ADR50001P013C01-SCONNA
GND                      J5               175      SCONN288_ADR50001P013C01-SCONNA
GND                      J5               177      SCONN288_ADR50001P013C01-SCONNA
GND                      J5               180      SCONN288_ADR50001P013C01-SCONNA
GND                      J5               182      SCONN288_ADR50001P013C01-SCONNA
GND                      J5               184      SCONN288_ADR50001P013C01-SCONNA
GND                      J5               186      SCONN288_ADR50001P013C01-SCONNA
GND                      J5               188      SCONN288_ADR50001P013C01-SCONNA
GND                      J5               191      SCONN288_ADR50001P013C01-SCONNA
GND                      J5               193      SCONN288_ADR50001P013C01-SCONNA
GND                      J5               195      SCONN288_ADR50001P013C01-SCONNA
GND                      J5               197      SCONN288_ADR50001P013C01-SCONNA
GND                      J5               199      SCONN288_ADR50001P013C01-SCONNA
GND                      J5               202      SCONN288_ADR50001P013C01-SCONNA
GND                      J5               204      SCONN288_ADR50001P013C01-SCONNA
GND                      J5               206      SCONN288_ADR50001P013C01-SCONNA
GND                      J5               208      SCONN288_ADR50001P013C01-SCONNA
GND                      J5               210      SCONN288_ADR50001P013C01-SCONNA
GND                      J5               212      SCONN288_ADR50001P013C01-SCONNA
GND                      J5               214      SCONN288_ADR50001P013C01-SCONNA
GND                      J5               216      SCONN288_ADR50001P013C01-SCONNA
GND                      J5               219      SCONN288_ADR50001P013C01-SCONNA
GND                      J5               222      SCONN288_ADR50001P013C01-SCONNA
GND                      J5               224      SCONN288_ADR50001P013C01-SCONNA
GND                      J5               226      SCONN288_ADR50001P013C01-SCONNA
GND                      J5               228      SCONN288_ADR50001P013C01-SCONNA
GND                      J5               230      SCONN288_ADR50001P013C01-SCONNA
GND                      J5               233      SCONN288_ADR50001P013C01-SCONNA
GND                      J5               235      SCONN288_ADR50001P013C01-SCONNA
GND                      J5               237      SCONN288_ADR50001P013C01-SCONNA
GND                      J5               240      SCONN288_ADR50001P013C01-SCONNA
GND                      J5               242      SCONN288_ADR50001P013C01-SCONNA
GND                      J5               244      SCONN288_ADR50001P013C01-SCONNA
GND                      J5               246      SCONN288_ADR50001P013C01-SCONNA
GND                      J5               248      SCONN288_ADR50001P013C01-SCONNA
GND                      J5               251      SCONN288_ADR50001P013C01-SCONNA
GND                      J5               253      SCONN288_ADR50001P013C01-SCONNA
GND                      J5               255      SCONN288_ADR50001P013C01-SCONNA
GND                      J5               257      SCONN288_ADR50001P013C01-SCONNA
GND                      J5               259      SCONN288_ADR50001P013C01-SCONNA
GND                      J5               262      SCONN288_ADR50001P013C01-SCONNA
GND                      J5               264      SCONN288_ADR50001P013C01-SCONNA
GND                      J5               266      SCONN288_ADR50001P013C01-SCONNA
GND                      J5               268      SCONN288_ADR50001P013C01-SCONNA
GND                      J5               270      SCONN288_ADR50001P013C01-SCONNA
GND                      J5               273      SCONN288_ADR50001P013C01-SCONNA
GND                      J5               275      SCONN288_ADR50001P013C01-SCONNA
GND                      J5               277      SCONN288_ADR50001P013C01-SCONNA
GND                      J5               279      SCONN288_ADR50001P013C01-SCONNA
GND                      J5               281      SCONN288_ADR50001P013C01-SCONNA
GND                      J5               284      SCONN288_ADR50001P013C01-SCONNA
GND                      J5               286      SCONN288_ADR50001P013C01-SCONNA
GND                      J5               288      SCONN288_ADR50001P013C01-SCONNA
GND                      J5               G1       SCONN288_ADR50001P013C01-SCONNA
GND                      J5               G2       SCONN288_ADR50001P013C01-SCONNA
GND                      J5               G3       SCONN288_ADR50001P013C01-SCONNA
GND                      J6               6        SCONN288_ADR50001P003C01-SCONNA
GND                      J6               8        SCONN288_ADR50001P003C01-SCONNA
GND                      J6               10       SCONN288_ADR50001P003C01-SCONNA
GND                      J6               13       SCONN288_ADR50001P003C01-SCONNA
GND                      J6               15       SCONN288_ADR50001P003C01-SCONNA
GND                      J6               17       SCONN288_ADR50001P003C01-SCONNA
GND                      J6               19       SCONN288_ADR50001P003C01-SCONNA
GND                      J6               21       SCONN288_ADR50001P003C01-SCONNA
GND                      J6               24       SCONN288_ADR50001P003C01-SCONNA
GND                      J6               26       SCONN288_ADR50001P003C01-SCONNA
GND                      J6               28       SCONN288_ADR50001P003C01-SCONNA
GND                      J6               30       SCONN288_ADR50001P003C01-SCONNA
GND                      J6               32       SCONN288_ADR50001P003C01-SCONNA
GND                      J6               35       SCONN288_ADR50001P003C01-SCONNA
GND                      J6               37       SCONN288_ADR50001P003C01-SCONNA
GND                      J6               39       SCONN288_ADR50001P003C01-SCONNA
GND                      J6               41       SCONN288_ADR50001P003C01-SCONNA
GND                      J6               43       SCONN288_ADR50001P003C01-SCONNA
GND                      J6               46       SCONN288_ADR50001P003C01-SCONNA
GND                      J6               48       SCONN288_ADR50001P003C01-SCONNA
GND                      J6               50       SCONN288_ADR50001P003C01-SCONNA
GND                      J6               52       SCONN288_ADR50001P003C01-SCONNA
GND                      J6               54       SCONN288_ADR50001P003C01-SCONNA
GND                      J6               57       SCONN288_ADR50001P003C01-SCONNA
GND                      J6               59       SCONN288_ADR50001P003C01-SCONNA
GND                      J6               61       SCONN288_ADR50001P003C01-SCONNA
GND                      J6               63       SCONN288_ADR50001P003C01-SCONNA
GND                      J6               65       SCONN288_ADR50001P003C01-SCONNA
GND                      J6               67       SCONN288_ADR50001P003C01-SCONNA
GND                      J6               69       SCONN288_ADR50001P003C01-SCONNA
GND                      J6               71       SCONN288_ADR50001P003C01-SCONNA
GND                      J6               73       SCONN288_ADR50001P003C01-SCONNA
GND                      J6               75       SCONN288_ADR50001P003C01-SCONNA
GND                      J6               77       SCONN288_ADR50001P003C01-SCONNA
GND                      J6               79       SCONN288_ADR50001P003C01-SCONNA
GND                      J6               81       SCONN288_ADR50001P003C01-SCONNA
GND                      J6               83       SCONN288_ADR50001P003C01-SCONNA
GND                      J6               85       SCONN288_ADR50001P003C01-SCONNA
GND                      J6               88       SCONN288_ADR50001P003C01-SCONNA
GND                      J6               90       SCONN288_ADR50001P003C01-SCONNA
GND                      J6               92       SCONN288_ADR50001P003C01-SCONNA
GND                      J6               95       SCONN288_ADR50001P003C01-SCONNA
GND                      J6               97       SCONN288_ADR50001P003C01-SCONNA
GND                      J6               99       SCONN288_ADR50001P003C01-SCONNA
GND                      J6               101      SCONN288_ADR50001P003C01-SCONNA
GND                      J6               103      SCONN288_ADR50001P003C01-SCONNA
GND                      J6               106      SCONN288_ADR50001P003C01-SCONNA
GND                      J6               108      SCONN288_ADR50001P003C01-SCONNA
GND                      J6               110      SCONN288_ADR50001P003C01-SCONNA
GND                      J6               112      SCONN288_ADR50001P003C01-SCONNA
GND                      J6               114      SCONN288_ADR50001P003C01-SCONNA
GND                      J6               117      SCONN288_ADR50001P003C01-SCONNA
GND                      J6               119      SCONN288_ADR50001P003C01-SCONNA
GND                      J6               121      SCONN288_ADR50001P003C01-SCONNA
GND                      J6               123      SCONN288_ADR50001P003C01-SCONNA
GND                      J6               125      SCONN288_ADR50001P003C01-SCONNA
GND                      J6               128      SCONN288_ADR50001P003C01-SCONNA
GND                      J6               130      SCONN288_ADR50001P003C01-SCONNA
GND                      J6               132      SCONN288_ADR50001P003C01-SCONNA
GND                      J6               134      SCONN288_ADR50001P003C01-SCONNA
GND                      J6               136      SCONN288_ADR50001P003C01-SCONNA
GND                      J6               139      SCONN288_ADR50001P003C01-SCONNA
GND                      J6               141      SCONN288_ADR50001P003C01-SCONNA
GND                      J6               143      SCONN288_ADR50001P003C01-SCONNA
GND                      J6               151      SCONN288_ADR50001P003C01-SCONNA
GND                      J6               153      SCONN288_ADR50001P003C01-SCONNA
GND                      J6               155      SCONN288_ADR50001P003C01-SCONNA
GND                      J6               158      SCONN288_ADR50001P003C01-SCONNA
GND                      J6               160      SCONN288_ADR50001P003C01-SCONNA
GND                      J6               162      SCONN288_ADR50001P003C01-SCONNA
GND                      J6               164      SCONN288_ADR50001P003C01-SCONNA
GND                      J6               166      SCONN288_ADR50001P003C01-SCONNA
GND                      J6               169      SCONN288_ADR50001P003C01-SCONNA
GND                      J6               171      SCONN288_ADR50001P003C01-SCONNA
GND                      J6               173      SCONN288_ADR50001P003C01-SCONNA
GND                      J6               175      SCONN288_ADR50001P003C01-SCONNA
GND                      J6               177      SCONN288_ADR50001P003C01-SCONNA
GND                      J6               180      SCONN288_ADR50001P003C01-SCONNA
GND                      J6               182      SCONN288_ADR50001P003C01-SCONNA
GND                      J6               184      SCONN288_ADR50001P003C01-SCONNA
GND                      J6               186      SCONN288_ADR50001P003C01-SCONNA
GND                      J6               188      SCONN288_ADR50001P003C01-SCONNA
GND                      J6               191      SCONN288_ADR50001P003C01-SCONNA
GND                      J6               193      SCONN288_ADR50001P003C01-SCONNA
GND                      J6               195      SCONN288_ADR50001P003C01-SCONNA
GND                      J6               197      SCONN288_ADR50001P003C01-SCONNA
GND                      J6               199      SCONN288_ADR50001P003C01-SCONNA
GND                      J6               202      SCONN288_ADR50001P003C01-SCONNA
GND                      J6               204      SCONN288_ADR50001P003C01-SCONNA
GND                      J6               206      SCONN288_ADR50001P003C01-SCONNA
GND                      J6               208      SCONN288_ADR50001P003C01-SCONNA
GND                      J6               210      SCONN288_ADR50001P003C01-SCONNA
GND                      J6               212      SCONN288_ADR50001P003C01-SCONNA
GND                      J6               214      SCONN288_ADR50001P003C01-SCONNA
GND                      J6               216      SCONN288_ADR50001P003C01-SCONNA
GND                      J6               219      SCONN288_ADR50001P003C01-SCONNA
GND                      J6               222      SCONN288_ADR50001P003C01-SCONNA
GND                      J6               224      SCONN288_ADR50001P003C01-SCONNA
GND                      J6               226      SCONN288_ADR50001P003C01-SCONNA
GND                      J6               228      SCONN288_ADR50001P003C01-SCONNA
GND                      J6               230      SCONN288_ADR50001P003C01-SCONNA
GND                      J6               233      SCONN288_ADR50001P003C01-SCONNA
GND                      J6               235      SCONN288_ADR50001P003C01-SCONNA
GND                      J6               237      SCONN288_ADR50001P003C01-SCONNA
GND                      J6               240      SCONN288_ADR50001P003C01-SCONNA
GND                      J6               242      SCONN288_ADR50001P003C01-SCONNA
GND                      J6               244      SCONN288_ADR50001P003C01-SCONNA
GND                      J6               246      SCONN288_ADR50001P003C01-SCONNA
GND                      J6               248      SCONN288_ADR50001P003C01-SCONNA
GND                      J6               251      SCONN288_ADR50001P003C01-SCONNA
GND                      J6               253      SCONN288_ADR50001P003C01-SCONNA
GND                      J6               255      SCONN288_ADR50001P003C01-SCONNA
GND                      J6               257      SCONN288_ADR50001P003C01-SCONNA
GND                      J6               259      SCONN288_ADR50001P003C01-SCONNA
GND                      J6               262      SCONN288_ADR50001P003C01-SCONNA
GND                      J6               264      SCONN288_ADR50001P003C01-SCONNA
GND                      J6               266      SCONN288_ADR50001P003C01-SCONNA
GND                      J6               268      SCONN288_ADR50001P003C01-SCONNA
GND                      J6               270      SCONN288_ADR50001P003C01-SCONNA
GND                      J6               273      SCONN288_ADR50001P003C01-SCONNA
GND                      J6               275      SCONN288_ADR50001P003C01-SCONNA
GND                      J6               277      SCONN288_ADR50001P003C01-SCONNA
GND                      J6               279      SCONN288_ADR50001P003C01-SCONNA
GND                      J6               281      SCONN288_ADR50001P003C01-SCONNA
GND                      J6               284      SCONN288_ADR50001P003C01-SCONNA
GND                      J6               286      SCONN288_ADR50001P003C01-SCONNA
GND                      J6               288      SCONN288_ADR50001P003C01-SCONNA
GND                      J6               G1       SCONN288_ADR50001P003C01-SCONNA
GND                      J6               G2       SCONN288_ADR50001P003C01-SCONNA
GND                      J6               G3       SCONN288_ADR50001P003C01-SCONNA
GND                      J7               6        SCONN288_ADR50001P013C01-SCONNA
GND                      J7               8        SCONN288_ADR50001P013C01-SCONNA
GND                      J7               10       SCONN288_ADR50001P013C01-SCONNA
GND                      J7               13       SCONN288_ADR50001P013C01-SCONNA
GND                      J7               15       SCONN288_ADR50001P013C01-SCONNA
GND                      J7               17       SCONN288_ADR50001P013C01-SCONNA
GND                      J7               19       SCONN288_ADR50001P013C01-SCONNA
GND                      J7               21       SCONN288_ADR50001P013C01-SCONNA
GND                      J7               24       SCONN288_ADR50001P013C01-SCONNA
GND                      J7               26       SCONN288_ADR50001P013C01-SCONNA
GND                      J7               28       SCONN288_ADR50001P013C01-SCONNA
GND                      J7               30       SCONN288_ADR50001P013C01-SCONNA
GND                      J7               32       SCONN288_ADR50001P013C01-SCONNA
GND                      J7               35       SCONN288_ADR50001P013C01-SCONNA
GND                      J7               37       SCONN288_ADR50001P013C01-SCONNA
GND                      J7               39       SCONN288_ADR50001P013C01-SCONNA
GND                      J7               41       SCONN288_ADR50001P013C01-SCONNA
GND                      J7               43       SCONN288_ADR50001P013C01-SCONNA
GND                      J7               46       SCONN288_ADR50001P013C01-SCONNA
GND                      J7               48       SCONN288_ADR50001P013C01-SCONNA
GND                      J7               50       SCONN288_ADR50001P013C01-SCONNA
GND                      J7               52       SCONN288_ADR50001P013C01-SCONNA
GND                      J7               54       SCONN288_ADR50001P013C01-SCONNA
GND                      J7               57       SCONN288_ADR50001P013C01-SCONNA
GND                      J7               59       SCONN288_ADR50001P013C01-SCONNA
GND                      J7               61       SCONN288_ADR50001P013C01-SCONNA
GND                      J7               63       SCONN288_ADR50001P013C01-SCONNA
GND                      J7               65       SCONN288_ADR50001P013C01-SCONNA
GND                      J7               67       SCONN288_ADR50001P013C01-SCONNA
GND                      J7               69       SCONN288_ADR50001P013C01-SCONNA
GND                      J7               71       SCONN288_ADR50001P013C01-SCONNA
GND                      J7               73       SCONN288_ADR50001P013C01-SCONNA
GND                      J7               75       SCONN288_ADR50001P013C01-SCONNA
GND                      J7               77       SCONN288_ADR50001P013C01-SCONNA
GND                      J7               79       SCONN288_ADR50001P013C01-SCONNA
GND                      J7               81       SCONN288_ADR50001P013C01-SCONNA
GND                      J7               83       SCONN288_ADR50001P013C01-SCONNA
GND                      J7               85       SCONN288_ADR50001P013C01-SCONNA
GND                      J7               88       SCONN288_ADR50001P013C01-SCONNA
GND                      J7               90       SCONN288_ADR50001P013C01-SCONNA
GND                      J7               92       SCONN288_ADR50001P013C01-SCONNA
GND                      J7               95       SCONN288_ADR50001P013C01-SCONNA
GND                      J7               97       SCONN288_ADR50001P013C01-SCONNA
GND                      J7               99       SCONN288_ADR50001P013C01-SCONNA
GND                      J7               101      SCONN288_ADR50001P013C01-SCONNA
GND                      J7               103      SCONN288_ADR50001P013C01-SCONNA
GND                      J7               106      SCONN288_ADR50001P013C01-SCONNA
GND                      J7               108      SCONN288_ADR50001P013C01-SCONNA
GND                      J7               110      SCONN288_ADR50001P013C01-SCONNA
GND                      J7               112      SCONN288_ADR50001P013C01-SCONNA
GND                      J7               114      SCONN288_ADR50001P013C01-SCONNA
GND                      J7               117      SCONN288_ADR50001P013C01-SCONNA
GND                      J7               119      SCONN288_ADR50001P013C01-SCONNA
GND                      J7               121      SCONN288_ADR50001P013C01-SCONNA
GND                      J7               123      SCONN288_ADR50001P013C01-SCONNA
GND                      J7               125      SCONN288_ADR50001P013C01-SCONNA
GND                      J7               128      SCONN288_ADR50001P013C01-SCONNA
GND                      J7               130      SCONN288_ADR50001P013C01-SCONNA
GND                      J7               132      SCONN288_ADR50001P013C01-SCONNA
GND                      J7               134      SCONN288_ADR50001P013C01-SCONNA
GND                      J7               136      SCONN288_ADR50001P013C01-SCONNA
GND                      J7               139      SCONN288_ADR50001P013C01-SCONNA
GND                      J7               141      SCONN288_ADR50001P013C01-SCONNA
GND                      J7               143      SCONN288_ADR50001P013C01-SCONNA
GND                      J7               151      SCONN288_ADR50001P013C01-SCONNA
GND                      J7               153      SCONN288_ADR50001P013C01-SCONNA
GND                      J7               155      SCONN288_ADR50001P013C01-SCONNA
GND                      J7               158      SCONN288_ADR50001P013C01-SCONNA
GND                      J7               160      SCONN288_ADR50001P013C01-SCONNA
GND                      J7               162      SCONN288_ADR50001P013C01-SCONNA
GND                      J7               164      SCONN288_ADR50001P013C01-SCONNA
GND                      J7               166      SCONN288_ADR50001P013C01-SCONNA
GND                      J7               169      SCONN288_ADR50001P013C01-SCONNA
GND                      J7               171      SCONN288_ADR50001P013C01-SCONNA
GND                      J7               173      SCONN288_ADR50001P013C01-SCONNA
GND                      J7               175      SCONN288_ADR50001P013C01-SCONNA
GND                      J7               177      SCONN288_ADR50001P013C01-SCONNA
GND                      J7               180      SCONN288_ADR50001P013C01-SCONNA
GND                      J7               182      SCONN288_ADR50001P013C01-SCONNA
GND                      J7               184      SCONN288_ADR50001P013C01-SCONNA
GND                      J7               186      SCONN288_ADR50001P013C01-SCONNA
GND                      J7               188      SCONN288_ADR50001P013C01-SCONNA
GND                      J7               191      SCONN288_ADR50001P013C01-SCONNA
GND                      J7               193      SCONN288_ADR50001P013C01-SCONNA
GND                      J7               195      SCONN288_ADR50001P013C01-SCONNA
GND                      J7               197      SCONN288_ADR50001P013C01-SCONNA
GND                      J7               199      SCONN288_ADR50001P013C01-SCONNA
GND                      J7               202      SCONN288_ADR50001P013C01-SCONNA
GND                      J7               204      SCONN288_ADR50001P013C01-SCONNA
GND                      J7               206      SCONN288_ADR50001P013C01-SCONNA
GND                      J7               208      SCONN288_ADR50001P013C01-SCONNA
GND                      J7               210      SCONN288_ADR50001P013C01-SCONNA
GND                      J7               212      SCONN288_ADR50001P013C01-SCONNA
GND                      J7               214      SCONN288_ADR50001P013C01-SCONNA
GND                      J7               216      SCONN288_ADR50001P013C01-SCONNA
GND                      J7               219      SCONN288_ADR50001P013C01-SCONNA
GND                      J7               222      SCONN288_ADR50001P013C01-SCONNA
GND                      J7               224      SCONN288_ADR50001P013C01-SCONNA
GND                      J7               226      SCONN288_ADR50001P013C01-SCONNA
GND                      J7               228      SCONN288_ADR50001P013C01-SCONNA
GND                      J7               230      SCONN288_ADR50001P013C01-SCONNA
GND                      J7               233      SCONN288_ADR50001P013C01-SCONNA
GND                      J7               235      SCONN288_ADR50001P013C01-SCONNA
GND                      J7               237      SCONN288_ADR50001P013C01-SCONNA
GND                      J7               240      SCONN288_ADR50001P013C01-SCONNA
GND                      J7               242      SCONN288_ADR50001P013C01-SCONNA
GND                      J7               244      SCONN288_ADR50001P013C01-SCONNA
GND                      J7               246      SCONN288_ADR50001P013C01-SCONNA
GND                      J7               248      SCONN288_ADR50001P013C01-SCONNA
GND                      J7               251      SCONN288_ADR50001P013C01-SCONNA
GND                      J7               253      SCONN288_ADR50001P013C01-SCONNA
GND                      J7               255      SCONN288_ADR50001P013C01-SCONNA
GND                      J7               257      SCONN288_ADR50001P013C01-SCONNA
GND                      J7               259      SCONN288_ADR50001P013C01-SCONNA
GND                      J7               262      SCONN288_ADR50001P013C01-SCONNA
GND                      J7               264      SCONN288_ADR50001P013C01-SCONNA
GND                      J7               266      SCONN288_ADR50001P013C01-SCONNA
GND                      J7               268      SCONN288_ADR50001P013C01-SCONNA
GND                      J7               270      SCONN288_ADR50001P013C01-SCONNA
GND                      J7               273      SCONN288_ADR50001P013C01-SCONNA
GND                      J7               275      SCONN288_ADR50001P013C01-SCONNA
GND                      J7               277      SCONN288_ADR50001P013C01-SCONNA
GND                      J7               279      SCONN288_ADR50001P013C01-SCONNA
GND                      J7               281      SCONN288_ADR50001P013C01-SCONNA
GND                      J7               284      SCONN288_ADR50001P013C01-SCONNA
GND                      J7               286      SCONN288_ADR50001P013C01-SCONNA
GND                      J7               288      SCONN288_ADR50001P013C01-SCONNA
GND                      J7               G1       SCONN288_ADR50001P013C01-SCONNA
GND                      J7               G2       SCONN288_ADR50001P013C01-SCONNA
GND                      J7               G3       SCONN288_ADR50001P013C01-SCONNA
GND                      J8               6        SCONN288_ADR50001P003C01-SCONNA
GND                      J8               8        SCONN288_ADR50001P003C01-SCONNA
GND                      J8               10       SCONN288_ADR50001P003C01-SCONNA
GND                      J8               13       SCONN288_ADR50001P003C01-SCONNA
GND                      J8               15       SCONN288_ADR50001P003C01-SCONNA
GND                      J8               17       SCONN288_ADR50001P003C01-SCONNA
GND                      J8               19       SCONN288_ADR50001P003C01-SCONNA
GND                      J8               21       SCONN288_ADR50001P003C01-SCONNA
GND                      J8               24       SCONN288_ADR50001P003C01-SCONNA
GND                      J8               26       SCONN288_ADR50001P003C01-SCONNA
GND                      J8               28       SCONN288_ADR50001P003C01-SCONNA
GND                      J8               30       SCONN288_ADR50001P003C01-SCONNA
GND                      J8               32       SCONN288_ADR50001P003C01-SCONNA
GND                      J8               35       SCONN288_ADR50001P003C01-SCONNA
GND                      J8               37       SCONN288_ADR50001P003C01-SCONNA
GND                      J8               39       SCONN288_ADR50001P003C01-SCONNA
GND                      J8               41       SCONN288_ADR50001P003C01-SCONNA
GND                      J8               43       SCONN288_ADR50001P003C01-SCONNA
GND                      J8               46       SCONN288_ADR50001P003C01-SCONNA
GND                      J8               48       SCONN288_ADR50001P003C01-SCONNA
GND                      J8               50       SCONN288_ADR50001P003C01-SCONNA
GND                      J8               52       SCONN288_ADR50001P003C01-SCONNA
GND                      J8               54       SCONN288_ADR50001P003C01-SCONNA
GND                      J8               57       SCONN288_ADR50001P003C01-SCONNA
GND                      J8               59       SCONN288_ADR50001P003C01-SCONNA
GND                      J8               61       SCONN288_ADR50001P003C01-SCONNA
GND                      J8               63       SCONN288_ADR50001P003C01-SCONNA
GND                      J8               65       SCONN288_ADR50001P003C01-SCONNA
GND                      J8               67       SCONN288_ADR50001P003C01-SCONNA
GND                      J8               69       SCONN288_ADR50001P003C01-SCONNA
GND                      J8               71       SCONN288_ADR50001P003C01-SCONNA
GND                      J8               73       SCONN288_ADR50001P003C01-SCONNA
GND                      J8               75       SCONN288_ADR50001P003C01-SCONNA
GND                      J8               77       SCONN288_ADR50001P003C01-SCONNA
GND                      J8               79       SCONN288_ADR50001P003C01-SCONNA
GND                      J8               81       SCONN288_ADR50001P003C01-SCONNA
GND                      J8               83       SCONN288_ADR50001P003C01-SCONNA
GND                      J8               85       SCONN288_ADR50001P003C01-SCONNA
GND                      J8               88       SCONN288_ADR50001P003C01-SCONNA
GND                      J8               90       SCONN288_ADR50001P003C01-SCONNA
GND                      J8               92       SCONN288_ADR50001P003C01-SCONNA
GND                      J8               95       SCONN288_ADR50001P003C01-SCONNA
GND                      J8               97       SCONN288_ADR50001P003C01-SCONNA
GND                      J8               99       SCONN288_ADR50001P003C01-SCONNA
GND                      J8               101      SCONN288_ADR50001P003C01-SCONNA
GND                      J8               103      SCONN288_ADR50001P003C01-SCONNA
GND                      J8               106      SCONN288_ADR50001P003C01-SCONNA
GND                      J8               108      SCONN288_ADR50001P003C01-SCONNA
GND                      J8               110      SCONN288_ADR50001P003C01-SCONNA
GND                      J8               112      SCONN288_ADR50001P003C01-SCONNA
GND                      J8               114      SCONN288_ADR50001P003C01-SCONNA
GND                      J8               117      SCONN288_ADR50001P003C01-SCONNA
GND                      J8               119      SCONN288_ADR50001P003C01-SCONNA
GND                      J8               121      SCONN288_ADR50001P003C01-SCONNA
GND                      J8               123      SCONN288_ADR50001P003C01-SCONNA
GND                      J8               125      SCONN288_ADR50001P003C01-SCONNA
GND                      J8               128      SCONN288_ADR50001P003C01-SCONNA
GND                      J8               130      SCONN288_ADR50001P003C01-SCONNA
GND                      J8               132      SCONN288_ADR50001P003C01-SCONNA
GND                      J8               134      SCONN288_ADR50001P003C01-SCONNA
GND                      J8               136      SCONN288_ADR50001P003C01-SCONNA
GND                      J8               139      SCONN288_ADR50001P003C01-SCONNA
GND                      J8               141      SCONN288_ADR50001P003C01-SCONNA
GND                      J8               143      SCONN288_ADR50001P003C01-SCONNA
GND                      J8               151      SCONN288_ADR50001P003C01-SCONNA
GND                      J8               153      SCONN288_ADR50001P003C01-SCONNA
GND                      J8               155      SCONN288_ADR50001P003C01-SCONNA
GND                      J8               158      SCONN288_ADR50001P003C01-SCONNA
GND                      J8               160      SCONN288_ADR50001P003C01-SCONNA
GND                      J8               162      SCONN288_ADR50001P003C01-SCONNA
GND                      J8               164      SCONN288_ADR50001P003C01-SCONNA
GND                      J8               166      SCONN288_ADR50001P003C01-SCONNA
GND                      J8               169      SCONN288_ADR50001P003C01-SCONNA
GND                      J8               171      SCONN288_ADR50001P003C01-SCONNA
GND                      J8               173      SCONN288_ADR50001P003C01-SCONNA
GND                      J8               175      SCONN288_ADR50001P003C01-SCONNA
GND                      J8               177      SCONN288_ADR50001P003C01-SCONNA
GND                      J8               180      SCONN288_ADR50001P003C01-SCONNA
GND                      J8               182      SCONN288_ADR50001P003C01-SCONNA
GND                      J8               184      SCONN288_ADR50001P003C01-SCONNA
GND                      J8               186      SCONN288_ADR50001P003C01-SCONNA
GND                      J8               188      SCONN288_ADR50001P003C01-SCONNA
GND                      J8               191      SCONN288_ADR50001P003C01-SCONNA
GND                      J8               193      SCONN288_ADR50001P003C01-SCONNA
GND                      J8               195      SCONN288_ADR50001P003C01-SCONNA
GND                      J8               197      SCONN288_ADR50001P003C01-SCONNA
GND                      J8               199      SCONN288_ADR50001P003C01-SCONNA
GND                      J8               202      SCONN288_ADR50001P003C01-SCONNA
GND                      J8               204      SCONN288_ADR50001P003C01-SCONNA
GND                      J8               206      SCONN288_ADR50001P003C01-SCONNA
GND                      J8               208      SCONN288_ADR50001P003C01-SCONNA
GND                      J8               210      SCONN288_ADR50001P003C01-SCONNA
GND                      J8               212      SCONN288_ADR50001P003C01-SCONNA
GND                      J8               214      SCONN288_ADR50001P003C01-SCONNA
GND                      J8               216      SCONN288_ADR50001P003C01-SCONNA
GND                      J8               219      SCONN288_ADR50001P003C01-SCONNA
GND                      J8               222      SCONN288_ADR50001P003C01-SCONNA
GND                      J8               224      SCONN288_ADR50001P003C01-SCONNA
GND                      J8               226      SCONN288_ADR50001P003C01-SCONNA
GND                      J8               228      SCONN288_ADR50001P003C01-SCONNA
GND                      J8               230      SCONN288_ADR50001P003C01-SCONNA
GND                      J8               233      SCONN288_ADR50001P003C01-SCONNA
GND                      J8               235      SCONN288_ADR50001P003C01-SCONNA
GND                      J8               237      SCONN288_ADR50001P003C01-SCONNA
GND                      J8               240      SCONN288_ADR50001P003C01-SCONNA
GND                      J8               242      SCONN288_ADR50001P003C01-SCONNA
GND                      J8               244      SCONN288_ADR50001P003C01-SCONNA
GND                      J8               246      SCONN288_ADR50001P003C01-SCONNA
GND                      J8               248      SCONN288_ADR50001P003C01-SCONNA
GND                      J8               251      SCONN288_ADR50001P003C01-SCONNA
GND                      J8               253      SCONN288_ADR50001P003C01-SCONNA
GND                      J8               255      SCONN288_ADR50001P003C01-SCONNA
GND                      J8               257      SCONN288_ADR50001P003C01-SCONNA
GND                      J8               259      SCONN288_ADR50001P003C01-SCONNA
GND                      J8               262      SCONN288_ADR50001P003C01-SCONNA
GND                      J8               264      SCONN288_ADR50001P003C01-SCONNA
GND                      J8               266      SCONN288_ADR50001P003C01-SCONNA
GND                      J8               268      SCONN288_ADR50001P003C01-SCONNA
GND                      J8               270      SCONN288_ADR50001P003C01-SCONNA
GND                      J8               273      SCONN288_ADR50001P003C01-SCONNA
GND                      J8               275      SCONN288_ADR50001P003C01-SCONNA
GND                      J8               277      SCONN288_ADR50001P003C01-SCONNA
GND                      J8               279      SCONN288_ADR50001P003C01-SCONNA
GND                      J8               281      SCONN288_ADR50001P003C01-SCONNA
GND                      J8               284      SCONN288_ADR50001P003C01-SCONNA
GND                      J8               286      SCONN288_ADR50001P003C01-SCONNA
GND                      J8               288      SCONN288_ADR50001P003C01-SCONNA
GND                      J8               G1       SCONN288_ADR50001P003C01-SCONNA
GND                      J8               G2       SCONN288_ADR50001P003C01-SCONNA
GND                      J8               G3       SCONN288_ADR50001P003C01-SCONNA
GND                      J9               6        SCONN288_ADR50001P013C01-SCONNA
GND                      J9               8        SCONN288_ADR50001P013C01-SCONNA
GND                      J9               10       SCONN288_ADR50001P013C01-SCONNA
GND                      J9               13       SCONN288_ADR50001P013C01-SCONNA
GND                      J9               15       SCONN288_ADR50001P013C01-SCONNA
GND                      J9               17       SCONN288_ADR50001P013C01-SCONNA
GND                      J9               19       SCONN288_ADR50001P013C01-SCONNA
GND                      J9               21       SCONN288_ADR50001P013C01-SCONNA
GND                      J9               24       SCONN288_ADR50001P013C01-SCONNA
GND                      J9               26       SCONN288_ADR50001P013C01-SCONNA
GND                      J9               28       SCONN288_ADR50001P013C01-SCONNA
GND                      J9               30       SCONN288_ADR50001P013C01-SCONNA
GND                      J9               32       SCONN288_ADR50001P013C01-SCONNA
GND                      J9               35       SCONN288_ADR50001P013C01-SCONNA
GND                      J9               37       SCONN288_ADR50001P013C01-SCONNA
GND                      J9               39       SCONN288_ADR50001P013C01-SCONNA
GND                      J9               41       SCONN288_ADR50001P013C01-SCONNA
GND                      J9               43       SCONN288_ADR50001P013C01-SCONNA
GND                      J9               46       SCONN288_ADR50001P013C01-SCONNA
GND                      J9               48       SCONN288_ADR50001P013C01-SCONNA
GND                      J9               50       SCONN288_ADR50001P013C01-SCONNA
GND                      J9               52       SCONN288_ADR50001P013C01-SCONNA
GND                      J9               54       SCONN288_ADR50001P013C01-SCONNA
GND                      J9               57       SCONN288_ADR50001P013C01-SCONNA
GND                      J9               59       SCONN288_ADR50001P013C01-SCONNA
GND                      J9               61       SCONN288_ADR50001P013C01-SCONNA
GND                      J9               63       SCONN288_ADR50001P013C01-SCONNA
GND                      J9               65       SCONN288_ADR50001P013C01-SCONNA
GND                      J9               67       SCONN288_ADR50001P013C01-SCONNA
GND                      J9               69       SCONN288_ADR50001P013C01-SCONNA
GND                      J9               71       SCONN288_ADR50001P013C01-SCONNA
GND                      J9               73       SCONN288_ADR50001P013C01-SCONNA
GND                      J9               75       SCONN288_ADR50001P013C01-SCONNA
GND                      J9               77       SCONN288_ADR50001P013C01-SCONNA
GND                      J9               79       SCONN288_ADR50001P013C01-SCONNA
GND                      J9               81       SCONN288_ADR50001P013C01-SCONNA
GND                      J9               83       SCONN288_ADR50001P013C01-SCONNA
GND                      J9               85       SCONN288_ADR50001P013C01-SCONNA
GND                      J9               88       SCONN288_ADR50001P013C01-SCONNA
GND                      J9               90       SCONN288_ADR50001P013C01-SCONNA
GND                      J9               92       SCONN288_ADR50001P013C01-SCONNA
GND                      J9               95       SCONN288_ADR50001P013C01-SCONNA
GND                      J9               97       SCONN288_ADR50001P013C01-SCONNA
GND                      J9               99       SCONN288_ADR50001P013C01-SCONNA
GND                      J9               101      SCONN288_ADR50001P013C01-SCONNA
GND                      J9               103      SCONN288_ADR50001P013C01-SCONNA
GND                      J9               106      SCONN288_ADR50001P013C01-SCONNA
GND                      J9               108      SCONN288_ADR50001P013C01-SCONNA
GND                      J9               110      SCONN288_ADR50001P013C01-SCONNA
GND                      J9               112      SCONN288_ADR50001P013C01-SCONNA
GND                      J9               114      SCONN288_ADR50001P013C01-SCONNA
GND                      J9               117      SCONN288_ADR50001P013C01-SCONNA
GND                      J9               119      SCONN288_ADR50001P013C01-SCONNA
GND                      J9               121      SCONN288_ADR50001P013C01-SCONNA
GND                      J9               123      SCONN288_ADR50001P013C01-SCONNA
GND                      J9               125      SCONN288_ADR50001P013C01-SCONNA
GND                      J9               128      SCONN288_ADR50001P013C01-SCONNA
GND                      J9               130      SCONN288_ADR50001P013C01-SCONNA
GND                      J9               132      SCONN288_ADR50001P013C01-SCONNA
GND                      J9               134      SCONN288_ADR50001P013C01-SCONNA
GND                      J9               136      SCONN288_ADR50001P013C01-SCONNA
GND                      J9               139      SCONN288_ADR50001P013C01-SCONNA
GND                      J9               141      SCONN288_ADR50001P013C01-SCONNA
GND                      J9               143      SCONN288_ADR50001P013C01-SCONNA
GND                      J9               151      SCONN288_ADR50001P013C01-SCONNA
GND                      J9               153      SCONN288_ADR50001P013C01-SCONNA
GND                      J9               155      SCONN288_ADR50001P013C01-SCONNA
GND                      J9               158      SCONN288_ADR50001P013C01-SCONNA
GND                      J9               160      SCONN288_ADR50001P013C01-SCONNA
GND                      J9               162      SCONN288_ADR50001P013C01-SCONNA
GND                      J9               164      SCONN288_ADR50001P013C01-SCONNA
GND                      J9               166      SCONN288_ADR50001P013C01-SCONNA
GND                      J9               169      SCONN288_ADR50001P013C01-SCONNA
GND                      J9               171      SCONN288_ADR50001P013C01-SCONNA
GND                      J9               173      SCONN288_ADR50001P013C01-SCONNA
GND                      J9               175      SCONN288_ADR50001P013C01-SCONNA
GND                      J9               177      SCONN288_ADR50001P013C01-SCONNA
GND                      J9               180      SCONN288_ADR50001P013C01-SCONNA
GND                      J9               182      SCONN288_ADR50001P013C01-SCONNA
GND                      J9               184      SCONN288_ADR50001P013C01-SCONNA
GND                      J9               186      SCONN288_ADR50001P013C01-SCONNA
GND                      J9               188      SCONN288_ADR50001P013C01-SCONNA
GND                      J9               191      SCONN288_ADR50001P013C01-SCONNA
GND                      J9               193      SCONN288_ADR50001P013C01-SCONNA
GND                      J9               195      SCONN288_ADR50001P013C01-SCONNA
GND                      J9               197      SCONN288_ADR50001P013C01-SCONNA
GND                      J9               199      SCONN288_ADR50001P013C01-SCONNA
GND                      J9               202      SCONN288_ADR50001P013C01-SCONNA
GND                      J9               204      SCONN288_ADR50001P013C01-SCONNA
GND                      J9               206      SCONN288_ADR50001P013C01-SCONNA
GND                      J9               208      SCONN288_ADR50001P013C01-SCONNA
GND                      J9               210      SCONN288_ADR50001P013C01-SCONNA
GND                      J9               212      SCONN288_ADR50001P013C01-SCONNA
GND                      J9               214      SCONN288_ADR50001P013C01-SCONNA
GND                      J9               216      SCONN288_ADR50001P013C01-SCONNA
GND                      J9               219      SCONN288_ADR50001P013C01-SCONNA
GND                      J9               222      SCONN288_ADR50001P013C01-SCONNA
GND                      J9               224      SCONN288_ADR50001P013C01-SCONNA
GND                      J9               226      SCONN288_ADR50001P013C01-SCONNA
GND                      J9               228      SCONN288_ADR50001P013C01-SCONNA
GND                      J9               230      SCONN288_ADR50001P013C01-SCONNA
GND                      J9               233      SCONN288_ADR50001P013C01-SCONNA
GND                      J9               235      SCONN288_ADR50001P013C01-SCONNA
GND                      J9               237      SCONN288_ADR50001P013C01-SCONNA
GND                      J9               240      SCONN288_ADR50001P013C01-SCONNA
GND                      J9               242      SCONN288_ADR50001P013C01-SCONNA
GND                      J9               244      SCONN288_ADR50001P013C01-SCONNA
GND                      J9               246      SCONN288_ADR50001P013C01-SCONNA
GND                      J9               248      SCONN288_ADR50001P013C01-SCONNA
GND                      J9               251      SCONN288_ADR50001P013C01-SCONNA
GND                      J9               253      SCONN288_ADR50001P013C01-SCONNA
GND                      J9               255      SCONN288_ADR50001P013C01-SCONNA
GND                      J9               257      SCONN288_ADR50001P013C01-SCONNA
GND                      J9               259      SCONN288_ADR50001P013C01-SCONNA
GND                      J9               262      SCONN288_ADR50001P013C01-SCONNA
GND                      J9               264      SCONN288_ADR50001P013C01-SCONNA
GND                      J9               266      SCONN288_ADR50001P013C01-SCONNA
GND                      J9               268      SCONN288_ADR50001P013C01-SCONNA
GND                      J9               270      SCONN288_ADR50001P013C01-SCONNA
GND                      J9               273      SCONN288_ADR50001P013C01-SCONNA
GND                      J9               275      SCONN288_ADR50001P013C01-SCONNA
GND                      J9               277      SCONN288_ADR50001P013C01-SCONNA
GND                      J9               279      SCONN288_ADR50001P013C01-SCONNA
GND                      J9               281      SCONN288_ADR50001P013C01-SCONNA
GND                      J9               284      SCONN288_ADR50001P013C01-SCONNA
GND                      J9               286      SCONN288_ADR50001P013C01-SCONNA
GND                      J9               288      SCONN288_ADR50001P013C01-SCONNA
GND                      J9               G1       SCONN288_ADR50001P013C01-SCONNA
GND                      J9               G2       SCONN288_ADR50001P013C01-SCONNA
GND                      J9               G3       SCONN288_ADR50001P013C01-SCONNA
GND                      J10              6        SCONN288_ADR50001P003C01-SCONNA
GND                      J10              8        SCONN288_ADR50001P003C01-SCONNA
GND                      J10              10       SCONN288_ADR50001P003C01-SCONNA
GND                      J10              13       SCONN288_ADR50001P003C01-SCONNA
GND                      J10              15       SCONN288_ADR50001P003C01-SCONNA
GND                      J10              17       SCONN288_ADR50001P003C01-SCONNA
GND                      J10              19       SCONN288_ADR50001P003C01-SCONNA
GND                      J10              21       SCONN288_ADR50001P003C01-SCONNA
GND                      J10              24       SCONN288_ADR50001P003C01-SCONNA
GND                      J10              26       SCONN288_ADR50001P003C01-SCONNA
GND                      J10              28       SCONN288_ADR50001P003C01-SCONNA
GND                      J10              30       SCONN288_ADR50001P003C01-SCONNA
GND                      J10              32       SCONN288_ADR50001P003C01-SCONNA
GND                      J10              35       SCONN288_ADR50001P003C01-SCONNA
GND                      J10              37       SCONN288_ADR50001P003C01-SCONNA
GND                      J10              39       SCONN288_ADR50001P003C01-SCONNA
GND                      J10              41       SCONN288_ADR50001P003C01-SCONNA
GND                      J10              43       SCONN288_ADR50001P003C01-SCONNA
GND                      J10              46       SCONN288_ADR50001P003C01-SCONNA
GND                      J10              48       SCONN288_ADR50001P003C01-SCONNA
GND                      J10              50       SCONN288_ADR50001P003C01-SCONNA
GND                      J10              52       SCONN288_ADR50001P003C01-SCONNA
GND                      J10              54       SCONN288_ADR50001P003C01-SCONNA
GND                      J10              57       SCONN288_ADR50001P003C01-SCONNA
GND                      J10              59       SCONN288_ADR50001P003C01-SCONNA
GND                      J10              61       SCONN288_ADR50001P003C01-SCONNA
GND                      J10              63       SCONN288_ADR50001P003C01-SCONNA
GND                      J10              65       SCONN288_ADR50001P003C01-SCONNA
GND                      J10              67       SCONN288_ADR50001P003C01-SCONNA
GND                      J10              69       SCONN288_ADR50001P003C01-SCONNA
GND                      J10              71       SCONN288_ADR50001P003C01-SCONNA
GND                      J10              73       SCONN288_ADR50001P003C01-SCONNA
GND                      J10              75       SCONN288_ADR50001P003C01-SCONNA
GND                      J10              77       SCONN288_ADR50001P003C01-SCONNA
GND                      J10              79       SCONN288_ADR50001P003C01-SCONNA
GND                      J10              81       SCONN288_ADR50001P003C01-SCONNA
GND                      J10              83       SCONN288_ADR50001P003C01-SCONNA
GND                      J10              85       SCONN288_ADR50001P003C01-SCONNA
GND                      J10              88       SCONN288_ADR50001P003C01-SCONNA
GND                      J10              90       SCONN288_ADR50001P003C01-SCONNA
GND                      J10              92       SCONN288_ADR50001P003C01-SCONNA
GND                      J10              95       SCONN288_ADR50001P003C01-SCONNA
GND                      J10              97       SCONN288_ADR50001P003C01-SCONNA
GND                      J10              99       SCONN288_ADR50001P003C01-SCONNA
GND                      J10              101      SCONN288_ADR50001P003C01-SCONNA
GND                      J10              103      SCONN288_ADR50001P003C01-SCONNA
GND                      J10              106      SCONN288_ADR50001P003C01-SCONNA
GND                      J10              108      SCONN288_ADR50001P003C01-SCONNA
GND                      J10              110      SCONN288_ADR50001P003C01-SCONNA
GND                      J10              112      SCONN288_ADR50001P003C01-SCONNA
GND                      J10              114      SCONN288_ADR50001P003C01-SCONNA
GND                      J10              117      SCONN288_ADR50001P003C01-SCONNA
GND                      J10              119      SCONN288_ADR50001P003C01-SCONNA
GND                      J10              121      SCONN288_ADR50001P003C01-SCONNA
GND                      J10              123      SCONN288_ADR50001P003C01-SCONNA
GND                      J10              125      SCONN288_ADR50001P003C01-SCONNA
GND                      J10              128      SCONN288_ADR50001P003C01-SCONNA
GND                      J10              130      SCONN288_ADR50001P003C01-SCONNA
GND                      J10              132      SCONN288_ADR50001P003C01-SCONNA
GND                      J10              134      SCONN288_ADR50001P003C01-SCONNA
GND                      J10              136      SCONN288_ADR50001P003C01-SCONNA
GND                      J10              139      SCONN288_ADR50001P003C01-SCONNA
GND                      J10              141      SCONN288_ADR50001P003C01-SCONNA
GND                      J10              143      SCONN288_ADR50001P003C01-SCONNA
GND                      J10              151      SCONN288_ADR50001P003C01-SCONNA
GND                      J10              153      SCONN288_ADR50001P003C01-SCONNA
GND                      J10              155      SCONN288_ADR50001P003C01-SCONNA
GND                      J10              158      SCONN288_ADR50001P003C01-SCONNA
GND                      J10              160      SCONN288_ADR50001P003C01-SCONNA
GND                      J10              162      SCONN288_ADR50001P003C01-SCONNA
GND                      J10              164      SCONN288_ADR50001P003C01-SCONNA
GND                      J10              166      SCONN288_ADR50001P003C01-SCONNA
GND                      J10              169      SCONN288_ADR50001P003C01-SCONNA
GND                      J10              171      SCONN288_ADR50001P003C01-SCONNA
GND                      J10              173      SCONN288_ADR50001P003C01-SCONNA
GND                      J10              175      SCONN288_ADR50001P003C01-SCONNA
GND                      J10              177      SCONN288_ADR50001P003C01-SCONNA
GND                      J10              180      SCONN288_ADR50001P003C01-SCONNA
GND                      J10              182      SCONN288_ADR50001P003C01-SCONNA
GND                      J10              184      SCONN288_ADR50001P003C01-SCONNA
GND                      J10              186      SCONN288_ADR50001P003C01-SCONNA
GND                      J10              188      SCONN288_ADR50001P003C01-SCONNA
GND                      J10              191      SCONN288_ADR50001P003C01-SCONNA
GND                      J10              193      SCONN288_ADR50001P003C01-SCONNA
GND                      J10              195      SCONN288_ADR50001P003C01-SCONNA
GND                      J10              197      SCONN288_ADR50001P003C01-SCONNA
GND                      J10              199      SCONN288_ADR50001P003C01-SCONNA
GND                      J10              202      SCONN288_ADR50001P003C01-SCONNA
GND                      J10              204      SCONN288_ADR50001P003C01-SCONNA
GND                      J10              206      SCONN288_ADR50001P003C01-SCONNA
GND                      J10              208      SCONN288_ADR50001P003C01-SCONNA
GND                      J10              210      SCONN288_ADR50001P003C01-SCONNA
GND                      J10              212      SCONN288_ADR50001P003C01-SCONNA
GND                      J10              214      SCONN288_ADR50001P003C01-SCONNA
GND                      J10              216      SCONN288_ADR50001P003C01-SCONNA
GND                      J10              219      SCONN288_ADR50001P003C01-SCONNA
GND                      J10              222      SCONN288_ADR50001P003C01-SCONNA
GND                      J10              224      SCONN288_ADR50001P003C01-SCONNA
GND                      J10              226      SCONN288_ADR50001P003C01-SCONNA
GND                      J10              228      SCONN288_ADR50001P003C01-SCONNA
GND                      J10              230      SCONN288_ADR50001P003C01-SCONNA
GND                      J10              233      SCONN288_ADR50001P003C01-SCONNA
GND                      J10              235      SCONN288_ADR50001P003C01-SCONNA
GND                      J10              237      SCONN288_ADR50001P003C01-SCONNA
GND                      J10              240      SCONN288_ADR50001P003C01-SCONNA
GND                      J10              242      SCONN288_ADR50001P003C01-SCONNA
GND                      J10              244      SCONN288_ADR50001P003C01-SCONNA
GND                      J10              246      SCONN288_ADR50001P003C01-SCONNA
GND                      J10              248      SCONN288_ADR50001P003C01-SCONNA
GND                      J10              251      SCONN288_ADR50001P003C01-SCONNA
GND                      J10              253      SCONN288_ADR50001P003C01-SCONNA
GND                      J10              255      SCONN288_ADR50001P003C01-SCONNA
GND                      J10              257      SCONN288_ADR50001P003C01-SCONNA
GND                      J10              259      SCONN288_ADR50001P003C01-SCONNA
GND                      J10              262      SCONN288_ADR50001P003C01-SCONNA
GND                      J10              264      SCONN288_ADR50001P003C01-SCONNA
GND                      J10              266      SCONN288_ADR50001P003C01-SCONNA
GND                      J10              268      SCONN288_ADR50001P003C01-SCONNA
GND                      J10              270      SCONN288_ADR50001P003C01-SCONNA
GND                      J10              273      SCONN288_ADR50001P003C01-SCONNA
GND                      J10              275      SCONN288_ADR50001P003C01-SCONNA
GND                      J10              277      SCONN288_ADR50001P003C01-SCONNA
GND                      J10              279      SCONN288_ADR50001P003C01-SCONNA
GND                      J10              281      SCONN288_ADR50001P003C01-SCONNA
GND                      J10              284      SCONN288_ADR50001P003C01-SCONNA
GND                      J10              286      SCONN288_ADR50001P003C01-SCONNA
GND                      J10              288      SCONN288_ADR50001P003C01-SCONNA
GND                      J10              G1       SCONN288_ADR50001P003C01-SCONNA
GND                      J10              G2       SCONN288_ADR50001P003C01-SCONNA
GND                      J10              G3       SCONN288_ADR50001P003C01-SCONNA
GND                      J11              6        SCONN288_ADR50001P013C01-SCONNA
GND                      J11              8        SCONN288_ADR50001P013C01-SCONNA
GND                      J11              10       SCONN288_ADR50001P013C01-SCONNA
GND                      J11              13       SCONN288_ADR50001P013C01-SCONNA
GND                      J11              15       SCONN288_ADR50001P013C01-SCONNA
GND                      J11              17       SCONN288_ADR50001P013C01-SCONNA
GND                      J11              19       SCONN288_ADR50001P013C01-SCONNA
GND                      J11              21       SCONN288_ADR50001P013C01-SCONNA
GND                      J11              24       SCONN288_ADR50001P013C01-SCONNA
GND                      J11              26       SCONN288_ADR50001P013C01-SCONNA
GND                      J11              28       SCONN288_ADR50001P013C01-SCONNA
GND                      J11              30       SCONN288_ADR50001P013C01-SCONNA
GND                      J11              32       SCONN288_ADR50001P013C01-SCONNA
GND                      J11              35       SCONN288_ADR50001P013C01-SCONNA
GND                      J11              37       SCONN288_ADR50001P013C01-SCONNA
GND                      J11              39       SCONN288_ADR50001P013C01-SCONNA
GND                      J11              41       SCONN288_ADR50001P013C01-SCONNA
GND                      J11              43       SCONN288_ADR50001P013C01-SCONNA
GND                      J11              46       SCONN288_ADR50001P013C01-SCONNA
GND                      J11              48       SCONN288_ADR50001P013C01-SCONNA
GND                      J11              50       SCONN288_ADR50001P013C01-SCONNA
GND                      J11              52       SCONN288_ADR50001P013C01-SCONNA
GND                      J11              54       SCONN288_ADR50001P013C01-SCONNA
GND                      J11              57       SCONN288_ADR50001P013C01-SCONNA
GND                      J11              59       SCONN288_ADR50001P013C01-SCONNA
GND                      J11              61       SCONN288_ADR50001P013C01-SCONNA
GND                      J11              63       SCONN288_ADR50001P013C01-SCONNA
GND                      J11              65       SCONN288_ADR50001P013C01-SCONNA
GND                      J11              67       SCONN288_ADR50001P013C01-SCONNA
GND                      J11              69       SCONN288_ADR50001P013C01-SCONNA
GND                      J11              71       SCONN288_ADR50001P013C01-SCONNA
GND                      J11              73       SCONN288_ADR50001P013C01-SCONNA
GND                      J11              75       SCONN288_ADR50001P013C01-SCONNA
GND                      J11              77       SCONN288_ADR50001P013C01-SCONNA
GND                      J11              79       SCONN288_ADR50001P013C01-SCONNA
GND                      J11              81       SCONN288_ADR50001P013C01-SCONNA
GND                      J11              83       SCONN288_ADR50001P013C01-SCONNA
GND                      J11              85       SCONN288_ADR50001P013C01-SCONNA
GND                      J11              88       SCONN288_ADR50001P013C01-SCONNA
GND                      J11              90       SCONN288_ADR50001P013C01-SCONNA
GND                      J11              92       SCONN288_ADR50001P013C01-SCONNA
GND                      J11              95       SCONN288_ADR50001P013C01-SCONNA
GND                      J11              97       SCONN288_ADR50001P013C01-SCONNA
GND                      J11              99       SCONN288_ADR50001P013C01-SCONNA
GND                      J11              101      SCONN288_ADR50001P013C01-SCONNA
GND                      J11              103      SCONN288_ADR50001P013C01-SCONNA
GND                      J11              106      SCONN288_ADR50001P013C01-SCONNA
GND                      J11              108      SCONN288_ADR50001P013C01-SCONNA
GND                      J11              110      SCONN288_ADR50001P013C01-SCONNA
GND                      J11              112      SCONN288_ADR50001P013C01-SCONNA
GND                      J11              114      SCONN288_ADR50001P013C01-SCONNA
GND                      J11              117      SCONN288_ADR50001P013C01-SCONNA
GND                      J11              119      SCONN288_ADR50001P013C01-SCONNA
GND                      J11              121      SCONN288_ADR50001P013C01-SCONNA
GND                      J11              123      SCONN288_ADR50001P013C01-SCONNA
GND                      J11              125      SCONN288_ADR50001P013C01-SCONNA
GND                      J11              128      SCONN288_ADR50001P013C01-SCONNA
GND                      J11              130      SCONN288_ADR50001P013C01-SCONNA
GND                      J11              132      SCONN288_ADR50001P013C01-SCONNA
GND                      J11              134      SCONN288_ADR50001P013C01-SCONNA
GND                      J11              136      SCONN288_ADR50001P013C01-SCONNA
GND                      J11              139      SCONN288_ADR50001P013C01-SCONNA
GND                      J11              141      SCONN288_ADR50001P013C01-SCONNA
GND                      J11              143      SCONN288_ADR50001P013C01-SCONNA
GND                      J11              151      SCONN288_ADR50001P013C01-SCONNA
GND                      J11              153      SCONN288_ADR50001P013C01-SCONNA
GND                      J11              155      SCONN288_ADR50001P013C01-SCONNA
GND                      J11              158      SCONN288_ADR50001P013C01-SCONNA
GND                      J11              160      SCONN288_ADR50001P013C01-SCONNA
GND                      J11              162      SCONN288_ADR50001P013C01-SCONNA
GND                      J11              164      SCONN288_ADR50001P013C01-SCONNA
GND                      J11              166      SCONN288_ADR50001P013C01-SCONNA
GND                      J11              169      SCONN288_ADR50001P013C01-SCONNA
GND                      J11              171      SCONN288_ADR50001P013C01-SCONNA
GND                      J11              173      SCONN288_ADR50001P013C01-SCONNA
GND                      J11              175      SCONN288_ADR50001P013C01-SCONNA
GND                      J11              177      SCONN288_ADR50001P013C01-SCONNA
GND                      J11              180      SCONN288_ADR50001P013C01-SCONNA
GND                      J11              182      SCONN288_ADR50001P013C01-SCONNA
GND                      J11              184      SCONN288_ADR50001P013C01-SCONNA
GND                      J11              186      SCONN288_ADR50001P013C01-SCONNA
GND                      J11              188      SCONN288_ADR50001P013C01-SCONNA
GND                      J11              191      SCONN288_ADR50001P013C01-SCONNA
GND                      J11              193      SCONN288_ADR50001P013C01-SCONNA
GND                      J11              195      SCONN288_ADR50001P013C01-SCONNA
GND                      J11              197      SCONN288_ADR50001P013C01-SCONNA
GND                      J11              199      SCONN288_ADR50001P013C01-SCONNA
GND                      J11              202      SCONN288_ADR50001P013C01-SCONNA
GND                      J11              204      SCONN288_ADR50001P013C01-SCONNA
GND                      J11              206      SCONN288_ADR50001P013C01-SCONNA
GND                      J11              208      SCONN288_ADR50001P013C01-SCONNA
GND                      J11              210      SCONN288_ADR50001P013C01-SCONNA
GND                      J11              212      SCONN288_ADR50001P013C01-SCONNA
GND                      J11              214      SCONN288_ADR50001P013C01-SCONNA
GND                      J11              216      SCONN288_ADR50001P013C01-SCONNA
GND                      J11              219      SCONN288_ADR50001P013C01-SCONNA
GND                      J11              222      SCONN288_ADR50001P013C01-SCONNA
GND                      J11              224      SCONN288_ADR50001P013C01-SCONNA
GND                      J11              226      SCONN288_ADR50001P013C01-SCONNA
GND                      J11              228      SCONN288_ADR50001P013C01-SCONNA
GND                      J11              230      SCONN288_ADR50001P013C01-SCONNA
GND                      J11              233      SCONN288_ADR50001P013C01-SCONNA
GND                      J11              235      SCONN288_ADR50001P013C01-SCONNA
GND                      J11              237      SCONN288_ADR50001P013C01-SCONNA
GND                      J11              240      SCONN288_ADR50001P013C01-SCONNA
GND                      J11              242      SCONN288_ADR50001P013C01-SCONNA
GND                      J11              244      SCONN288_ADR50001P013C01-SCONNA
GND                      J11              246      SCONN288_ADR50001P013C01-SCONNA
GND                      J11              248      SCONN288_ADR50001P013C01-SCONNA
GND                      J11              251      SCONN288_ADR50001P013C01-SCONNA
GND                      J11              253      SCONN288_ADR50001P013C01-SCONNA
GND                      J11              255      SCONN288_ADR50001P013C01-SCONNA
GND                      J11              257      SCONN288_ADR50001P013C01-SCONNA
GND                      J11              259      SCONN288_ADR50001P013C01-SCONNA
GND                      J11              262      SCONN288_ADR50001P013C01-SCONNA
GND                      J11              264      SCONN288_ADR50001P013C01-SCONNA
GND                      J11              266      SCONN288_ADR50001P013C01-SCONNA
GND                      J11              268      SCONN288_ADR50001P013C01-SCONNA
GND                      J11              270      SCONN288_ADR50001P013C01-SCONNA
GND                      J11              273      SCONN288_ADR50001P013C01-SCONNA
GND                      J11              275      SCONN288_ADR50001P013C01-SCONNA
GND                      J11              277      SCONN288_ADR50001P013C01-SCONNA
GND                      J11              279      SCONN288_ADR50001P013C01-SCONNA
GND                      J11              281      SCONN288_ADR50001P013C01-SCONNA
GND                      J11              284      SCONN288_ADR50001P013C01-SCONNA
GND                      J11              286      SCONN288_ADR50001P013C01-SCONNA
GND                      J11              288      SCONN288_ADR50001P013C01-SCONNA
GND                      J11              G1       SCONN288_ADR50001P013C01-SCONNA
GND                      J11              G2       SCONN288_ADR50001P013C01-SCONNA
GND                      J11              G3       SCONN288_ADR50001P013C01-SCONNA
GND                      J12              6        SCONN288_ADR50001P003C01-SCONNA
GND                      J12              8        SCONN288_ADR50001P003C01-SCONNA
GND                      J12              10       SCONN288_ADR50001P003C01-SCONNA
GND                      J12              13       SCONN288_ADR50001P003C01-SCONNA
GND                      J12              15       SCONN288_ADR50001P003C01-SCONNA
GND                      J12              17       SCONN288_ADR50001P003C01-SCONNA
GND                      J12              19       SCONN288_ADR50001P003C01-SCONNA
GND                      J12              21       SCONN288_ADR50001P003C01-SCONNA
GND                      J12              24       SCONN288_ADR50001P003C01-SCONNA
GND                      J12              26       SCONN288_ADR50001P003C01-SCONNA
GND                      J12              28       SCONN288_ADR50001P003C01-SCONNA
GND                      J12              30       SCONN288_ADR50001P003C01-SCONNA
GND                      J12              32       SCONN288_ADR50001P003C01-SCONNA
GND                      J12              35       SCONN288_ADR50001P003C01-SCONNA
GND                      J12              37       SCONN288_ADR50001P003C01-SCONNA
GND                      J12              39       SCONN288_ADR50001P003C01-SCONNA
GND                      J12              41       SCONN288_ADR50001P003C01-SCONNA
GND                      J12              43       SCONN288_ADR50001P003C01-SCONNA
GND                      J12              46       SCONN288_ADR50001P003C01-SCONNA
GND                      J12              48       SCONN288_ADR50001P003C01-SCONNA
GND                      J12              50       SCONN288_ADR50001P003C01-SCONNA
GND                      J12              52       SCONN288_ADR50001P003C01-SCONNA
GND                      J12              54       SCONN288_ADR50001P003C01-SCONNA
GND                      J12              57       SCONN288_ADR50001P003C01-SCONNA
GND                      J12              59       SCONN288_ADR50001P003C01-SCONNA
GND                      J12              61       SCONN288_ADR50001P003C01-SCONNA
GND                      J12              63       SCONN288_ADR50001P003C01-SCONNA
GND                      J12              65       SCONN288_ADR50001P003C01-SCONNA
GND                      J12              67       SCONN288_ADR50001P003C01-SCONNA
GND                      J12              69       SCONN288_ADR50001P003C01-SCONNA
GND                      J12              71       SCONN288_ADR50001P003C01-SCONNA
GND                      J12              73       SCONN288_ADR50001P003C01-SCONNA
GND                      J12              75       SCONN288_ADR50001P003C01-SCONNA
GND                      J12              77       SCONN288_ADR50001P003C01-SCONNA
GND                      J12              79       SCONN288_ADR50001P003C01-SCONNA
GND                      J12              81       SCONN288_ADR50001P003C01-SCONNA
GND                      J12              83       SCONN288_ADR50001P003C01-SCONNA
GND                      J12              85       SCONN288_ADR50001P003C01-SCONNA
GND                      J12              88       SCONN288_ADR50001P003C01-SCONNA
GND                      J12              90       SCONN288_ADR50001P003C01-SCONNA
GND                      J12              92       SCONN288_ADR50001P003C01-SCONNA
GND                      J12              95       SCONN288_ADR50001P003C01-SCONNA
GND                      J12              97       SCONN288_ADR50001P003C01-SCONNA
GND                      J12              99       SCONN288_ADR50001P003C01-SCONNA
GND                      J12              101      SCONN288_ADR50001P003C01-SCONNA
GND                      J12              103      SCONN288_ADR50001P003C01-SCONNA
GND                      J12              106      SCONN288_ADR50001P003C01-SCONNA
GND                      J12              108      SCONN288_ADR50001P003C01-SCONNA
GND                      J12              110      SCONN288_ADR50001P003C01-SCONNA
GND                      J12              112      SCONN288_ADR50001P003C01-SCONNA
GND                      J12              114      SCONN288_ADR50001P003C01-SCONNA
GND                      J12              117      SCONN288_ADR50001P003C01-SCONNA
GND                      J12              119      SCONN288_ADR50001P003C01-SCONNA
GND                      J12              121      SCONN288_ADR50001P003C01-SCONNA
GND                      J12              123      SCONN288_ADR50001P003C01-SCONNA
GND                      J12              125      SCONN288_ADR50001P003C01-SCONNA
GND                      J12              128      SCONN288_ADR50001P003C01-SCONNA
GND                      J12              130      SCONN288_ADR50001P003C01-SCONNA
GND                      J12              132      SCONN288_ADR50001P003C01-SCONNA
GND                      J12              134      SCONN288_ADR50001P003C01-SCONNA
GND                      J12              136      SCONN288_ADR50001P003C01-SCONNA
GND                      J12              139      SCONN288_ADR50001P003C01-SCONNA
GND                      J12              141      SCONN288_ADR50001P003C01-SCONNA
GND                      J12              143      SCONN288_ADR50001P003C01-SCONNA
GND                      J12              151      SCONN288_ADR50001P003C01-SCONNA
GND                      J12              153      SCONN288_ADR50001P003C01-SCONNA
GND                      J12              155      SCONN288_ADR50001P003C01-SCONNA
GND                      J12              158      SCONN288_ADR50001P003C01-SCONNA
GND                      J12              160      SCONN288_ADR50001P003C01-SCONNA
GND                      J12              162      SCONN288_ADR50001P003C01-SCONNA
GND                      J12              164      SCONN288_ADR50001P003C01-SCONNA
GND                      J12              166      SCONN288_ADR50001P003C01-SCONNA
GND                      J12              169      SCONN288_ADR50001P003C01-SCONNA
GND                      J12              171      SCONN288_ADR50001P003C01-SCONNA
GND                      J12              173      SCONN288_ADR50001P003C01-SCONNA
GND                      J12              175      SCONN288_ADR50001P003C01-SCONNA
GND                      J12              177      SCONN288_ADR50001P003C01-SCONNA
GND                      J12              180      SCONN288_ADR50001P003C01-SCONNA
GND                      J12              182      SCONN288_ADR50001P003C01-SCONNA
GND                      J12              184      SCONN288_ADR50001P003C01-SCONNA
GND                      J12              186      SCONN288_ADR50001P003C01-SCONNA
GND                      J12              188      SCONN288_ADR50001P003C01-SCONNA
GND                      J12              191      SCONN288_ADR50001P003C01-SCONNA
GND                      J12              193      SCONN288_ADR50001P003C01-SCONNA
GND                      J12              195      SCONN288_ADR50001P003C01-SCONNA
GND                      J12              197      SCONN288_ADR50001P003C01-SCONNA
GND                      J12              199      SCONN288_ADR50001P003C01-SCONNA
GND                      J12              202      SCONN288_ADR50001P003C01-SCONNA
GND                      J12              204      SCONN288_ADR50001P003C01-SCONNA
GND                      J12              206      SCONN288_ADR50001P003C01-SCONNA
GND                      J12              208      SCONN288_ADR50001P003C01-SCONNA
GND                      J12              210      SCONN288_ADR50001P003C01-SCONNA
GND                      J12              212      SCONN288_ADR50001P003C01-SCONNA
GND                      J12              214      SCONN288_ADR50001P003C01-SCONNA
GND                      J12              216      SCONN288_ADR50001P003C01-SCONNA
GND                      J12              219      SCONN288_ADR50001P003C01-SCONNA
GND                      J12              222      SCONN288_ADR50001P003C01-SCONNA
GND                      J12              224      SCONN288_ADR50001P003C01-SCONNA
GND                      J12              226      SCONN288_ADR50001P003C01-SCONNA
GND                      J12              228      SCONN288_ADR50001P003C01-SCONNA
GND                      J12              230      SCONN288_ADR50001P003C01-SCONNA
GND                      J12              233      SCONN288_ADR50001P003C01-SCONNA
GND                      J12              235      SCONN288_ADR50001P003C01-SCONNA
GND                      J12              237      SCONN288_ADR50001P003C01-SCONNA
GND                      J12              240      SCONN288_ADR50001P003C01-SCONNA
GND                      J12              242      SCONN288_ADR50001P003C01-SCONNA
GND                      J12              244      SCONN288_ADR50001P003C01-SCONNA
GND                      J12              246      SCONN288_ADR50001P003C01-SCONNA
GND                      J12              248      SCONN288_ADR50001P003C01-SCONNA
GND                      J12              251      SCONN288_ADR50001P003C01-SCONNA
GND                      J12              253      SCONN288_ADR50001P003C01-SCONNA
GND                      J12              255      SCONN288_ADR50001P003C01-SCONNA
GND                      J12              257      SCONN288_ADR50001P003C01-SCONNA
GND                      J12              259      SCONN288_ADR50001P003C01-SCONNA
GND                      J12              262      SCONN288_ADR50001P003C01-SCONNA
GND                      J12              264      SCONN288_ADR50001P003C01-SCONNA
GND                      J12              266      SCONN288_ADR50001P003C01-SCONNA
GND                      J12              268      SCONN288_ADR50001P003C01-SCONNA
GND                      J12              270      SCONN288_ADR50001P003C01-SCONNA
GND                      J12              273      SCONN288_ADR50001P003C01-SCONNA
GND                      J12              275      SCONN288_ADR50001P003C01-SCONNA
GND                      J12              277      SCONN288_ADR50001P003C01-SCONNA
GND                      J12              279      SCONN288_ADR50001P003C01-SCONNA
GND                      J12              281      SCONN288_ADR50001P003C01-SCONNA
GND                      J12              284      SCONN288_ADR50001P003C01-SCONNA
GND                      J12              286      SCONN288_ADR50001P003C01-SCONNA
GND                      J12              288      SCONN288_ADR50001P003C01-SCONNA
GND                      J12              G1       SCONN288_ADR50001P003C01-SCONNA
GND                      J12              G2       SCONN288_ADR50001P003C01-SCONNA
GND                      J12              G3       SCONN288_ADR50001P003C01-SCONNA
GND                      J13              6        SCONN288_ADR50001P013C01-SCONNA
GND                      J13              8        SCONN288_ADR50001P013C01-SCONNA
GND                      J13              10       SCONN288_ADR50001P013C01-SCONNA
GND                      J13              13       SCONN288_ADR50001P013C01-SCONNA
GND                      J13              15       SCONN288_ADR50001P013C01-SCONNA
GND                      J13              17       SCONN288_ADR50001P013C01-SCONNA
GND                      J13              19       SCONN288_ADR50001P013C01-SCONNA
GND                      J13              21       SCONN288_ADR50001P013C01-SCONNA
GND                      J13              24       SCONN288_ADR50001P013C01-SCONNA
GND                      J13              26       SCONN288_ADR50001P013C01-SCONNA
GND                      J13              28       SCONN288_ADR50001P013C01-SCONNA
GND                      J13              30       SCONN288_ADR50001P013C01-SCONNA
GND                      J13              32       SCONN288_ADR50001P013C01-SCONNA
GND                      J13              35       SCONN288_ADR50001P013C01-SCONNA
GND                      J13              37       SCONN288_ADR50001P013C01-SCONNA
GND                      J13              39       SCONN288_ADR50001P013C01-SCONNA
GND                      J13              41       SCONN288_ADR50001P013C01-SCONNA
GND                      J13              43       SCONN288_ADR50001P013C01-SCONNA
GND                      J13              46       SCONN288_ADR50001P013C01-SCONNA
GND                      J13              48       SCONN288_ADR50001P013C01-SCONNA
GND                      J13              50       SCONN288_ADR50001P013C01-SCONNA
GND                      J13              52       SCONN288_ADR50001P013C01-SCONNA
GND                      J13              54       SCONN288_ADR50001P013C01-SCONNA
GND                      J13              57       SCONN288_ADR50001P013C01-SCONNA
GND                      J13              59       SCONN288_ADR50001P013C01-SCONNA
GND                      J13              61       SCONN288_ADR50001P013C01-SCONNA
GND                      J13              63       SCONN288_ADR50001P013C01-SCONNA
GND                      J13              65       SCONN288_ADR50001P013C01-SCONNA
GND                      J13              67       SCONN288_ADR50001P013C01-SCONNA
GND                      J13              69       SCONN288_ADR50001P013C01-SCONNA
GND                      J13              71       SCONN288_ADR50001P013C01-SCONNA
GND                      J13              73       SCONN288_ADR50001P013C01-SCONNA
GND                      J13              75       SCONN288_ADR50001P013C01-SCONNA
GND                      J13              77       SCONN288_ADR50001P013C01-SCONNA
GND                      J13              79       SCONN288_ADR50001P013C01-SCONNA
GND                      J13              81       SCONN288_ADR50001P013C01-SCONNA
GND                      J13              83       SCONN288_ADR50001P013C01-SCONNA
GND                      J13              85       SCONN288_ADR50001P013C01-SCONNA
GND                      J13              88       SCONN288_ADR50001P013C01-SCONNA
GND                      J13              90       SCONN288_ADR50001P013C01-SCONNA
GND                      J13              92       SCONN288_ADR50001P013C01-SCONNA
GND                      J13              95       SCONN288_ADR50001P013C01-SCONNA
GND                      J13              97       SCONN288_ADR50001P013C01-SCONNA
GND                      J13              99       SCONN288_ADR50001P013C01-SCONNA
GND                      J13              101      SCONN288_ADR50001P013C01-SCONNA
GND                      J13              103      SCONN288_ADR50001P013C01-SCONNA
GND                      J13              106      SCONN288_ADR50001P013C01-SCONNA
GND                      J13              108      SCONN288_ADR50001P013C01-SCONNA
GND                      J13              110      SCONN288_ADR50001P013C01-SCONNA
GND                      J13              112      SCONN288_ADR50001P013C01-SCONNA
GND                      J13              114      SCONN288_ADR50001P013C01-SCONNA
GND                      J13              117      SCONN288_ADR50001P013C01-SCONNA
GND                      J13              119      SCONN288_ADR50001P013C01-SCONNA
GND                      J13              121      SCONN288_ADR50001P013C01-SCONNA
GND                      J13              123      SCONN288_ADR50001P013C01-SCONNA
GND                      J13              125      SCONN288_ADR50001P013C01-SCONNA
GND                      J13              128      SCONN288_ADR50001P013C01-SCONNA
GND                      J13              130      SCONN288_ADR50001P013C01-SCONNA
GND                      J13              132      SCONN288_ADR50001P013C01-SCONNA
GND                      J13              134      SCONN288_ADR50001P013C01-SCONNA
GND                      J13              136      SCONN288_ADR50001P013C01-SCONNA
GND                      J13              139      SCONN288_ADR50001P013C01-SCONNA
GND                      J13              141      SCONN288_ADR50001P013C01-SCONNA
GND                      J13              143      SCONN288_ADR50001P013C01-SCONNA
GND                      J13              151      SCONN288_ADR50001P013C01-SCONNA
GND                      J13              153      SCONN288_ADR50001P013C01-SCONNA
GND                      J13              155      SCONN288_ADR50001P013C01-SCONNA
GND                      J13              158      SCONN288_ADR50001P013C01-SCONNA
GND                      J13              160      SCONN288_ADR50001P013C01-SCONNA
GND                      J13              162      SCONN288_ADR50001P013C01-SCONNA
GND                      J13              164      SCONN288_ADR50001P013C01-SCONNA
GND                      J13              166      SCONN288_ADR50001P013C01-SCONNA
GND                      J13              169      SCONN288_ADR50001P013C01-SCONNA
GND                      J13              171      SCONN288_ADR50001P013C01-SCONNA
GND                      J13              173      SCONN288_ADR50001P013C01-SCONNA
GND                      J13              175      SCONN288_ADR50001P013C01-SCONNA
GND                      J13              177      SCONN288_ADR50001P013C01-SCONNA
GND                      J13              180      SCONN288_ADR50001P013C01-SCONNA
GND                      J13              182      SCONN288_ADR50001P013C01-SCONNA
GND                      J13              184      SCONN288_ADR50001P013C01-SCONNA
GND                      J13              186      SCONN288_ADR50001P013C01-SCONNA
GND                      J13              188      SCONN288_ADR50001P013C01-SCONNA
GND                      J13              191      SCONN288_ADR50001P013C01-SCONNA
GND                      J13              193      SCONN288_ADR50001P013C01-SCONNA
GND                      J13              195      SCONN288_ADR50001P013C01-SCONNA
GND                      J13              197      SCONN288_ADR50001P013C01-SCONNA
GND                      J13              199      SCONN288_ADR50001P013C01-SCONNA
GND                      J13              202      SCONN288_ADR50001P013C01-SCONNA
GND                      J13              204      SCONN288_ADR50001P013C01-SCONNA
GND                      J13              206      SCONN288_ADR50001P013C01-SCONNA
GND                      J13              208      SCONN288_ADR50001P013C01-SCONNA
GND                      J13              210      SCONN288_ADR50001P013C01-SCONNA
GND                      J13              212      SCONN288_ADR50001P013C01-SCONNA
GND                      J13              214      SCONN288_ADR50001P013C01-SCONNA
GND                      J13              216      SCONN288_ADR50001P013C01-SCONNA
GND                      J13              219      SCONN288_ADR50001P013C01-SCONNA
GND                      J13              222      SCONN288_ADR50001P013C01-SCONNA
GND                      J13              224      SCONN288_ADR50001P013C01-SCONNA
GND                      J13              226      SCONN288_ADR50001P013C01-SCONNA
GND                      J13              228      SCONN288_ADR50001P013C01-SCONNA
GND                      J13              230      SCONN288_ADR50001P013C01-SCONNA
GND                      J13              233      SCONN288_ADR50001P013C01-SCONNA
GND                      J13              235      SCONN288_ADR50001P013C01-SCONNA
GND                      J13              237      SCONN288_ADR50001P013C01-SCONNA
GND                      J13              240      SCONN288_ADR50001P013C01-SCONNA
GND                      J13              242      SCONN288_ADR50001P013C01-SCONNA
GND                      J13              244      SCONN288_ADR50001P013C01-SCONNA
GND                      J13              246      SCONN288_ADR50001P013C01-SCONNA
GND                      J13              248      SCONN288_ADR50001P013C01-SCONNA
GND                      J13              251      SCONN288_ADR50001P013C01-SCONNA
GND                      J13              253      SCONN288_ADR50001P013C01-SCONNA
GND                      J13              255      SCONN288_ADR50001P013C01-SCONNA
GND                      J13              257      SCONN288_ADR50001P013C01-SCONNA
GND                      J13              259      SCONN288_ADR50001P013C01-SCONNA
GND                      J13              262      SCONN288_ADR50001P013C01-SCONNA
GND                      J13              264      SCONN288_ADR50001P013C01-SCONNA
GND                      J13              266      SCONN288_ADR50001P013C01-SCONNA
GND                      J13              268      SCONN288_ADR50001P013C01-SCONNA
GND                      J13              270      SCONN288_ADR50001P013C01-SCONNA
GND                      J13              273      SCONN288_ADR50001P013C01-SCONNA
GND                      J13              275      SCONN288_ADR50001P013C01-SCONNA
GND                      J13              277      SCONN288_ADR50001P013C01-SCONNA
GND                      J13              279      SCONN288_ADR50001P013C01-SCONNA
GND                      J13              281      SCONN288_ADR50001P013C01-SCONNA
GND                      J13              284      SCONN288_ADR50001P013C01-SCONNA
GND                      J13              286      SCONN288_ADR50001P013C01-SCONNA
GND                      J13              288      SCONN288_ADR50001P013C01-SCONNA
GND                      J13              G1       SCONN288_ADR50001P013C01-SCONNA
GND                      J13              G2       SCONN288_ADR50001P013C01-SCONNA
GND                      J13              G3       SCONN288_ADR50001P013C01-SCONNA
GND                      J14              6        SCONN288_ADR50001P003C01-SCONNA
GND                      J14              8        SCONN288_ADR50001P003C01-SCONNA
GND                      J14              10       SCONN288_ADR50001P003C01-SCONNA
GND                      J14              13       SCONN288_ADR50001P003C01-SCONNA
GND                      J14              15       SCONN288_ADR50001P003C01-SCONNA
GND                      J14              17       SCONN288_ADR50001P003C01-SCONNA
GND                      J14              19       SCONN288_ADR50001P003C01-SCONNA
GND                      J14              21       SCONN288_ADR50001P003C01-SCONNA
GND                      J14              24       SCONN288_ADR50001P003C01-SCONNA
GND                      J14              26       SCONN288_ADR50001P003C01-SCONNA
GND                      J14              28       SCONN288_ADR50001P003C01-SCONNA
GND                      J14              30       SCONN288_ADR50001P003C01-SCONNA
GND                      J14              32       SCONN288_ADR50001P003C01-SCONNA
GND                      J14              35       SCONN288_ADR50001P003C01-SCONNA
GND                      J14              37       SCONN288_ADR50001P003C01-SCONNA
GND                      J14              39       SCONN288_ADR50001P003C01-SCONNA
GND                      J14              41       SCONN288_ADR50001P003C01-SCONNA
GND                      J14              43       SCONN288_ADR50001P003C01-SCONNA
GND                      J14              46       SCONN288_ADR50001P003C01-SCONNA
GND                      J14              48       SCONN288_ADR50001P003C01-SCONNA
GND                      J14              50       SCONN288_ADR50001P003C01-SCONNA
GND                      J14              52       SCONN288_ADR50001P003C01-SCONNA
GND                      J14              54       SCONN288_ADR50001P003C01-SCONNA
GND                      J14              57       SCONN288_ADR50001P003C01-SCONNA
GND                      J14              59       SCONN288_ADR50001P003C01-SCONNA
GND                      J14              61       SCONN288_ADR50001P003C01-SCONNA
GND                      J14              63       SCONN288_ADR50001P003C01-SCONNA
GND                      J14              65       SCONN288_ADR50001P003C01-SCONNA
GND                      J14              67       SCONN288_ADR50001P003C01-SCONNA
GND                      J14              69       SCONN288_ADR50001P003C01-SCONNA
GND                      J14              71       SCONN288_ADR50001P003C01-SCONNA
GND                      J14              73       SCONN288_ADR50001P003C01-SCONNA
GND                      J14              75       SCONN288_ADR50001P003C01-SCONNA
GND                      J14              77       SCONN288_ADR50001P003C01-SCONNA
GND                      J14              79       SCONN288_ADR50001P003C01-SCONNA
GND                      J14              81       SCONN288_ADR50001P003C01-SCONNA
GND                      J14              83       SCONN288_ADR50001P003C01-SCONNA
GND                      J14              85       SCONN288_ADR50001P003C01-SCONNA
GND                      J14              88       SCONN288_ADR50001P003C01-SCONNA
GND                      J14              90       SCONN288_ADR50001P003C01-SCONNA
GND                      J14              92       SCONN288_ADR50001P003C01-SCONNA
GND                      J14              95       SCONN288_ADR50001P003C01-SCONNA
GND                      J14              97       SCONN288_ADR50001P003C01-SCONNA
GND                      J14              99       SCONN288_ADR50001P003C01-SCONNA
GND                      J14              101      SCONN288_ADR50001P003C01-SCONNA
GND                      J14              103      SCONN288_ADR50001P003C01-SCONNA
GND                      J14              106      SCONN288_ADR50001P003C01-SCONNA
GND                      J14              108      SCONN288_ADR50001P003C01-SCONNA
GND                      J14              110      SCONN288_ADR50001P003C01-SCONNA
GND                      J14              112      SCONN288_ADR50001P003C01-SCONNA
GND                      J14              114      SCONN288_ADR50001P003C01-SCONNA
GND                      J14              117      SCONN288_ADR50001P003C01-SCONNA
GND                      J14              119      SCONN288_ADR50001P003C01-SCONNA
GND                      J14              121      SCONN288_ADR50001P003C01-SCONNA
GND                      J14              123      SCONN288_ADR50001P003C01-SCONNA
GND                      J14              125      SCONN288_ADR50001P003C01-SCONNA
GND                      J14              128      SCONN288_ADR50001P003C01-SCONNA
GND                      J14              130      SCONN288_ADR50001P003C01-SCONNA
GND                      J14              132      SCONN288_ADR50001P003C01-SCONNA
GND                      J14              134      SCONN288_ADR50001P003C01-SCONNA
GND                      J14              136      SCONN288_ADR50001P003C01-SCONNA
GND                      J14              139      SCONN288_ADR50001P003C01-SCONNA
GND                      J14              141      SCONN288_ADR50001P003C01-SCONNA
GND                      J14              143      SCONN288_ADR50001P003C01-SCONNA
GND                      J14              151      SCONN288_ADR50001P003C01-SCONNA
GND                      J14              153      SCONN288_ADR50001P003C01-SCONNA
GND                      J14              155      SCONN288_ADR50001P003C01-SCONNA
GND                      J14              158      SCONN288_ADR50001P003C01-SCONNA
GND                      J14              160      SCONN288_ADR50001P003C01-SCONNA
GND                      J14              162      SCONN288_ADR50001P003C01-SCONNA
GND                      J14              164      SCONN288_ADR50001P003C01-SCONNA
GND                      J14              166      SCONN288_ADR50001P003C01-SCONNA
GND                      J14              169      SCONN288_ADR50001P003C01-SCONNA
GND                      J14              171      SCONN288_ADR50001P003C01-SCONNA
GND                      J14              173      SCONN288_ADR50001P003C01-SCONNA
GND                      J14              175      SCONN288_ADR50001P003C01-SCONNA
GND                      J14              177      SCONN288_ADR50001P003C01-SCONNA
GND                      J14              180      SCONN288_ADR50001P003C01-SCONNA
GND                      J14              182      SCONN288_ADR50001P003C01-SCONNA
GND                      J14              184      SCONN288_ADR50001P003C01-SCONNA
GND                      J14              186      SCONN288_ADR50001P003C01-SCONNA
GND                      J14              188      SCONN288_ADR50001P003C01-SCONNA
GND                      J14              191      SCONN288_ADR50001P003C01-SCONNA
GND                      J14              193      SCONN288_ADR50001P003C01-SCONNA
GND                      J14              195      SCONN288_ADR50001P003C01-SCONNA
GND                      J14              197      SCONN288_ADR50001P003C01-SCONNA
GND                      J14              199      SCONN288_ADR50001P003C01-SCONNA
GND                      J14              202      SCONN288_ADR50001P003C01-SCONNA
GND                      J14              204      SCONN288_ADR50001P003C01-SCONNA
GND                      J14              206      SCONN288_ADR50001P003C01-SCONNA
GND                      J14              208      SCONN288_ADR50001P003C01-SCONNA
GND                      J14              210      SCONN288_ADR50001P003C01-SCONNA
GND                      J14              212      SCONN288_ADR50001P003C01-SCONNA
GND                      J14              214      SCONN288_ADR50001P003C01-SCONNA
GND                      J14              216      SCONN288_ADR50001P003C01-SCONNA
GND                      J14              219      SCONN288_ADR50001P003C01-SCONNA
GND                      J14              222      SCONN288_ADR50001P003C01-SCONNA
GND                      J14              224      SCONN288_ADR50001P003C01-SCONNA
GND                      J14              226      SCONN288_ADR50001P003C01-SCONNA
GND                      J14              228      SCONN288_ADR50001P003C01-SCONNA
GND                      J14              230      SCONN288_ADR50001P003C01-SCONNA
GND                      J14              233      SCONN288_ADR50001P003C01-SCONNA
GND                      J14              235      SCONN288_ADR50001P003C01-SCONNA
GND                      J14              237      SCONN288_ADR50001P003C01-SCONNA
GND                      J14              240      SCONN288_ADR50001P003C01-SCONNA
GND                      J14              242      SCONN288_ADR50001P003C01-SCONNA
GND                      J14              244      SCONN288_ADR50001P003C01-SCONNA
GND                      J14              246      SCONN288_ADR50001P003C01-SCONNA
GND                      J14              248      SCONN288_ADR50001P003C01-SCONNA
GND                      J14              251      SCONN288_ADR50001P003C01-SCONNA
GND                      J14              253      SCONN288_ADR50001P003C01-SCONNA
GND                      J14              255      SCONN288_ADR50001P003C01-SCONNA
GND                      J14              257      SCONN288_ADR50001P003C01-SCONNA
GND                      J14              259      SCONN288_ADR50001P003C01-SCONNA
GND                      J14              262      SCONN288_ADR50001P003C01-SCONNA
GND                      J14              264      SCONN288_ADR50001P003C01-SCONNA
GND                      J14              266      SCONN288_ADR50001P003C01-SCONNA
GND                      J14              268      SCONN288_ADR50001P003C01-SCONNA
GND                      J14              270      SCONN288_ADR50001P003C01-SCONNA
GND                      J14              273      SCONN288_ADR50001P003C01-SCONNA
GND                      J14              275      SCONN288_ADR50001P003C01-SCONNA
GND                      J14              277      SCONN288_ADR50001P003C01-SCONNA
GND                      J14              279      SCONN288_ADR50001P003C01-SCONNA
GND                      J14              281      SCONN288_ADR50001P003C01-SCONNA
GND                      J14              284      SCONN288_ADR50001P003C01-SCONNA
GND                      J14              286      SCONN288_ADR50001P003C01-SCONNA
GND                      J14              288      SCONN288_ADR50001P003C01-SCONNA
GND                      J14              G1       SCONN288_ADR50001P003C01-SCONNA
GND                      J14              G2       SCONN288_ADR50001P003C01-SCONNA
GND                      J14              G3       SCONN288_ADR50001P003C01-SCONNA
GND                      J15              6        SCONN288_ADR50001P013C01-SCONNA
GND                      J15              8        SCONN288_ADR50001P013C01-SCONNA
GND                      J15              10       SCONN288_ADR50001P013C01-SCONNA
GND                      J15              13       SCONN288_ADR50001P013C01-SCONNA
GND                      J15              15       SCONN288_ADR50001P013C01-SCONNA
GND                      J15              17       SCONN288_ADR50001P013C01-SCONNA
GND                      J15              19       SCONN288_ADR50001P013C01-SCONNA
GND                      J15              21       SCONN288_ADR50001P013C01-SCONNA
GND                      J15              24       SCONN288_ADR50001P013C01-SCONNA
GND                      J15              26       SCONN288_ADR50001P013C01-SCONNA
GND                      J15              28       SCONN288_ADR50001P013C01-SCONNA
GND                      J15              30       SCONN288_ADR50001P013C01-SCONNA
GND                      J15              32       SCONN288_ADR50001P013C01-SCONNA
GND                      J15              35       SCONN288_ADR50001P013C01-SCONNA
GND                      J15              37       SCONN288_ADR50001P013C01-SCONNA
GND                      J15              39       SCONN288_ADR50001P013C01-SCONNA
GND                      J15              41       SCONN288_ADR50001P013C01-SCONNA
GND                      J15              43       SCONN288_ADR50001P013C01-SCONNA
GND                      J15              46       SCONN288_ADR50001P013C01-SCONNA
GND                      J15              48       SCONN288_ADR50001P013C01-SCONNA
GND                      J15              50       SCONN288_ADR50001P013C01-SCONNA
GND                      J15              52       SCONN288_ADR50001P013C01-SCONNA
GND                      J15              54       SCONN288_ADR50001P013C01-SCONNA
GND                      J15              57       SCONN288_ADR50001P013C01-SCONNA
GND                      J15              59       SCONN288_ADR50001P013C01-SCONNA
GND                      J15              61       SCONN288_ADR50001P013C01-SCONNA
GND                      J15              63       SCONN288_ADR50001P013C01-SCONNA
GND                      J15              65       SCONN288_ADR50001P013C01-SCONNA
GND                      J15              67       SCONN288_ADR50001P013C01-SCONNA
GND                      J15              69       SCONN288_ADR50001P013C01-SCONNA
GND                      J15              71       SCONN288_ADR50001P013C01-SCONNA
GND                      J15              73       SCONN288_ADR50001P013C01-SCONNA
GND                      J15              75       SCONN288_ADR50001P013C01-SCONNA
GND                      J15              77       SCONN288_ADR50001P013C01-SCONNA
GND                      J15              79       SCONN288_ADR50001P013C01-SCONNA
GND                      J15              81       SCONN288_ADR50001P013C01-SCONNA
GND                      J15              83       SCONN288_ADR50001P013C01-SCONNA
GND                      J15              85       SCONN288_ADR50001P013C01-SCONNA
GND                      J15              88       SCONN288_ADR50001P013C01-SCONNA
GND                      J15              90       SCONN288_ADR50001P013C01-SCONNA
GND                      J15              92       SCONN288_ADR50001P013C01-SCONNA
GND                      J15              95       SCONN288_ADR50001P013C01-SCONNA
GND                      J15              97       SCONN288_ADR50001P013C01-SCONNA
GND                      J15              99       SCONN288_ADR50001P013C01-SCONNA
GND                      J15              101      SCONN288_ADR50001P013C01-SCONNA
GND                      J15              103      SCONN288_ADR50001P013C01-SCONNA
GND                      J15              106      SCONN288_ADR50001P013C01-SCONNA
GND                      J15              108      SCONN288_ADR50001P013C01-SCONNA
GND                      J15              110      SCONN288_ADR50001P013C01-SCONNA
GND                      J15              112      SCONN288_ADR50001P013C01-SCONNA
GND                      J15              114      SCONN288_ADR50001P013C01-SCONNA
GND                      J15              117      SCONN288_ADR50001P013C01-SCONNA
GND                      J15              119      SCONN288_ADR50001P013C01-SCONNA
GND                      J15              121      SCONN288_ADR50001P013C01-SCONNA
GND                      J15              123      SCONN288_ADR50001P013C01-SCONNA
GND                      J15              125      SCONN288_ADR50001P013C01-SCONNA
GND                      J15              128      SCONN288_ADR50001P013C01-SCONNA
GND                      J15              130      SCONN288_ADR50001P013C01-SCONNA
GND                      J15              132      SCONN288_ADR50001P013C01-SCONNA
GND                      J15              134      SCONN288_ADR50001P013C01-SCONNA
GND                      J15              136      SCONN288_ADR50001P013C01-SCONNA
GND                      J15              139      SCONN288_ADR50001P013C01-SCONNA
GND                      J15              141      SCONN288_ADR50001P013C01-SCONNA
GND                      J15              143      SCONN288_ADR50001P013C01-SCONNA
GND                      J15              151      SCONN288_ADR50001P013C01-SCONNA
GND                      J15              153      SCONN288_ADR50001P013C01-SCONNA
GND                      J15              155      SCONN288_ADR50001P013C01-SCONNA
GND                      J15              158      SCONN288_ADR50001P013C01-SCONNA
GND                      J15              160      SCONN288_ADR50001P013C01-SCONNA
GND                      J15              162      SCONN288_ADR50001P013C01-SCONNA
GND                      J15              164      SCONN288_ADR50001P013C01-SCONNA
GND                      J15              166      SCONN288_ADR50001P013C01-SCONNA
GND                      J15              169      SCONN288_ADR50001P013C01-SCONNA
GND                      J15              171      SCONN288_ADR50001P013C01-SCONNA
GND                      J15              173      SCONN288_ADR50001P013C01-SCONNA
GND                      J15              175      SCONN288_ADR50001P013C01-SCONNA
GND                      J15              177      SCONN288_ADR50001P013C01-SCONNA
GND                      J15              180      SCONN288_ADR50001P013C01-SCONNA
GND                      J15              182      SCONN288_ADR50001P013C01-SCONNA
GND                      J15              184      SCONN288_ADR50001P013C01-SCONNA
GND                      J15              186      SCONN288_ADR50001P013C01-SCONNA
GND                      J15              188      SCONN288_ADR50001P013C01-SCONNA
GND                      J15              191      SCONN288_ADR50001P013C01-SCONNA
GND                      J15              193      SCONN288_ADR50001P013C01-SCONNA
GND                      J15              195      SCONN288_ADR50001P013C01-SCONNA
GND                      J15              197      SCONN288_ADR50001P013C01-SCONNA
GND                      J15              199      SCONN288_ADR50001P013C01-SCONNA
GND                      J15              202      SCONN288_ADR50001P013C01-SCONNA
GND                      J15              204      SCONN288_ADR50001P013C01-SCONNA
GND                      J15              206      SCONN288_ADR50001P013C01-SCONNA
GND                      J15              208      SCONN288_ADR50001P013C01-SCONNA
GND                      J15              210      SCONN288_ADR50001P013C01-SCONNA
GND                      J15              212      SCONN288_ADR50001P013C01-SCONNA
GND                      J15              214      SCONN288_ADR50001P013C01-SCONNA
GND                      J15              216      SCONN288_ADR50001P013C01-SCONNA
GND                      J15              219      SCONN288_ADR50001P013C01-SCONNA
GND                      J15              222      SCONN288_ADR50001P013C01-SCONNA
GND                      J15              224      SCONN288_ADR50001P013C01-SCONNA
GND                      J15              226      SCONN288_ADR50001P013C01-SCONNA
GND                      J15              228      SCONN288_ADR50001P013C01-SCONNA
GND                      J15              230      SCONN288_ADR50001P013C01-SCONNA
GND                      J15              233      SCONN288_ADR50001P013C01-SCONNA
GND                      J15              235      SCONN288_ADR50001P013C01-SCONNA
GND                      J15              237      SCONN288_ADR50001P013C01-SCONNA
GND                      J15              240      SCONN288_ADR50001P013C01-SCONNA
GND                      J15              242      SCONN288_ADR50001P013C01-SCONNA
GND                      J15              244      SCONN288_ADR50001P013C01-SCONNA
GND                      J15              246      SCONN288_ADR50001P013C01-SCONNA
GND                      J15              248      SCONN288_ADR50001P013C01-SCONNA
GND                      J15              251      SCONN288_ADR50001P013C01-SCONNA
GND                      J15              253      SCONN288_ADR50001P013C01-SCONNA
GND                      J15              255      SCONN288_ADR50001P013C01-SCONNA
GND                      J15              257      SCONN288_ADR50001P013C01-SCONNA
GND                      J15              259      SCONN288_ADR50001P013C01-SCONNA
GND                      J15              262      SCONN288_ADR50001P013C01-SCONNA
GND                      J15              264      SCONN288_ADR50001P013C01-SCONNA
GND                      J15              266      SCONN288_ADR50001P013C01-SCONNA
GND                      J15              268      SCONN288_ADR50001P013C01-SCONNA
GND                      J15              270      SCONN288_ADR50001P013C01-SCONNA
GND                      J15              273      SCONN288_ADR50001P013C01-SCONNA
GND                      J15              275      SCONN288_ADR50001P013C01-SCONNA
GND                      J15              277      SCONN288_ADR50001P013C01-SCONNA
GND                      J15              279      SCONN288_ADR50001P013C01-SCONNA
GND                      J15              281      SCONN288_ADR50001P013C01-SCONNA
GND                      J15              284      SCONN288_ADR50001P013C01-SCONNA
GND                      J15              286      SCONN288_ADR50001P013C01-SCONNA
GND                      J15              288      SCONN288_ADR50001P013C01-SCONNA
GND                      J15              G1       SCONN288_ADR50001P013C01-SCONNA
GND                      J15              G2       SCONN288_ADR50001P013C01-SCONNA
GND                      J15              G3       SCONN288_ADR50001P013C01-SCONNA
GND                      J16              6        SCONN288_ADR50001P003C01-SCONNA
GND                      J16              8        SCONN288_ADR50001P003C01-SCONNA
GND                      J16              10       SCONN288_ADR50001P003C01-SCONNA
GND                      J16              13       SCONN288_ADR50001P003C01-SCONNA
GND                      J16              15       SCONN288_ADR50001P003C01-SCONNA
GND                      J16              17       SCONN288_ADR50001P003C01-SCONNA
GND                      J16              19       SCONN288_ADR50001P003C01-SCONNA
GND                      J16              21       SCONN288_ADR50001P003C01-SCONNA
GND                      J16              24       SCONN288_ADR50001P003C01-SCONNA
GND                      J16              26       SCONN288_ADR50001P003C01-SCONNA
GND                      J16              28       SCONN288_ADR50001P003C01-SCONNA
GND                      J16              30       SCONN288_ADR50001P003C01-SCONNA
GND                      J16              32       SCONN288_ADR50001P003C01-SCONNA
GND                      J16              35       SCONN288_ADR50001P003C01-SCONNA
GND                      J16              37       SCONN288_ADR50001P003C01-SCONNA
GND                      J16              39       SCONN288_ADR50001P003C01-SCONNA
GND                      J16              41       SCONN288_ADR50001P003C01-SCONNA
GND                      J16              43       SCONN288_ADR50001P003C01-SCONNA
GND                      J16              46       SCONN288_ADR50001P003C01-SCONNA
GND                      J16              48       SCONN288_ADR50001P003C01-SCONNA
GND                      J16              50       SCONN288_ADR50001P003C01-SCONNA
GND                      J16              52       SCONN288_ADR50001P003C01-SCONNA
GND                      J16              54       SCONN288_ADR50001P003C01-SCONNA
GND                      J16              57       SCONN288_ADR50001P003C01-SCONNA
GND                      J16              59       SCONN288_ADR50001P003C01-SCONNA
GND                      J16              61       SCONN288_ADR50001P003C01-SCONNA
GND                      J16              63       SCONN288_ADR50001P003C01-SCONNA
GND                      J16              65       SCONN288_ADR50001P003C01-SCONNA
GND                      J16              67       SCONN288_ADR50001P003C01-SCONNA
GND                      J16              69       SCONN288_ADR50001P003C01-SCONNA
GND                      J16              71       SCONN288_ADR50001P003C01-SCONNA
GND                      J16              73       SCONN288_ADR50001P003C01-SCONNA
GND                      J16              75       SCONN288_ADR50001P003C01-SCONNA
GND                      J16              77       SCONN288_ADR50001P003C01-SCONNA
GND                      J16              79       SCONN288_ADR50001P003C01-SCONNA
GND                      J16              81       SCONN288_ADR50001P003C01-SCONNA
GND                      J16              83       SCONN288_ADR50001P003C01-SCONNA
GND                      J16              85       SCONN288_ADR50001P003C01-SCONNA
GND                      J16              88       SCONN288_ADR50001P003C01-SCONNA
GND                      J16              90       SCONN288_ADR50001P003C01-SCONNA
GND                      J16              92       SCONN288_ADR50001P003C01-SCONNA
GND                      J16              95       SCONN288_ADR50001P003C01-SCONNA
GND                      J16              97       SCONN288_ADR50001P003C01-SCONNA
GND                      J16              99       SCONN288_ADR50001P003C01-SCONNA
GND                      J16              101      SCONN288_ADR50001P003C01-SCONNA
GND                      J16              103      SCONN288_ADR50001P003C01-SCONNA
GND                      J16              106      SCONN288_ADR50001P003C01-SCONNA
GND                      J16              108      SCONN288_ADR50001P003C01-SCONNA
GND                      J16              110      SCONN288_ADR50001P003C01-SCONNA
GND                      J16              112      SCONN288_ADR50001P003C01-SCONNA
GND                      J16              114      SCONN288_ADR50001P003C01-SCONNA
GND                      J16              117      SCONN288_ADR50001P003C01-SCONNA
GND                      J16              119      SCONN288_ADR50001P003C01-SCONNA
GND                      J16              121      SCONN288_ADR50001P003C01-SCONNA
GND                      J16              123      SCONN288_ADR50001P003C01-SCONNA
GND                      J16              125      SCONN288_ADR50001P003C01-SCONNA
GND                      J16              128      SCONN288_ADR50001P003C01-SCONNA
GND                      J16              130      SCONN288_ADR50001P003C01-SCONNA
GND                      J16              132      SCONN288_ADR50001P003C01-SCONNA
GND                      J16              134      SCONN288_ADR50001P003C01-SCONNA
GND                      J16              136      SCONN288_ADR50001P003C01-SCONNA
GND                      J16              139      SCONN288_ADR50001P003C01-SCONNA
GND                      J16              141      SCONN288_ADR50001P003C01-SCONNA
GND                      J16              143      SCONN288_ADR50001P003C01-SCONNA
GND                      J16              151      SCONN288_ADR50001P003C01-SCONNA
GND                      J16              153      SCONN288_ADR50001P003C01-SCONNA
GND                      J16              155      SCONN288_ADR50001P003C01-SCONNA
GND                      J16              158      SCONN288_ADR50001P003C01-SCONNA
GND                      J16              160      SCONN288_ADR50001P003C01-SCONNA
GND                      J16              162      SCONN288_ADR50001P003C01-SCONNA
GND                      J16              164      SCONN288_ADR50001P003C01-SCONNA
GND                      J16              166      SCONN288_ADR50001P003C01-SCONNA
GND                      J16              169      SCONN288_ADR50001P003C01-SCONNA
GND                      J16              171      SCONN288_ADR50001P003C01-SCONNA
GND                      J16              173      SCONN288_ADR50001P003C01-SCONNA
GND                      J16              175      SCONN288_ADR50001P003C01-SCONNA
GND                      J16              177      SCONN288_ADR50001P003C01-SCONNA
GND                      J16              180      SCONN288_ADR50001P003C01-SCONNA
GND                      J16              182      SCONN288_ADR50001P003C01-SCONNA
GND                      J16              184      SCONN288_ADR50001P003C01-SCONNA
GND                      J16              186      SCONN288_ADR50001P003C01-SCONNA
GND                      J16              188      SCONN288_ADR50001P003C01-SCONNA
GND                      J16              191      SCONN288_ADR50001P003C01-SCONNA
GND                      J16              193      SCONN288_ADR50001P003C01-SCONNA
GND                      J16              195      SCONN288_ADR50001P003C01-SCONNA
GND                      J16              197      SCONN288_ADR50001P003C01-SCONNA
GND                      J16              199      SCONN288_ADR50001P003C01-SCONNA
GND                      J16              202      SCONN288_ADR50001P003C01-SCONNA
GND                      J16              204      SCONN288_ADR50001P003C01-SCONNA
GND                      J16              206      SCONN288_ADR50001P003C01-SCONNA
GND                      J16              208      SCONN288_ADR50001P003C01-SCONNA
GND                      J16              210      SCONN288_ADR50001P003C01-SCONNA
GND                      J16              212      SCONN288_ADR50001P003C01-SCONNA
GND                      J16              214      SCONN288_ADR50001P003C01-SCONNA
GND                      J16              216      SCONN288_ADR50001P003C01-SCONNA
GND                      J16              219      SCONN288_ADR50001P003C01-SCONNA
GND                      J16              222      SCONN288_ADR50001P003C01-SCONNA
GND                      J16              224      SCONN288_ADR50001P003C01-SCONNA
GND                      J16              226      SCONN288_ADR50001P003C01-SCONNA
GND                      J16              228      SCONN288_ADR50001P003C01-SCONNA
GND                      J16              230      SCONN288_ADR50001P003C01-SCONNA
GND                      J16              233      SCONN288_ADR50001P003C01-SCONNA
GND                      J16              235      SCONN288_ADR50001P003C01-SCONNA
GND                      J16              237      SCONN288_ADR50001P003C01-SCONNA
GND                      J16              240      SCONN288_ADR50001P003C01-SCONNA
GND                      J16              242      SCONN288_ADR50001P003C01-SCONNA
GND                      J16              244      SCONN288_ADR50001P003C01-SCONNA
GND                      J16              246      SCONN288_ADR50001P003C01-SCONNA
GND                      J16              248      SCONN288_ADR50001P003C01-SCONNA
GND                      J16              251      SCONN288_ADR50001P003C01-SCONNA
GND                      J16              253      SCONN288_ADR50001P003C01-SCONNA
GND                      J16              255      SCONN288_ADR50001P003C01-SCONNA
GND                      J16              257      SCONN288_ADR50001P003C01-SCONNA
GND                      J16              259      SCONN288_ADR50001P003C01-SCONNA
GND                      J16              262      SCONN288_ADR50001P003C01-SCONNA
GND                      J16              264      SCONN288_ADR50001P003C01-SCONNA
GND                      J16              266      SCONN288_ADR50001P003C01-SCONNA
GND                      J16              268      SCONN288_ADR50001P003C01-SCONNA
GND                      J16              270      SCONN288_ADR50001P003C01-SCONNA
GND                      J16              273      SCONN288_ADR50001P003C01-SCONNA
GND                      J16              275      SCONN288_ADR50001P003C01-SCONNA
GND                      J16              277      SCONN288_ADR50001P003C01-SCONNA
GND                      J16              279      SCONN288_ADR50001P003C01-SCONNA
GND                      J16              281      SCONN288_ADR50001P003C01-SCONNA
GND                      J16              284      SCONN288_ADR50001P003C01-SCONNA
GND                      J16              286      SCONN288_ADR50001P003C01-SCONNA
GND                      J16              288      SCONN288_ADR50001P003C01-SCONNA
GND                      J16              G1       SCONN288_ADR50001P003C01-SCONNA
GND                      J16              G2       SCONN288_ADR50001P003C01-SCONNA
GND                      J16              G3       SCONN288_ADR50001P003C01-SCONNA
GND                      J17              6        SCONN288_ADR50001P013C01-SCONNA
GND                      J17              8        SCONN288_ADR50001P013C01-SCONNA
GND                      J17              10       SCONN288_ADR50001P013C01-SCONNA
GND                      J17              13       SCONN288_ADR50001P013C01-SCONNA
GND                      J17              15       SCONN288_ADR50001P013C01-SCONNA
GND                      J17              17       SCONN288_ADR50001P013C01-SCONNA
GND                      J17              19       SCONN288_ADR50001P013C01-SCONNA
GND                      J17              21       SCONN288_ADR50001P013C01-SCONNA
GND                      J17              24       SCONN288_ADR50001P013C01-SCONNA
GND                      J17              26       SCONN288_ADR50001P013C01-SCONNA
GND                      J17              28       SCONN288_ADR50001P013C01-SCONNA
GND                      J17              30       SCONN288_ADR50001P013C01-SCONNA
GND                      J17              32       SCONN288_ADR50001P013C01-SCONNA
GND                      J17              35       SCONN288_ADR50001P013C01-SCONNA
GND                      J17              37       SCONN288_ADR50001P013C01-SCONNA
GND                      J17              39       SCONN288_ADR50001P013C01-SCONNA
GND                      J17              41       SCONN288_ADR50001P013C01-SCONNA
GND                      J17              43       SCONN288_ADR50001P013C01-SCONNA
GND                      J17              46       SCONN288_ADR50001P013C01-SCONNA
GND                      J17              48       SCONN288_ADR50001P013C01-SCONNA
GND                      J17              50       SCONN288_ADR50001P013C01-SCONNA
GND                      J17              52       SCONN288_ADR50001P013C01-SCONNA
GND                      J17              54       SCONN288_ADR50001P013C01-SCONNA
GND                      J17              57       SCONN288_ADR50001P013C01-SCONNA
GND                      J17              59       SCONN288_ADR50001P013C01-SCONNA
GND                      J17              61       SCONN288_ADR50001P013C01-SCONNA
GND                      J17              63       SCONN288_ADR50001P013C01-SCONNA
GND                      J17              65       SCONN288_ADR50001P013C01-SCONNA
GND                      J17              67       SCONN288_ADR50001P013C01-SCONNA
GND                      J17              69       SCONN288_ADR50001P013C01-SCONNA
GND                      J17              71       SCONN288_ADR50001P013C01-SCONNA
GND                      J17              73       SCONN288_ADR50001P013C01-SCONNA
GND                      J17              75       SCONN288_ADR50001P013C01-SCONNA
GND                      J17              77       SCONN288_ADR50001P013C01-SCONNA
GND                      J17              79       SCONN288_ADR50001P013C01-SCONNA
GND                      J17              81       SCONN288_ADR50001P013C01-SCONNA
GND                      J17              83       SCONN288_ADR50001P013C01-SCONNA
GND                      J17              85       SCONN288_ADR50001P013C01-SCONNA
GND                      J17              88       SCONN288_ADR50001P013C01-SCONNA
GND                      J17              90       SCONN288_ADR50001P013C01-SCONNA
GND                      J17              92       SCONN288_ADR50001P013C01-SCONNA
GND                      J17              95       SCONN288_ADR50001P013C01-SCONNA
GND                      J17              97       SCONN288_ADR50001P013C01-SCONNA
GND                      J17              99       SCONN288_ADR50001P013C01-SCONNA
GND                      J17              101      SCONN288_ADR50001P013C01-SCONNA
GND                      J17              103      SCONN288_ADR50001P013C01-SCONNA
GND                      J17              106      SCONN288_ADR50001P013C01-SCONNA
GND                      J17              108      SCONN288_ADR50001P013C01-SCONNA
GND                      J17              110      SCONN288_ADR50001P013C01-SCONNA
GND                      J17              112      SCONN288_ADR50001P013C01-SCONNA
GND                      J17              114      SCONN288_ADR50001P013C01-SCONNA
GND                      J17              117      SCONN288_ADR50001P013C01-SCONNA
GND                      J17              119      SCONN288_ADR50001P013C01-SCONNA
GND                      J17              121      SCONN288_ADR50001P013C01-SCONNA
GND                      J17              123      SCONN288_ADR50001P013C01-SCONNA
GND                      J17              125      SCONN288_ADR50001P013C01-SCONNA
GND                      J17              128      SCONN288_ADR50001P013C01-SCONNA
GND                      J17              130      SCONN288_ADR50001P013C01-SCONNA
GND                      J17              132      SCONN288_ADR50001P013C01-SCONNA
GND                      J17              134      SCONN288_ADR50001P013C01-SCONNA
GND                      J17              136      SCONN288_ADR50001P013C01-SCONNA
GND                      J17              139      SCONN288_ADR50001P013C01-SCONNA
GND                      J17              141      SCONN288_ADR50001P013C01-SCONNA
GND                      J17              143      SCONN288_ADR50001P013C01-SCONNA
GND                      J17              151      SCONN288_ADR50001P013C01-SCONNA
GND                      J17              153      SCONN288_ADR50001P013C01-SCONNA
GND                      J17              155      SCONN288_ADR50001P013C01-SCONNA
GND                      J17              158      SCONN288_ADR50001P013C01-SCONNA
GND                      J17              160      SCONN288_ADR50001P013C01-SCONNA
GND                      J17              162      SCONN288_ADR50001P013C01-SCONNA
GND                      J17              164      SCONN288_ADR50001P013C01-SCONNA
GND                      J17              166      SCONN288_ADR50001P013C01-SCONNA
GND                      J17              169      SCONN288_ADR50001P013C01-SCONNA
GND                      J17              171      SCONN288_ADR50001P013C01-SCONNA
GND                      J17              173      SCONN288_ADR50001P013C01-SCONNA
GND                      J17              175      SCONN288_ADR50001P013C01-SCONNA
GND                      J17              177      SCONN288_ADR50001P013C01-SCONNA
GND                      J17              180      SCONN288_ADR50001P013C01-SCONNA
GND                      J17              182      SCONN288_ADR50001P013C01-SCONNA
GND                      J17              184      SCONN288_ADR50001P013C01-SCONNA
GND                      J17              186      SCONN288_ADR50001P013C01-SCONNA
GND                      J17              188      SCONN288_ADR50001P013C01-SCONNA
GND                      J17              191      SCONN288_ADR50001P013C01-SCONNA
GND                      J17              193      SCONN288_ADR50001P013C01-SCONNA
GND                      J17              195      SCONN288_ADR50001P013C01-SCONNA
GND                      J17              197      SCONN288_ADR50001P013C01-SCONNA
GND                      J17              199      SCONN288_ADR50001P013C01-SCONNA
GND                      J17              202      SCONN288_ADR50001P013C01-SCONNA
GND                      J17              204      SCONN288_ADR50001P013C01-SCONNA
GND                      J17              206      SCONN288_ADR50001P013C01-SCONNA
GND                      J17              208      SCONN288_ADR50001P013C01-SCONNA
GND                      J17              210      SCONN288_ADR50001P013C01-SCONNA
GND                      J17              212      SCONN288_ADR50001P013C01-SCONNA
GND                      J17              214      SCONN288_ADR50001P013C01-SCONNA
GND                      J17              216      SCONN288_ADR50001P013C01-SCONNA
GND                      J17              219      SCONN288_ADR50001P013C01-SCONNA
GND                      J17              222      SCONN288_ADR50001P013C01-SCONNA
GND                      J17              224      SCONN288_ADR50001P013C01-SCONNA
GND                      J17              226      SCONN288_ADR50001P013C01-SCONNA
GND                      J17              228      SCONN288_ADR50001P013C01-SCONNA
GND                      J17              230      SCONN288_ADR50001P013C01-SCONNA
GND                      J17              233      SCONN288_ADR50001P013C01-SCONNA
GND                      J17              235      SCONN288_ADR50001P013C01-SCONNA
GND                      J17              237      SCONN288_ADR50001P013C01-SCONNA
GND                      J17              240      SCONN288_ADR50001P013C01-SCONNA
GND                      J17              242      SCONN288_ADR50001P013C01-SCONNA
GND                      J17              244      SCONN288_ADR50001P013C01-SCONNA
GND                      J17              246      SCONN288_ADR50001P013C01-SCONNA
GND                      J17              248      SCONN288_ADR50001P013C01-SCONNA
GND                      J17              251      SCONN288_ADR50001P013C01-SCONNA
GND                      J17              253      SCONN288_ADR50001P013C01-SCONNA
GND                      J17              255      SCONN288_ADR50001P013C01-SCONNA
GND                      J17              257      SCONN288_ADR50001P013C01-SCONNA
GND                      J17              259      SCONN288_ADR50001P013C01-SCONNA
GND                      J17              262      SCONN288_ADR50001P013C01-SCONNA
GND                      J17              264      SCONN288_ADR50001P013C01-SCONNA
GND                      J17              266      SCONN288_ADR50001P013C01-SCONNA
GND                      J17              268      SCONN288_ADR50001P013C01-SCONNA
GND                      J17              270      SCONN288_ADR50001P013C01-SCONNA
GND                      J17              273      SCONN288_ADR50001P013C01-SCONNA
GND                      J17              275      SCONN288_ADR50001P013C01-SCONNA
GND                      J17              277      SCONN288_ADR50001P013C01-SCONNA
GND                      J17              279      SCONN288_ADR50001P013C01-SCONNA
GND                      J17              281      SCONN288_ADR50001P013C01-SCONNA
GND                      J17              284      SCONN288_ADR50001P013C01-SCONNA
GND                      J17              286      SCONN288_ADR50001P013C01-SCONNA
GND                      J17              288      SCONN288_ADR50001P013C01-SCONNA
GND                      J17              G1       SCONN288_ADR50001P013C01-SCONNA
GND                      J17              G2       SCONN288_ADR50001P013C01-SCONNA
GND                      J17              G3       SCONN288_ADR50001P013C01-SCONNA
GND                      J18              6        SCONN288_ADR50001P003C01-SCONNA
GND                      J18              8        SCONN288_ADR50001P003C01-SCONNA
GND                      J18              10       SCONN288_ADR50001P003C01-SCONNA
GND                      J18              13       SCONN288_ADR50001P003C01-SCONNA
GND                      J18              15       SCONN288_ADR50001P003C01-SCONNA
GND                      J18              17       SCONN288_ADR50001P003C01-SCONNA
GND                      J18              19       SCONN288_ADR50001P003C01-SCONNA
GND                      J18              21       SCONN288_ADR50001P003C01-SCONNA
GND                      J18              24       SCONN288_ADR50001P003C01-SCONNA
GND                      J18              26       SCONN288_ADR50001P003C01-SCONNA
GND                      J18              28       SCONN288_ADR50001P003C01-SCONNA
GND                      J18              30       SCONN288_ADR50001P003C01-SCONNA
GND                      J18              32       SCONN288_ADR50001P003C01-SCONNA
GND                      J18              35       SCONN288_ADR50001P003C01-SCONNA
GND                      J18              37       SCONN288_ADR50001P003C01-SCONNA
GND                      J18              39       SCONN288_ADR50001P003C01-SCONNA
GND                      J18              41       SCONN288_ADR50001P003C01-SCONNA
GND                      J18              43       SCONN288_ADR50001P003C01-SCONNA
GND                      J18              46       SCONN288_ADR50001P003C01-SCONNA
GND                      J18              48       SCONN288_ADR50001P003C01-SCONNA
GND                      J18              50       SCONN288_ADR50001P003C01-SCONNA
GND                      J18              52       SCONN288_ADR50001P003C01-SCONNA
GND                      J18              54       SCONN288_ADR50001P003C01-SCONNA
GND                      J18              57       SCONN288_ADR50001P003C01-SCONNA
GND                      J18              59       SCONN288_ADR50001P003C01-SCONNA
GND                      J18              61       SCONN288_ADR50001P003C01-SCONNA
GND                      J18              63       SCONN288_ADR50001P003C01-SCONNA
GND                      J18              65       SCONN288_ADR50001P003C01-SCONNA
GND                      J18              67       SCONN288_ADR50001P003C01-SCONNA
GND                      J18              69       SCONN288_ADR50001P003C01-SCONNA
GND                      J18              71       SCONN288_ADR50001P003C01-SCONNA
GND                      J18              73       SCONN288_ADR50001P003C01-SCONNA
GND                      J18              75       SCONN288_ADR50001P003C01-SCONNA
GND                      J18              77       SCONN288_ADR50001P003C01-SCONNA
GND                      J18              79       SCONN288_ADR50001P003C01-SCONNA
GND                      J18              81       SCONN288_ADR50001P003C01-SCONNA
GND                      J18              83       SCONN288_ADR50001P003C01-SCONNA
GND                      J18              85       SCONN288_ADR50001P003C01-SCONNA
GND                      J18              88       SCONN288_ADR50001P003C01-SCONNA
GND                      J18              90       SCONN288_ADR50001P003C01-SCONNA
GND                      J18              92       SCONN288_ADR50001P003C01-SCONNA
GND                      J18              95       SCONN288_ADR50001P003C01-SCONNA
GND                      J18              97       SCONN288_ADR50001P003C01-SCONNA
GND                      J18              99       SCONN288_ADR50001P003C01-SCONNA
GND                      J18              101      SCONN288_ADR50001P003C01-SCONNA
GND                      J18              103      SCONN288_ADR50001P003C01-SCONNA
GND                      J18              106      SCONN288_ADR50001P003C01-SCONNA
GND                      J18              108      SCONN288_ADR50001P003C01-SCONNA
GND                      J18              110      SCONN288_ADR50001P003C01-SCONNA
GND                      J18              112      SCONN288_ADR50001P003C01-SCONNA
GND                      J18              114      SCONN288_ADR50001P003C01-SCONNA
GND                      J18              117      SCONN288_ADR50001P003C01-SCONNA
GND                      J18              119      SCONN288_ADR50001P003C01-SCONNA
GND                      J18              121      SCONN288_ADR50001P003C01-SCONNA
GND                      J18              123      SCONN288_ADR50001P003C01-SCONNA
GND                      J18              125      SCONN288_ADR50001P003C01-SCONNA
GND                      J18              128      SCONN288_ADR50001P003C01-SCONNA
GND                      J18              130      SCONN288_ADR50001P003C01-SCONNA
GND                      J18              132      SCONN288_ADR50001P003C01-SCONNA
GND                      J18              134      SCONN288_ADR50001P003C01-SCONNA
GND                      J18              136      SCONN288_ADR50001P003C01-SCONNA
GND                      J18              139      SCONN288_ADR50001P003C01-SCONNA
GND                      J18              141      SCONN288_ADR50001P003C01-SCONNA
GND                      J18              143      SCONN288_ADR50001P003C01-SCONNA
GND                      J18              151      SCONN288_ADR50001P003C01-SCONNA
GND                      J18              153      SCONN288_ADR50001P003C01-SCONNA
GND                      J18              155      SCONN288_ADR50001P003C01-SCONNA
GND                      J18              158      SCONN288_ADR50001P003C01-SCONNA
GND                      J18              160      SCONN288_ADR50001P003C01-SCONNA
GND                      J18              162      SCONN288_ADR50001P003C01-SCONNA
GND                      J18              164      SCONN288_ADR50001P003C01-SCONNA
GND                      J18              166      SCONN288_ADR50001P003C01-SCONNA
GND                      J18              169      SCONN288_ADR50001P003C01-SCONNA
GND                      J18              171      SCONN288_ADR50001P003C01-SCONNA
GND                      J18              173      SCONN288_ADR50001P003C01-SCONNA
GND                      J18              175      SCONN288_ADR50001P003C01-SCONNA
GND                      J18              177      SCONN288_ADR50001P003C01-SCONNA
GND                      J18              180      SCONN288_ADR50001P003C01-SCONNA
GND                      J18              182      SCONN288_ADR50001P003C01-SCONNA
GND                      J18              184      SCONN288_ADR50001P003C01-SCONNA
GND                      J18              186      SCONN288_ADR50001P003C01-SCONNA
GND                      J18              188      SCONN288_ADR50001P003C01-SCONNA
GND                      J18              191      SCONN288_ADR50001P003C01-SCONNA
GND                      J18              193      SCONN288_ADR50001P003C01-SCONNA
GND                      J18              195      SCONN288_ADR50001P003C01-SCONNA
GND                      J18              197      SCONN288_ADR50001P003C01-SCONNA
GND                      J18              199      SCONN288_ADR50001P003C01-SCONNA
GND                      J18              202      SCONN288_ADR50001P003C01-SCONNA
GND                      J18              204      SCONN288_ADR50001P003C01-SCONNA
GND                      J18              206      SCONN288_ADR50001P003C01-SCONNA
GND                      J18              208      SCONN288_ADR50001P003C01-SCONNA
GND                      J18              210      SCONN288_ADR50001P003C01-SCONNA
GND                      J18              212      SCONN288_ADR50001P003C01-SCONNA
GND                      J18              214      SCONN288_ADR50001P003C01-SCONNA
GND                      J18              216      SCONN288_ADR50001P003C01-SCONNA
GND                      J18              219      SCONN288_ADR50001P003C01-SCONNA
GND                      J18              222      SCONN288_ADR50001P003C01-SCONNA
GND                      J18              224      SCONN288_ADR50001P003C01-SCONNA
GND                      J18              226      SCONN288_ADR50001P003C01-SCONNA
GND                      J18              228      SCONN288_ADR50001P003C01-SCONNA
GND                      J18              230      SCONN288_ADR50001P003C01-SCONNA
GND                      J18              233      SCONN288_ADR50001P003C01-SCONNA
GND                      J18              235      SCONN288_ADR50001P003C01-SCONNA
GND                      J18              237      SCONN288_ADR50001P003C01-SCONNA
GND                      J18              240      SCONN288_ADR50001P003C01-SCONNA
GND                      J18              242      SCONN288_ADR50001P003C01-SCONNA
GND                      J18              244      SCONN288_ADR50001P003C01-SCONNA
GND                      J18              246      SCONN288_ADR50001P003C01-SCONNA
GND                      J18              248      SCONN288_ADR50001P003C01-SCONNA
GND                      J18              251      SCONN288_ADR50001P003C01-SCONNA
GND                      J18              253      SCONN288_ADR50001P003C01-SCONNA
GND                      J18              255      SCONN288_ADR50001P003C01-SCONNA
GND                      J18              257      SCONN288_ADR50001P003C01-SCONNA
GND                      J18              259      SCONN288_ADR50001P003C01-SCONNA
GND                      J18              262      SCONN288_ADR50001P003C01-SCONNA
GND                      J18              264      SCONN288_ADR50001P003C01-SCONNA
GND                      J18              266      SCONN288_ADR50001P003C01-SCONNA
GND                      J18              268      SCONN288_ADR50001P003C01-SCONNA
GND                      J18              270      SCONN288_ADR50001P003C01-SCONNA
GND                      J18              273      SCONN288_ADR50001P003C01-SCONNA
GND                      J18              275      SCONN288_ADR50001P003C01-SCONNA
GND                      J18              277      SCONN288_ADR50001P003C01-SCONNA
GND                      J18              279      SCONN288_ADR50001P003C01-SCONNA
GND                      J18              281      SCONN288_ADR50001P003C01-SCONNA
GND                      J18              284      SCONN288_ADR50001P003C01-SCONNA
GND                      J18              286      SCONN288_ADR50001P003C01-SCONNA
GND                      J18              288      SCONN288_ADR50001P003C01-SCONNA
GND                      J18              G1       SCONN288_ADR50001P003C01-SCONNA
GND                      J18              G2       SCONN288_ADR50001P003C01-SCONNA
GND                      J18              G3       SCONN288_ADR50001P003C01-SCONNA
GND                      J19              6        SCONN288_ADR50001P013C01-SCONNA
GND                      J19              8        SCONN288_ADR50001P013C01-SCONNA
GND                      J19              10       SCONN288_ADR50001P013C01-SCONNA
GND                      J19              13       SCONN288_ADR50001P013C01-SCONNA
GND                      J19              15       SCONN288_ADR50001P013C01-SCONNA
GND                      J19              17       SCONN288_ADR50001P013C01-SCONNA
GND                      J19              19       SCONN288_ADR50001P013C01-SCONNA
GND                      J19              21       SCONN288_ADR50001P013C01-SCONNA
GND                      J19              24       SCONN288_ADR50001P013C01-SCONNA
GND                      J19              26       SCONN288_ADR50001P013C01-SCONNA
GND                      J19              28       SCONN288_ADR50001P013C01-SCONNA
GND                      J19              30       SCONN288_ADR50001P013C01-SCONNA
GND                      J19              32       SCONN288_ADR50001P013C01-SCONNA
GND                      J19              35       SCONN288_ADR50001P013C01-SCONNA
GND                      J19              37       SCONN288_ADR50001P013C01-SCONNA
GND                      J19              39       SCONN288_ADR50001P013C01-SCONNA
GND                      J19              41       SCONN288_ADR50001P013C01-SCONNA
GND                      J19              43       SCONN288_ADR50001P013C01-SCONNA
GND                      J19              46       SCONN288_ADR50001P013C01-SCONNA
GND                      J19              48       SCONN288_ADR50001P013C01-SCONNA
GND                      J19              50       SCONN288_ADR50001P013C01-SCONNA
GND                      J19              52       SCONN288_ADR50001P013C01-SCONNA
GND                      J19              54       SCONN288_ADR50001P013C01-SCONNA
GND                      J19              57       SCONN288_ADR50001P013C01-SCONNA
GND                      J19              59       SCONN288_ADR50001P013C01-SCONNA
GND                      J19              61       SCONN288_ADR50001P013C01-SCONNA
GND                      J19              63       SCONN288_ADR50001P013C01-SCONNA
GND                      J19              65       SCONN288_ADR50001P013C01-SCONNA
GND                      J19              67       SCONN288_ADR50001P013C01-SCONNA
GND                      J19              69       SCONN288_ADR50001P013C01-SCONNA
GND                      J19              71       SCONN288_ADR50001P013C01-SCONNA
GND                      J19              73       SCONN288_ADR50001P013C01-SCONNA
GND                      J19              75       SCONN288_ADR50001P013C01-SCONNA
GND                      J19              77       SCONN288_ADR50001P013C01-SCONNA
GND                      J19              79       SCONN288_ADR50001P013C01-SCONNA
GND                      J19              81       SCONN288_ADR50001P013C01-SCONNA
GND                      J19              83       SCONN288_ADR50001P013C01-SCONNA
GND                      J19              85       SCONN288_ADR50001P013C01-SCONNA
GND                      J19              88       SCONN288_ADR50001P013C01-SCONNA
GND                      J19              90       SCONN288_ADR50001P013C01-SCONNA
GND                      J19              92       SCONN288_ADR50001P013C01-SCONNA
GND                      J19              95       SCONN288_ADR50001P013C01-SCONNA
GND                      J19              97       SCONN288_ADR50001P013C01-SCONNA
GND                      J19              99       SCONN288_ADR50001P013C01-SCONNA
GND                      J19              101      SCONN288_ADR50001P013C01-SCONNA
GND                      J19              103      SCONN288_ADR50001P013C01-SCONNA
GND                      J19              106      SCONN288_ADR50001P013C01-SCONNA
GND                      J19              108      SCONN288_ADR50001P013C01-SCONNA
GND                      J19              110      SCONN288_ADR50001P013C01-SCONNA
GND                      J19              112      SCONN288_ADR50001P013C01-SCONNA
GND                      J19              114      SCONN288_ADR50001P013C01-SCONNA
GND                      J19              117      SCONN288_ADR50001P013C01-SCONNA
GND                      J19              119      SCONN288_ADR50001P013C01-SCONNA
GND                      J19              121      SCONN288_ADR50001P013C01-SCONNA
GND                      J19              123      SCONN288_ADR50001P013C01-SCONNA
GND                      J19              125      SCONN288_ADR50001P013C01-SCONNA
GND                      J19              128      SCONN288_ADR50001P013C01-SCONNA
GND                      J19              130      SCONN288_ADR50001P013C01-SCONNA
GND                      J19              132      SCONN288_ADR50001P013C01-SCONNA
GND                      J19              134      SCONN288_ADR50001P013C01-SCONNA
GND                      J19              136      SCONN288_ADR50001P013C01-SCONNA
GND                      J19              139      SCONN288_ADR50001P013C01-SCONNA
GND                      J19              141      SCONN288_ADR50001P013C01-SCONNA
GND                      J19              143      SCONN288_ADR50001P013C01-SCONNA
GND                      J19              151      SCONN288_ADR50001P013C01-SCONNA
GND                      J19              153      SCONN288_ADR50001P013C01-SCONNA
GND                      J19              155      SCONN288_ADR50001P013C01-SCONNA
GND                      J19              158      SCONN288_ADR50001P013C01-SCONNA
GND                      J19              160      SCONN288_ADR50001P013C01-SCONNA
GND                      J19              162      SCONN288_ADR50001P013C01-SCONNA
GND                      J19              164      SCONN288_ADR50001P013C01-SCONNA
GND                      J19              166      SCONN288_ADR50001P013C01-SCONNA
GND                      J19              169      SCONN288_ADR50001P013C01-SCONNA
GND                      J19              171      SCONN288_ADR50001P013C01-SCONNA
GND                      J19              173      SCONN288_ADR50001P013C01-SCONNA
GND                      J19              175      SCONN288_ADR50001P013C01-SCONNA
GND                      J19              177      SCONN288_ADR50001P013C01-SCONNA
GND                      J19              180      SCONN288_ADR50001P013C01-SCONNA
GND                      J19              182      SCONN288_ADR50001P013C01-SCONNA
GND                      J19              184      SCONN288_ADR50001P013C01-SCONNA
GND                      J19              186      SCONN288_ADR50001P013C01-SCONNA
GND                      J19              188      SCONN288_ADR50001P013C01-SCONNA
GND                      J19              191      SCONN288_ADR50001P013C01-SCONNA
GND                      J19              193      SCONN288_ADR50001P013C01-SCONNA
GND                      J19              195      SCONN288_ADR50001P013C01-SCONNA
GND                      J19              197      SCONN288_ADR50001P013C01-SCONNA
GND                      J19              199      SCONN288_ADR50001P013C01-SCONNA
GND                      J19              202      SCONN288_ADR50001P013C01-SCONNA
GND                      J19              204      SCONN288_ADR50001P013C01-SCONNA
GND                      J19              206      SCONN288_ADR50001P013C01-SCONNA
GND                      J19              208      SCONN288_ADR50001P013C01-SCONNA
GND                      J19              210      SCONN288_ADR50001P013C01-SCONNA
GND                      J19              212      SCONN288_ADR50001P013C01-SCONNA
GND                      J19              214      SCONN288_ADR50001P013C01-SCONNA
GND                      J19              216      SCONN288_ADR50001P013C01-SCONNA
GND                      J19              219      SCONN288_ADR50001P013C01-SCONNA
GND                      J19              222      SCONN288_ADR50001P013C01-SCONNA
GND                      J19              224      SCONN288_ADR50001P013C01-SCONNA
GND                      J19              226      SCONN288_ADR50001P013C01-SCONNA
GND                      J19              228      SCONN288_ADR50001P013C01-SCONNA
GND                      J19              230      SCONN288_ADR50001P013C01-SCONNA
GND                      J19              233      SCONN288_ADR50001P013C01-SCONNA
GND                      J19              235      SCONN288_ADR50001P013C01-SCONNA
GND                      J19              237      SCONN288_ADR50001P013C01-SCONNA
GND                      J19              240      SCONN288_ADR50001P013C01-SCONNA
GND                      J19              242      SCONN288_ADR50001P013C01-SCONNA
GND                      J19              244      SCONN288_ADR50001P013C01-SCONNA
GND                      J19              246      SCONN288_ADR50001P013C01-SCONNA
GND                      J19              248      SCONN288_ADR50001P013C01-SCONNA
GND                      J19              251      SCONN288_ADR50001P013C01-SCONNA
GND                      J19              253      SCONN288_ADR50001P013C01-SCONNA
GND                      J19              255      SCONN288_ADR50001P013C01-SCONNA
GND                      J19              257      SCONN288_ADR50001P013C01-SCONNA
GND                      J19              259      SCONN288_ADR50001P013C01-SCONNA
GND                      J19              262      SCONN288_ADR50001P013C01-SCONNA
GND                      J19              264      SCONN288_ADR50001P013C01-SCONNA
GND                      J19              266      SCONN288_ADR50001P013C01-SCONNA
GND                      J19              268      SCONN288_ADR50001P013C01-SCONNA
GND                      J19              270      SCONN288_ADR50001P013C01-SCONNA
GND                      J19              273      SCONN288_ADR50001P013C01-SCONNA
GND                      J19              275      SCONN288_ADR50001P013C01-SCONNA
GND                      J19              277      SCONN288_ADR50001P013C01-SCONNA
GND                      J19              279      SCONN288_ADR50001P013C01-SCONNA
GND                      J19              281      SCONN288_ADR50001P013C01-SCONNA
GND                      J19              284      SCONN288_ADR50001P013C01-SCONNA
GND                      J19              286      SCONN288_ADR50001P013C01-SCONNA
GND                      J19              288      SCONN288_ADR50001P013C01-SCONNA
GND                      J19              G1       SCONN288_ADR50001P013C01-SCONNA
GND                      J19              G2       SCONN288_ADR50001P013C01-SCONNA
GND                      J19              G3       SCONN288_ADR50001P013C01-SCONNA
GND                      J20              6        SCONN288_ADR50001P003C01-SCONNA
GND                      J20              8        SCONN288_ADR50001P003C01-SCONNA
GND                      J20              10       SCONN288_ADR50001P003C01-SCONNA
GND                      J20              13       SCONN288_ADR50001P003C01-SCONNA
GND                      J20              15       SCONN288_ADR50001P003C01-SCONNA
GND                      J20              17       SCONN288_ADR50001P003C01-SCONNA
GND                      J20              19       SCONN288_ADR50001P003C01-SCONNA
GND                      J20              21       SCONN288_ADR50001P003C01-SCONNA
GND                      J20              24       SCONN288_ADR50001P003C01-SCONNA
GND                      J20              26       SCONN288_ADR50001P003C01-SCONNA
GND                      J20              28       SCONN288_ADR50001P003C01-SCONNA
GND                      J20              30       SCONN288_ADR50001P003C01-SCONNA
GND                      J20              32       SCONN288_ADR50001P003C01-SCONNA
GND                      J20              35       SCONN288_ADR50001P003C01-SCONNA
GND                      J20              37       SCONN288_ADR50001P003C01-SCONNA
GND                      J20              39       SCONN288_ADR50001P003C01-SCONNA
GND                      J20              41       SCONN288_ADR50001P003C01-SCONNA
GND                      J20              43       SCONN288_ADR50001P003C01-SCONNA
GND                      J20              46       SCONN288_ADR50001P003C01-SCONNA
GND                      J20              48       SCONN288_ADR50001P003C01-SCONNA
GND                      J20              50       SCONN288_ADR50001P003C01-SCONNA
GND                      J20              52       SCONN288_ADR50001P003C01-SCONNA
GND                      J20              54       SCONN288_ADR50001P003C01-SCONNA
GND                      J20              57       SCONN288_ADR50001P003C01-SCONNA
GND                      J20              59       SCONN288_ADR50001P003C01-SCONNA
GND                      J20              61       SCONN288_ADR50001P003C01-SCONNA
GND                      J20              63       SCONN288_ADR50001P003C01-SCONNA
GND                      J20              65       SCONN288_ADR50001P003C01-SCONNA
GND                      J20              67       SCONN288_ADR50001P003C01-SCONNA
GND                      J20              69       SCONN288_ADR50001P003C01-SCONNA
GND                      J20              71       SCONN288_ADR50001P003C01-SCONNA
GND                      J20              73       SCONN288_ADR50001P003C01-SCONNA
GND                      J20              75       SCONN288_ADR50001P003C01-SCONNA
GND                      J20              77       SCONN288_ADR50001P003C01-SCONNA
GND                      J20              79       SCONN288_ADR50001P003C01-SCONNA
GND                      J20              81       SCONN288_ADR50001P003C01-SCONNA
GND                      J20              83       SCONN288_ADR50001P003C01-SCONNA
GND                      J20              85       SCONN288_ADR50001P003C01-SCONNA
GND                      J20              88       SCONN288_ADR50001P003C01-SCONNA
GND                      J20              90       SCONN288_ADR50001P003C01-SCONNA
GND                      J20              92       SCONN288_ADR50001P003C01-SCONNA
GND                      J20              95       SCONN288_ADR50001P003C01-SCONNA
GND                      J20              97       SCONN288_ADR50001P003C01-SCONNA
GND                      J20              99       SCONN288_ADR50001P003C01-SCONNA
GND                      J20              101      SCONN288_ADR50001P003C01-SCONNA
GND                      J20              103      SCONN288_ADR50001P003C01-SCONNA
GND                      J20              106      SCONN288_ADR50001P003C01-SCONNA
GND                      J20              108      SCONN288_ADR50001P003C01-SCONNA
GND                      J20              110      SCONN288_ADR50001P003C01-SCONNA
GND                      J20              112      SCONN288_ADR50001P003C01-SCONNA
GND                      J20              114      SCONN288_ADR50001P003C01-SCONNA
GND                      J20              117      SCONN288_ADR50001P003C01-SCONNA
GND                      J20              119      SCONN288_ADR50001P003C01-SCONNA
GND                      J20              121      SCONN288_ADR50001P003C01-SCONNA
GND                      J20              123      SCONN288_ADR50001P003C01-SCONNA
GND                      J20              125      SCONN288_ADR50001P003C01-SCONNA
GND                      J20              128      SCONN288_ADR50001P003C01-SCONNA
GND                      J20              130      SCONN288_ADR50001P003C01-SCONNA
GND                      J20              132      SCONN288_ADR50001P003C01-SCONNA
GND                      J20              134      SCONN288_ADR50001P003C01-SCONNA
GND                      J20              136      SCONN288_ADR50001P003C01-SCONNA
GND                      J20              139      SCONN288_ADR50001P003C01-SCONNA
GND                      J20              141      SCONN288_ADR50001P003C01-SCONNA
GND                      J20              143      SCONN288_ADR50001P003C01-SCONNA
GND                      J20              151      SCONN288_ADR50001P003C01-SCONNA
GND                      J20              153      SCONN288_ADR50001P003C01-SCONNA
GND                      J20              155      SCONN288_ADR50001P003C01-SCONNA
GND                      J20              158      SCONN288_ADR50001P003C01-SCONNA
GND                      J20              160      SCONN288_ADR50001P003C01-SCONNA
GND                      J20              162      SCONN288_ADR50001P003C01-SCONNA
GND                      J20              164      SCONN288_ADR50001P003C01-SCONNA
GND                      J20              166      SCONN288_ADR50001P003C01-SCONNA
GND                      J20              169      SCONN288_ADR50001P003C01-SCONNA
GND                      J20              171      SCONN288_ADR50001P003C01-SCONNA
GND                      J20              173      SCONN288_ADR50001P003C01-SCONNA
GND                      J20              175      SCONN288_ADR50001P003C01-SCONNA
GND                      J20              177      SCONN288_ADR50001P003C01-SCONNA
GND                      J20              180      SCONN288_ADR50001P003C01-SCONNA
GND                      J20              182      SCONN288_ADR50001P003C01-SCONNA
GND                      J20              184      SCONN288_ADR50001P003C01-SCONNA
GND                      J20              186      SCONN288_ADR50001P003C01-SCONNA
GND                      J20              188      SCONN288_ADR50001P003C01-SCONNA
GND                      J20              191      SCONN288_ADR50001P003C01-SCONNA
GND                      J20              193      SCONN288_ADR50001P003C01-SCONNA
GND                      J20              195      SCONN288_ADR50001P003C01-SCONNA
GND                      J20              197      SCONN288_ADR50001P003C01-SCONNA
GND                      J20              199      SCONN288_ADR50001P003C01-SCONNA
GND                      J20              202      SCONN288_ADR50001P003C01-SCONNA
GND                      J20              204      SCONN288_ADR50001P003C01-SCONNA
GND                      J20              206      SCONN288_ADR50001P003C01-SCONNA
GND                      J20              208      SCONN288_ADR50001P003C01-SCONNA
GND                      J20              210      SCONN288_ADR50001P003C01-SCONNA
GND                      J20              212      SCONN288_ADR50001P003C01-SCONNA
GND                      J20              214      SCONN288_ADR50001P003C01-SCONNA
GND                      J20              216      SCONN288_ADR50001P003C01-SCONNA
GND                      J20              219      SCONN288_ADR50001P003C01-SCONNA
GND                      J20              222      SCONN288_ADR50001P003C01-SCONNA
GND                      J20              224      SCONN288_ADR50001P003C01-SCONNA
GND                      J20              226      SCONN288_ADR50001P003C01-SCONNA
GND                      J20              228      SCONN288_ADR50001P003C01-SCONNA
GND                      J20              230      SCONN288_ADR50001P003C01-SCONNA
GND                      J20              233      SCONN288_ADR50001P003C01-SCONNA
GND                      J20              235      SCONN288_ADR50001P003C01-SCONNA
GND                      J20              237      SCONN288_ADR50001P003C01-SCONNA
GND                      J20              240      SCONN288_ADR50001P003C01-SCONNA
GND                      J20              242      SCONN288_ADR50001P003C01-SCONNA
GND                      J20              244      SCONN288_ADR50001P003C01-SCONNA
GND                      J20              246      SCONN288_ADR50001P003C01-SCONNA
GND                      J20              248      SCONN288_ADR50001P003C01-SCONNA
GND                      J20              251      SCONN288_ADR50001P003C01-SCONNA
GND                      J20              253      SCONN288_ADR50001P003C01-SCONNA
GND                      J20              255      SCONN288_ADR50001P003C01-SCONNA
GND                      J20              257      SCONN288_ADR50001P003C01-SCONNA
GND                      J20              259      SCONN288_ADR50001P003C01-SCONNA
GND                      J20              262      SCONN288_ADR50001P003C01-SCONNA
GND                      J20              264      SCONN288_ADR50001P003C01-SCONNA
GND                      J20              266      SCONN288_ADR50001P003C01-SCONNA
GND                      J20              268      SCONN288_ADR50001P003C01-SCONNA
GND                      J20              270      SCONN288_ADR50001P003C01-SCONNA
GND                      J20              273      SCONN288_ADR50001P003C01-SCONNA
GND                      J20              275      SCONN288_ADR50001P003C01-SCONNA
GND                      J20              277      SCONN288_ADR50001P003C01-SCONNA
GND                      J20              279      SCONN288_ADR50001P003C01-SCONNA
GND                      J20              281      SCONN288_ADR50001P003C01-SCONNA
GND                      J20              284      SCONN288_ADR50001P003C01-SCONNA
GND                      J20              286      SCONN288_ADR50001P003C01-SCONNA
GND                      J20              288      SCONN288_ADR50001P003C01-SCONNA
GND                      J20              G1       SCONN288_ADR50001P003C01-SCONNA
GND                      J20              G2       SCONN288_ADR50001P003C01-SCONNA
GND                      J20              G3       SCONN288_ADR50001P003C01-SCONNA
GND                      J21              6        SCONN288_ADR50001P013C01-SCONNA
GND                      J21              8        SCONN288_ADR50001P013C01-SCONNA
GND                      J21              10       SCONN288_ADR50001P013C01-SCONNA
GND                      J21              13       SCONN288_ADR50001P013C01-SCONNA
GND                      J21              15       SCONN288_ADR50001P013C01-SCONNA
GND                      J21              17       SCONN288_ADR50001P013C01-SCONNA
GND                      J21              19       SCONN288_ADR50001P013C01-SCONNA
GND                      J21              21       SCONN288_ADR50001P013C01-SCONNA
GND                      J21              24       SCONN288_ADR50001P013C01-SCONNA
GND                      J21              26       SCONN288_ADR50001P013C01-SCONNA
GND                      J21              28       SCONN288_ADR50001P013C01-SCONNA
GND                      J21              30       SCONN288_ADR50001P013C01-SCONNA
GND                      J21              32       SCONN288_ADR50001P013C01-SCONNA
GND                      J21              35       SCONN288_ADR50001P013C01-SCONNA
GND                      J21              37       SCONN288_ADR50001P013C01-SCONNA
GND                      J21              39       SCONN288_ADR50001P013C01-SCONNA
GND                      J21              41       SCONN288_ADR50001P013C01-SCONNA
GND                      J21              43       SCONN288_ADR50001P013C01-SCONNA
GND                      J21              46       SCONN288_ADR50001P013C01-SCONNA
GND                      J21              48       SCONN288_ADR50001P013C01-SCONNA
GND                      J21              50       SCONN288_ADR50001P013C01-SCONNA
GND                      J21              52       SCONN288_ADR50001P013C01-SCONNA
GND                      J21              54       SCONN288_ADR50001P013C01-SCONNA
GND                      J21              57       SCONN288_ADR50001P013C01-SCONNA
GND                      J21              59       SCONN288_ADR50001P013C01-SCONNA
GND                      J21              61       SCONN288_ADR50001P013C01-SCONNA
GND                      J21              63       SCONN288_ADR50001P013C01-SCONNA
GND                      J21              65       SCONN288_ADR50001P013C01-SCONNA
GND                      J21              67       SCONN288_ADR50001P013C01-SCONNA
GND                      J21              69       SCONN288_ADR50001P013C01-SCONNA
GND                      J21              71       SCONN288_ADR50001P013C01-SCONNA
GND                      J21              73       SCONN288_ADR50001P013C01-SCONNA
GND                      J21              75       SCONN288_ADR50001P013C01-SCONNA
GND                      J21              77       SCONN288_ADR50001P013C01-SCONNA
GND                      J21              79       SCONN288_ADR50001P013C01-SCONNA
GND                      J21              81       SCONN288_ADR50001P013C01-SCONNA
GND                      J21              83       SCONN288_ADR50001P013C01-SCONNA
GND                      J21              85       SCONN288_ADR50001P013C01-SCONNA
GND                      J21              88       SCONN288_ADR50001P013C01-SCONNA
GND                      J21              90       SCONN288_ADR50001P013C01-SCONNA
GND                      J21              92       SCONN288_ADR50001P013C01-SCONNA
GND                      J21              95       SCONN288_ADR50001P013C01-SCONNA
GND                      J21              97       SCONN288_ADR50001P013C01-SCONNA
GND                      J21              99       SCONN288_ADR50001P013C01-SCONNA
GND                      J21              101      SCONN288_ADR50001P013C01-SCONNA
GND                      J21              103      SCONN288_ADR50001P013C01-SCONNA
GND                      J21              106      SCONN288_ADR50001P013C01-SCONNA
GND                      J21              108      SCONN288_ADR50001P013C01-SCONNA
GND                      J21              110      SCONN288_ADR50001P013C01-SCONNA
GND                      J21              112      SCONN288_ADR50001P013C01-SCONNA
GND                      J21              114      SCONN288_ADR50001P013C01-SCONNA
GND                      J21              117      SCONN288_ADR50001P013C01-SCONNA
GND                      J21              119      SCONN288_ADR50001P013C01-SCONNA
GND                      J21              121      SCONN288_ADR50001P013C01-SCONNA
GND                      J21              123      SCONN288_ADR50001P013C01-SCONNA
GND                      J21              125      SCONN288_ADR50001P013C01-SCONNA
GND                      J21              128      SCONN288_ADR50001P013C01-SCONNA
GND                      J21              130      SCONN288_ADR50001P013C01-SCONNA
GND                      J21              132      SCONN288_ADR50001P013C01-SCONNA
GND                      J21              134      SCONN288_ADR50001P013C01-SCONNA
GND                      J21              136      SCONN288_ADR50001P013C01-SCONNA
GND                      J21              139      SCONN288_ADR50001P013C01-SCONNA
GND                      J21              141      SCONN288_ADR50001P013C01-SCONNA
GND                      J21              143      SCONN288_ADR50001P013C01-SCONNA
GND                      J21              151      SCONN288_ADR50001P013C01-SCONNA
GND                      J21              153      SCONN288_ADR50001P013C01-SCONNA
GND                      J21              155      SCONN288_ADR50001P013C01-SCONNA
GND                      J21              158      SCONN288_ADR50001P013C01-SCONNA
GND                      J21              160      SCONN288_ADR50001P013C01-SCONNA
GND                      J21              162      SCONN288_ADR50001P013C01-SCONNA
GND                      J21              164      SCONN288_ADR50001P013C01-SCONNA
GND                      J21              166      SCONN288_ADR50001P013C01-SCONNA
GND                      J21              169      SCONN288_ADR50001P013C01-SCONNA
GND                      J21              171      SCONN288_ADR50001P013C01-SCONNA
GND                      J21              173      SCONN288_ADR50001P013C01-SCONNA
GND                      J21              175      SCONN288_ADR50001P013C01-SCONNA
GND                      J21              177      SCONN288_ADR50001P013C01-SCONNA
GND                      J21              180      SCONN288_ADR50001P013C01-SCONNA
GND                      J21              182      SCONN288_ADR50001P013C01-SCONNA
GND                      J21              184      SCONN288_ADR50001P013C01-SCONNA
GND                      J21              186      SCONN288_ADR50001P013C01-SCONNA
GND                      J21              188      SCONN288_ADR50001P013C01-SCONNA
GND                      J21              191      SCONN288_ADR50001P013C01-SCONNA
GND                      J21              193      SCONN288_ADR50001P013C01-SCONNA
GND                      J21              195      SCONN288_ADR50001P013C01-SCONNA
GND                      J21              197      SCONN288_ADR50001P013C01-SCONNA
GND                      J21              199      SCONN288_ADR50001P013C01-SCONNA
GND                      J21              202      SCONN288_ADR50001P013C01-SCONNA
GND                      J21              204      SCONN288_ADR50001P013C01-SCONNA
GND                      J21              206      SCONN288_ADR50001P013C01-SCONNA
GND                      J21              208      SCONN288_ADR50001P013C01-SCONNA
GND                      J21              210      SCONN288_ADR50001P013C01-SCONNA
GND                      J21              212      SCONN288_ADR50001P013C01-SCONNA
GND                      J21              214      SCONN288_ADR50001P013C01-SCONNA
GND                      J21              216      SCONN288_ADR50001P013C01-SCONNA
GND                      J21              219      SCONN288_ADR50001P013C01-SCONNA
GND                      J21              222      SCONN288_ADR50001P013C01-SCONNA
GND                      J21              224      SCONN288_ADR50001P013C01-SCONNA
GND                      J21              226      SCONN288_ADR50001P013C01-SCONNA
GND                      J21              228      SCONN288_ADR50001P013C01-SCONNA
GND                      J21              230      SCONN288_ADR50001P013C01-SCONNA
GND                      J21              233      SCONN288_ADR50001P013C01-SCONNA
GND                      J21              235      SCONN288_ADR50001P013C01-SCONNA
GND                      J21              237      SCONN288_ADR50001P013C01-SCONNA
GND                      J21              240      SCONN288_ADR50001P013C01-SCONNA
GND                      J21              242      SCONN288_ADR50001P013C01-SCONNA
GND                      J21              244      SCONN288_ADR50001P013C01-SCONNA
GND                      J21              246      SCONN288_ADR50001P013C01-SCONNA
GND                      J21              248      SCONN288_ADR50001P013C01-SCONNA
GND                      J21              251      SCONN288_ADR50001P013C01-SCONNA
GND                      J21              253      SCONN288_ADR50001P013C01-SCONNA
GND                      J21              255      SCONN288_ADR50001P013C01-SCONNA
GND                      J21              257      SCONN288_ADR50001P013C01-SCONNA
GND                      J21              259      SCONN288_ADR50001P013C01-SCONNA
GND                      J21              262      SCONN288_ADR50001P013C01-SCONNA
GND                      J21              264      SCONN288_ADR50001P013C01-SCONNA
GND                      J21              266      SCONN288_ADR50001P013C01-SCONNA
GND                      J21              268      SCONN288_ADR50001P013C01-SCONNA
GND                      J21              270      SCONN288_ADR50001P013C01-SCONNA
GND                      J21              273      SCONN288_ADR50001P013C01-SCONNA
GND                      J21              275      SCONN288_ADR50001P013C01-SCONNA
GND                      J21              277      SCONN288_ADR50001P013C01-SCONNA
GND                      J21              279      SCONN288_ADR50001P013C01-SCONNA
GND                      J21              281      SCONN288_ADR50001P013C01-SCONNA
GND                      J21              284      SCONN288_ADR50001P013C01-SCONNA
GND                      J21              286      SCONN288_ADR50001P013C01-SCONNA
GND                      J21              288      SCONN288_ADR50001P013C01-SCONNA
GND                      J21              G1       SCONN288_ADR50001P013C01-SCONNA
GND                      J21              G2       SCONN288_ADR50001P013C01-SCONNA
GND                      J21              G3       SCONN288_ADR50001P013C01-SCONNA
GND                      J22              6        SCONN288_ADR50001P003C01-SCONNA
GND                      J22              8        SCONN288_ADR50001P003C01-SCONNA
GND                      J22              10       SCONN288_ADR50001P003C01-SCONNA
GND                      J22              13       SCONN288_ADR50001P003C01-SCONNA
GND                      J22              15       SCONN288_ADR50001P003C01-SCONNA
GND                      J22              17       SCONN288_ADR50001P003C01-SCONNA
GND                      J22              19       SCONN288_ADR50001P003C01-SCONNA
GND                      J22              21       SCONN288_ADR50001P003C01-SCONNA
GND                      J22              24       SCONN288_ADR50001P003C01-SCONNA
GND                      J22              26       SCONN288_ADR50001P003C01-SCONNA
GND                      J22              28       SCONN288_ADR50001P003C01-SCONNA
GND                      J22              30       SCONN288_ADR50001P003C01-SCONNA
GND                      J22              32       SCONN288_ADR50001P003C01-SCONNA
GND                      J22              35       SCONN288_ADR50001P003C01-SCONNA
GND                      J22              37       SCONN288_ADR50001P003C01-SCONNA
GND                      J22              39       SCONN288_ADR50001P003C01-SCONNA
GND                      J22              41       SCONN288_ADR50001P003C01-SCONNA
GND                      J22              43       SCONN288_ADR50001P003C01-SCONNA
GND                      J22              46       SCONN288_ADR50001P003C01-SCONNA
GND                      J22              48       SCONN288_ADR50001P003C01-SCONNA
GND                      J22              50       SCONN288_ADR50001P003C01-SCONNA
GND                      J22              52       SCONN288_ADR50001P003C01-SCONNA
GND                      J22              54       SCONN288_ADR50001P003C01-SCONNA
GND                      J22              57       SCONN288_ADR50001P003C01-SCONNA
GND                      J22              59       SCONN288_ADR50001P003C01-SCONNA
GND                      J22              61       SCONN288_ADR50001P003C01-SCONNA
GND                      J22              63       SCONN288_ADR50001P003C01-SCONNA
GND                      J22              65       SCONN288_ADR50001P003C01-SCONNA
GND                      J22              67       SCONN288_ADR50001P003C01-SCONNA
GND                      J22              69       SCONN288_ADR50001P003C01-SCONNA
GND                      J22              71       SCONN288_ADR50001P003C01-SCONNA
GND                      J22              73       SCONN288_ADR50001P003C01-SCONNA
GND                      J22              75       SCONN288_ADR50001P003C01-SCONNA
GND                      J22              77       SCONN288_ADR50001P003C01-SCONNA
GND                      J22              79       SCONN288_ADR50001P003C01-SCONNA
GND                      J22              81       SCONN288_ADR50001P003C01-SCONNA
GND                      J22              83       SCONN288_ADR50001P003C01-SCONNA
GND                      J22              85       SCONN288_ADR50001P003C01-SCONNA
GND                      J22              88       SCONN288_ADR50001P003C01-SCONNA
GND                      J22              90       SCONN288_ADR50001P003C01-SCONNA
GND                      J22              92       SCONN288_ADR50001P003C01-SCONNA
GND                      J22              95       SCONN288_ADR50001P003C01-SCONNA
GND                      J22              97       SCONN288_ADR50001P003C01-SCONNA
GND                      J22              99       SCONN288_ADR50001P003C01-SCONNA
GND                      J22              101      SCONN288_ADR50001P003C01-SCONNA
GND                      J22              103      SCONN288_ADR50001P003C01-SCONNA
GND                      J22              106      SCONN288_ADR50001P003C01-SCONNA
GND                      J22              108      SCONN288_ADR50001P003C01-SCONNA
GND                      J22              110      SCONN288_ADR50001P003C01-SCONNA
GND                      J22              112      SCONN288_ADR50001P003C01-SCONNA
GND                      J22              114      SCONN288_ADR50001P003C01-SCONNA
GND                      J22              117      SCONN288_ADR50001P003C01-SCONNA
GND                      J22              119      SCONN288_ADR50001P003C01-SCONNA
GND                      J22              121      SCONN288_ADR50001P003C01-SCONNA
GND                      J22              123      SCONN288_ADR50001P003C01-SCONNA
GND                      J22              125      SCONN288_ADR50001P003C01-SCONNA
GND                      J22              128      SCONN288_ADR50001P003C01-SCONNA
GND                      J22              130      SCONN288_ADR50001P003C01-SCONNA
GND                      J22              132      SCONN288_ADR50001P003C01-SCONNA
GND                      J22              134      SCONN288_ADR50001P003C01-SCONNA
GND                      J22              136      SCONN288_ADR50001P003C01-SCONNA
GND                      J22              139      SCONN288_ADR50001P003C01-SCONNA
GND                      J22              141      SCONN288_ADR50001P003C01-SCONNA
GND                      J22              143      SCONN288_ADR50001P003C01-SCONNA
GND                      J22              151      SCONN288_ADR50001P003C01-SCONNA
GND                      J22              153      SCONN288_ADR50001P003C01-SCONNA
GND                      J22              155      SCONN288_ADR50001P003C01-SCONNA
GND                      J22              158      SCONN288_ADR50001P003C01-SCONNA
GND                      J22              160      SCONN288_ADR50001P003C01-SCONNA
GND                      J22              162      SCONN288_ADR50001P003C01-SCONNA
GND                      J22              164      SCONN288_ADR50001P003C01-SCONNA
GND                      J22              166      SCONN288_ADR50001P003C01-SCONNA
GND                      J22              169      SCONN288_ADR50001P003C01-SCONNA
GND                      J22              171      SCONN288_ADR50001P003C01-SCONNA
GND                      J22              173      SCONN288_ADR50001P003C01-SCONNA
GND                      J22              175      SCONN288_ADR50001P003C01-SCONNA
GND                      J22              177      SCONN288_ADR50001P003C01-SCONNA
GND                      J22              180      SCONN288_ADR50001P003C01-SCONNA
GND                      J22              182      SCONN288_ADR50001P003C01-SCONNA
GND                      J22              184      SCONN288_ADR50001P003C01-SCONNA
GND                      J22              186      SCONN288_ADR50001P003C01-SCONNA
GND                      J22              188      SCONN288_ADR50001P003C01-SCONNA
GND                      J22              191      SCONN288_ADR50001P003C01-SCONNA
GND                      J22              193      SCONN288_ADR50001P003C01-SCONNA
GND                      J22              195      SCONN288_ADR50001P003C01-SCONNA
GND                      J22              197      SCONN288_ADR50001P003C01-SCONNA
GND                      J22              199      SCONN288_ADR50001P003C01-SCONNA
GND                      J22              202      SCONN288_ADR50001P003C01-SCONNA
GND                      J22              204      SCONN288_ADR50001P003C01-SCONNA
GND                      J22              206      SCONN288_ADR50001P003C01-SCONNA
GND                      J22              208      SCONN288_ADR50001P003C01-SCONNA
GND                      J22              210      SCONN288_ADR50001P003C01-SCONNA
GND                      J22              212      SCONN288_ADR50001P003C01-SCONNA
GND                      J22              214      SCONN288_ADR50001P003C01-SCONNA
GND                      J22              216      SCONN288_ADR50001P003C01-SCONNA
GND                      J22              219      SCONN288_ADR50001P003C01-SCONNA
GND                      J22              222      SCONN288_ADR50001P003C01-SCONNA
GND                      J22              224      SCONN288_ADR50001P003C01-SCONNA
GND                      J22              226      SCONN288_ADR50001P003C01-SCONNA
GND                      J22              228      SCONN288_ADR50001P003C01-SCONNA
GND                      J22              230      SCONN288_ADR50001P003C01-SCONNA
GND                      J22              233      SCONN288_ADR50001P003C01-SCONNA
GND                      J22              235      SCONN288_ADR50001P003C01-SCONNA
GND                      J22              237      SCONN288_ADR50001P003C01-SCONNA
GND                      J22              240      SCONN288_ADR50001P003C01-SCONNA
GND                      J22              242      SCONN288_ADR50001P003C01-SCONNA
GND                      J22              244      SCONN288_ADR50001P003C01-SCONNA
GND                      J22              246      SCONN288_ADR50001P003C01-SCONNA
GND                      J22              248      SCONN288_ADR50001P003C01-SCONNA
GND                      J22              251      SCONN288_ADR50001P003C01-SCONNA
GND                      J22              253      SCONN288_ADR50001P003C01-SCONNA
GND                      J22              255      SCONN288_ADR50001P003C01-SCONNA
GND                      J22              257      SCONN288_ADR50001P003C01-SCONNA
GND                      J22              259      SCONN288_ADR50001P003C01-SCONNA
GND                      J22              262      SCONN288_ADR50001P003C01-SCONNA
GND                      J22              264      SCONN288_ADR50001P003C01-SCONNA
GND                      J22              266      SCONN288_ADR50001P003C01-SCONNA
GND                      J22              268      SCONN288_ADR50001P003C01-SCONNA
GND                      J22              270      SCONN288_ADR50001P003C01-SCONNA
GND                      J22              273      SCONN288_ADR50001P003C01-SCONNA
GND                      J22              275      SCONN288_ADR50001P003C01-SCONNA
GND                      J22              277      SCONN288_ADR50001P003C01-SCONNA
GND                      J22              279      SCONN288_ADR50001P003C01-SCONNA
GND                      J22              281      SCONN288_ADR50001P003C01-SCONNA
GND                      J22              284      SCONN288_ADR50001P003C01-SCONNA
GND                      J22              286      SCONN288_ADR50001P003C01-SCONNA
GND                      J22              288      SCONN288_ADR50001P003C01-SCONNA
GND                      J22              G1       SCONN288_ADR50001P003C01-SCONNA
GND                      J22              G2       SCONN288_ADR50001P003C01-SCONNA
GND                      J22              G3       SCONN288_ADR50001P003C01-SCONNA
GND                      J23              6        SCONN288_ADR50001P013C01-SCONNA
GND                      J23              8        SCONN288_ADR50001P013C01-SCONNA
GND                      J23              10       SCONN288_ADR50001P013C01-SCONNA
GND                      J23              13       SCONN288_ADR50001P013C01-SCONNA
GND                      J23              15       SCONN288_ADR50001P013C01-SCONNA
GND                      J23              17       SCONN288_ADR50001P013C01-SCONNA
GND                      J23              19       SCONN288_ADR50001P013C01-SCONNA
GND                      J23              21       SCONN288_ADR50001P013C01-SCONNA
GND                      J23              24       SCONN288_ADR50001P013C01-SCONNA
GND                      J23              26       SCONN288_ADR50001P013C01-SCONNA
GND                      J23              28       SCONN288_ADR50001P013C01-SCONNA
GND                      J23              30       SCONN288_ADR50001P013C01-SCONNA
GND                      J23              32       SCONN288_ADR50001P013C01-SCONNA
GND                      J23              35       SCONN288_ADR50001P013C01-SCONNA
GND                      J23              37       SCONN288_ADR50001P013C01-SCONNA
GND                      J23              39       SCONN288_ADR50001P013C01-SCONNA
GND                      J23              41       SCONN288_ADR50001P013C01-SCONNA
GND                      J23              43       SCONN288_ADR50001P013C01-SCONNA
GND                      J23              46       SCONN288_ADR50001P013C01-SCONNA
GND                      J23              48       SCONN288_ADR50001P013C01-SCONNA
GND                      J23              50       SCONN288_ADR50001P013C01-SCONNA
GND                      J23              52       SCONN288_ADR50001P013C01-SCONNA
GND                      J23              54       SCONN288_ADR50001P013C01-SCONNA
GND                      J23              57       SCONN288_ADR50001P013C01-SCONNA
GND                      J23              59       SCONN288_ADR50001P013C01-SCONNA
GND                      J23              61       SCONN288_ADR50001P013C01-SCONNA
GND                      J23              63       SCONN288_ADR50001P013C01-SCONNA
GND                      J23              65       SCONN288_ADR50001P013C01-SCONNA
GND                      J23              67       SCONN288_ADR50001P013C01-SCONNA
GND                      J23              69       SCONN288_ADR50001P013C01-SCONNA
GND                      J23              71       SCONN288_ADR50001P013C01-SCONNA
GND                      J23              73       SCONN288_ADR50001P013C01-SCONNA
GND                      J23              75       SCONN288_ADR50001P013C01-SCONNA
GND                      J23              77       SCONN288_ADR50001P013C01-SCONNA
GND                      J23              79       SCONN288_ADR50001P013C01-SCONNA
GND                      J23              81       SCONN288_ADR50001P013C01-SCONNA
GND                      J23              83       SCONN288_ADR50001P013C01-SCONNA
GND                      J23              85       SCONN288_ADR50001P013C01-SCONNA
GND                      J23              88       SCONN288_ADR50001P013C01-SCONNA
GND                      J23              90       SCONN288_ADR50001P013C01-SCONNA
GND                      J23              92       SCONN288_ADR50001P013C01-SCONNA
GND                      J23              95       SCONN288_ADR50001P013C01-SCONNA
GND                      J23              97       SCONN288_ADR50001P013C01-SCONNA
GND                      J23              99       SCONN288_ADR50001P013C01-SCONNA
GND                      J23              101      SCONN288_ADR50001P013C01-SCONNA
GND                      J23              103      SCONN288_ADR50001P013C01-SCONNA
GND                      J23              106      SCONN288_ADR50001P013C01-SCONNA
GND                      J23              108      SCONN288_ADR50001P013C01-SCONNA
GND                      J23              110      SCONN288_ADR50001P013C01-SCONNA
GND                      J23              112      SCONN288_ADR50001P013C01-SCONNA
GND                      J23              114      SCONN288_ADR50001P013C01-SCONNA
GND                      J23              117      SCONN288_ADR50001P013C01-SCONNA
GND                      J23              119      SCONN288_ADR50001P013C01-SCONNA
GND                      J23              121      SCONN288_ADR50001P013C01-SCONNA
GND                      J23              123      SCONN288_ADR50001P013C01-SCONNA
GND                      J23              125      SCONN288_ADR50001P013C01-SCONNA
GND                      J23              128      SCONN288_ADR50001P013C01-SCONNA
GND                      J23              130      SCONN288_ADR50001P013C01-SCONNA
GND                      J23              132      SCONN288_ADR50001P013C01-SCONNA
GND                      J23              134      SCONN288_ADR50001P013C01-SCONNA
GND                      J23              136      SCONN288_ADR50001P013C01-SCONNA
GND                      J23              139      SCONN288_ADR50001P013C01-SCONNA
GND                      J23              141      SCONN288_ADR50001P013C01-SCONNA
GND                      J23              143      SCONN288_ADR50001P013C01-SCONNA
GND                      J23              151      SCONN288_ADR50001P013C01-SCONNA
GND                      J23              153      SCONN288_ADR50001P013C01-SCONNA
GND                      J23              155      SCONN288_ADR50001P013C01-SCONNA
GND                      J23              158      SCONN288_ADR50001P013C01-SCONNA
GND                      J23              160      SCONN288_ADR50001P013C01-SCONNA
GND                      J23              162      SCONN288_ADR50001P013C01-SCONNA
GND                      J23              164      SCONN288_ADR50001P013C01-SCONNA
GND                      J23              166      SCONN288_ADR50001P013C01-SCONNA
GND                      J23              169      SCONN288_ADR50001P013C01-SCONNA
GND                      J23              171      SCONN288_ADR50001P013C01-SCONNA
GND                      J23              173      SCONN288_ADR50001P013C01-SCONNA
GND                      J23              175      SCONN288_ADR50001P013C01-SCONNA
GND                      J23              177      SCONN288_ADR50001P013C01-SCONNA
GND                      J23              180      SCONN288_ADR50001P013C01-SCONNA
GND                      J23              182      SCONN288_ADR50001P013C01-SCONNA
GND                      J23              184      SCONN288_ADR50001P013C01-SCONNA
GND                      J23              186      SCONN288_ADR50001P013C01-SCONNA
GND                      J23              188      SCONN288_ADR50001P013C01-SCONNA
GND                      J23              191      SCONN288_ADR50001P013C01-SCONNA
GND                      J23              193      SCONN288_ADR50001P013C01-SCONNA
GND                      J23              195      SCONN288_ADR50001P013C01-SCONNA
GND                      J23              197      SCONN288_ADR50001P013C01-SCONNA
GND                      J23              199      SCONN288_ADR50001P013C01-SCONNA
GND                      J23              202      SCONN288_ADR50001P013C01-SCONNA
GND                      J23              204      SCONN288_ADR50001P013C01-SCONNA
GND                      J23              206      SCONN288_ADR50001P013C01-SCONNA
GND                      J23              208      SCONN288_ADR50001P013C01-SCONNA
GND                      J23              210      SCONN288_ADR50001P013C01-SCONNA
GND                      J23              212      SCONN288_ADR50001P013C01-SCONNA
GND                      J23              214      SCONN288_ADR50001P013C01-SCONNA
GND                      J23              216      SCONN288_ADR50001P013C01-SCONNA
GND                      J23              219      SCONN288_ADR50001P013C01-SCONNA
GND                      J23              222      SCONN288_ADR50001P013C01-SCONNA
GND                      J23              224      SCONN288_ADR50001P013C01-SCONNA
GND                      J23              226      SCONN288_ADR50001P013C01-SCONNA
GND                      J23              228      SCONN288_ADR50001P013C01-SCONNA
GND                      J23              230      SCONN288_ADR50001P013C01-SCONNA
GND                      J23              233      SCONN288_ADR50001P013C01-SCONNA
GND                      J23              235      SCONN288_ADR50001P013C01-SCONNA
GND                      J23              237      SCONN288_ADR50001P013C01-SCONNA
GND                      J23              240      SCONN288_ADR50001P013C01-SCONNA
GND                      J23              242      SCONN288_ADR50001P013C01-SCONNA
GND                      J23              244      SCONN288_ADR50001P013C01-SCONNA
GND                      J23              246      SCONN288_ADR50001P013C01-SCONNA
GND                      J23              248      SCONN288_ADR50001P013C01-SCONNA
GND                      J23              251      SCONN288_ADR50001P013C01-SCONNA
GND                      J23              253      SCONN288_ADR50001P013C01-SCONNA
GND                      J23              255      SCONN288_ADR50001P013C01-SCONNA
GND                      J23              257      SCONN288_ADR50001P013C01-SCONNA
GND                      J23              259      SCONN288_ADR50001P013C01-SCONNA
GND                      J23              262      SCONN288_ADR50001P013C01-SCONNA
GND                      J23              264      SCONN288_ADR50001P013C01-SCONNA
GND                      J23              266      SCONN288_ADR50001P013C01-SCONNA
GND                      J23              268      SCONN288_ADR50001P013C01-SCONNA
GND                      J23              270      SCONN288_ADR50001P013C01-SCONNA
GND                      J23              273      SCONN288_ADR50001P013C01-SCONNA
GND                      J23              275      SCONN288_ADR50001P013C01-SCONNA
GND                      J23              277      SCONN288_ADR50001P013C01-SCONNA
GND                      J23              279      SCONN288_ADR50001P013C01-SCONNA
GND                      J23              281      SCONN288_ADR50001P013C01-SCONNA
GND                      J23              284      SCONN288_ADR50001P013C01-SCONNA
GND                      J23              286      SCONN288_ADR50001P013C01-SCONNA
GND                      J23              288      SCONN288_ADR50001P013C01-SCONNA
GND                      J23              G1       SCONN288_ADR50001P013C01-SCONNA
GND                      J23              G2       SCONN288_ADR50001P013C01-SCONNA
GND                      J23              G3       SCONN288_ADR50001P013C01-SCONNA
GND                      J24              6        SCONN288_ADR50001P003C01-SCONNA
GND                      J24              8        SCONN288_ADR50001P003C01-SCONNA
GND                      J24              10       SCONN288_ADR50001P003C01-SCONNA
GND                      J24              13       SCONN288_ADR50001P003C01-SCONNA
GND                      J24              15       SCONN288_ADR50001P003C01-SCONNA
GND                      J24              17       SCONN288_ADR50001P003C01-SCONNA
GND                      J24              19       SCONN288_ADR50001P003C01-SCONNA
GND                      J24              21       SCONN288_ADR50001P003C01-SCONNA
GND                      J24              24       SCONN288_ADR50001P003C01-SCONNA
GND                      J24              26       SCONN288_ADR50001P003C01-SCONNA
GND                      J24              28       SCONN288_ADR50001P003C01-SCONNA
GND                      J24              30       SCONN288_ADR50001P003C01-SCONNA
GND                      J24              32       SCONN288_ADR50001P003C01-SCONNA
GND                      J24              35       SCONN288_ADR50001P003C01-SCONNA
GND                      J24              37       SCONN288_ADR50001P003C01-SCONNA
GND                      J24              39       SCONN288_ADR50001P003C01-SCONNA
GND                      J24              41       SCONN288_ADR50001P003C01-SCONNA
GND                      J24              43       SCONN288_ADR50001P003C01-SCONNA
GND                      J24              46       SCONN288_ADR50001P003C01-SCONNA
GND                      J24              48       SCONN288_ADR50001P003C01-SCONNA
GND                      J24              50       SCONN288_ADR50001P003C01-SCONNA
GND                      J24              52       SCONN288_ADR50001P003C01-SCONNA
GND                      J24              54       SCONN288_ADR50001P003C01-SCONNA
GND                      J24              57       SCONN288_ADR50001P003C01-SCONNA
GND                      J24              59       SCONN288_ADR50001P003C01-SCONNA
GND                      J24              61       SCONN288_ADR50001P003C01-SCONNA
GND                      J24              63       SCONN288_ADR50001P003C01-SCONNA
GND                      J24              65       SCONN288_ADR50001P003C01-SCONNA
GND                      J24              67       SCONN288_ADR50001P003C01-SCONNA
GND                      J24              69       SCONN288_ADR50001P003C01-SCONNA
GND                      J24              71       SCONN288_ADR50001P003C01-SCONNA
GND                      J24              73       SCONN288_ADR50001P003C01-SCONNA
GND                      J24              75       SCONN288_ADR50001P003C01-SCONNA
GND                      J24              77       SCONN288_ADR50001P003C01-SCONNA
GND                      J24              79       SCONN288_ADR50001P003C01-SCONNA
GND                      J24              81       SCONN288_ADR50001P003C01-SCONNA
GND                      J24              83       SCONN288_ADR50001P003C01-SCONNA
GND                      J24              85       SCONN288_ADR50001P003C01-SCONNA
GND                      J24              88       SCONN288_ADR50001P003C01-SCONNA
GND                      J24              90       SCONN288_ADR50001P003C01-SCONNA
GND                      J24              92       SCONN288_ADR50001P003C01-SCONNA
GND                      J24              95       SCONN288_ADR50001P003C01-SCONNA
GND                      J24              97       SCONN288_ADR50001P003C01-SCONNA
GND                      J24              99       SCONN288_ADR50001P003C01-SCONNA
GND                      J24              101      SCONN288_ADR50001P003C01-SCONNA
GND                      J24              103      SCONN288_ADR50001P003C01-SCONNA
GND                      J24              106      SCONN288_ADR50001P003C01-SCONNA
GND                      J24              108      SCONN288_ADR50001P003C01-SCONNA
GND                      J24              110      SCONN288_ADR50001P003C01-SCONNA
GND                      J24              112      SCONN288_ADR50001P003C01-SCONNA
GND                      J24              114      SCONN288_ADR50001P003C01-SCONNA
GND                      J24              117      SCONN288_ADR50001P003C01-SCONNA
GND                      J24              119      SCONN288_ADR50001P003C01-SCONNA
GND                      J24              121      SCONN288_ADR50001P003C01-SCONNA
GND                      J24              123      SCONN288_ADR50001P003C01-SCONNA
GND                      J24              125      SCONN288_ADR50001P003C01-SCONNA
GND                      J24              128      SCONN288_ADR50001P003C01-SCONNA
GND                      J24              130      SCONN288_ADR50001P003C01-SCONNA
GND                      J24              132      SCONN288_ADR50001P003C01-SCONNA
GND                      J24              134      SCONN288_ADR50001P003C01-SCONNA
GND                      J24              136      SCONN288_ADR50001P003C01-SCONNA
GND                      J24              139      SCONN288_ADR50001P003C01-SCONNA
GND                      J24              141      SCONN288_ADR50001P003C01-SCONNA
GND                      J24              143      SCONN288_ADR50001P003C01-SCONNA
GND                      J24              151      SCONN288_ADR50001P003C01-SCONNA
GND                      J24              153      SCONN288_ADR50001P003C01-SCONNA
GND                      J24              155      SCONN288_ADR50001P003C01-SCONNA
GND                      J24              158      SCONN288_ADR50001P003C01-SCONNA
GND                      J24              160      SCONN288_ADR50001P003C01-SCONNA
GND                      J24              162      SCONN288_ADR50001P003C01-SCONNA
GND                      J24              164      SCONN288_ADR50001P003C01-SCONNA
GND                      J24              166      SCONN288_ADR50001P003C01-SCONNA
GND                      J24              169      SCONN288_ADR50001P003C01-SCONNA
GND                      J24              171      SCONN288_ADR50001P003C01-SCONNA
GND                      J24              173      SCONN288_ADR50001P003C01-SCONNA
GND                      J24              175      SCONN288_ADR50001P003C01-SCONNA
GND                      J24              177      SCONN288_ADR50001P003C01-SCONNA
GND                      J24              180      SCONN288_ADR50001P003C01-SCONNA
GND                      J24              182      SCONN288_ADR50001P003C01-SCONNA
GND                      J24              184      SCONN288_ADR50001P003C01-SCONNA
GND                      J24              186      SCONN288_ADR50001P003C01-SCONNA
GND                      J24              188      SCONN288_ADR50001P003C01-SCONNA
GND                      J24              191      SCONN288_ADR50001P003C01-SCONNA
GND                      J24              193      SCONN288_ADR50001P003C01-SCONNA
GND                      J24              195      SCONN288_ADR50001P003C01-SCONNA
GND                      J24              197      SCONN288_ADR50001P003C01-SCONNA
GND                      J24              199      SCONN288_ADR50001P003C01-SCONNA
GND                      J24              202      SCONN288_ADR50001P003C01-SCONNA
GND                      J24              204      SCONN288_ADR50001P003C01-SCONNA
GND                      J24              206      SCONN288_ADR50001P003C01-SCONNA
GND                      J24              208      SCONN288_ADR50001P003C01-SCONNA
GND                      J24              210      SCONN288_ADR50001P003C01-SCONNA
GND                      J24              212      SCONN288_ADR50001P003C01-SCONNA
GND                      J24              214      SCONN288_ADR50001P003C01-SCONNA
GND                      J24              216      SCONN288_ADR50001P003C01-SCONNA
GND                      J24              219      SCONN288_ADR50001P003C01-SCONNA
GND                      J24              222      SCONN288_ADR50001P003C01-SCONNA
GND                      J24              224      SCONN288_ADR50001P003C01-SCONNA
GND                      J24              226      SCONN288_ADR50001P003C01-SCONNA
GND                      J24              228      SCONN288_ADR50001P003C01-SCONNA
GND                      J24              230      SCONN288_ADR50001P003C01-SCONNA
GND                      J24              233      SCONN288_ADR50001P003C01-SCONNA
GND                      J24              235      SCONN288_ADR50001P003C01-SCONNA
GND                      J24              237      SCONN288_ADR50001P003C01-SCONNA
GND                      J24              240      SCONN288_ADR50001P003C01-SCONNA
GND                      J24              242      SCONN288_ADR50001P003C01-SCONNA
GND                      J24              244      SCONN288_ADR50001P003C01-SCONNA
GND                      J24              246      SCONN288_ADR50001P003C01-SCONNA
GND                      J24              248      SCONN288_ADR50001P003C01-SCONNA
GND                      J24              251      SCONN288_ADR50001P003C01-SCONNA
GND                      J24              253      SCONN288_ADR50001P003C01-SCONNA
GND                      J24              255      SCONN288_ADR50001P003C01-SCONNA
GND                      J24              257      SCONN288_ADR50001P003C01-SCONNA
GND                      J24              259      SCONN288_ADR50001P003C01-SCONNA
GND                      J24              262      SCONN288_ADR50001P003C01-SCONNA
GND                      J24              264      SCONN288_ADR50001P003C01-SCONNA
GND                      J24              266      SCONN288_ADR50001P003C01-SCONNA
GND                      J24              268      SCONN288_ADR50001P003C01-SCONNA
GND                      J24              270      SCONN288_ADR50001P003C01-SCONNA
GND                      J24              273      SCONN288_ADR50001P003C01-SCONNA
GND                      J24              275      SCONN288_ADR50001P003C01-SCONNA
GND                      J24              277      SCONN288_ADR50001P003C01-SCONNA
GND                      J24              279      SCONN288_ADR50001P003C01-SCONNA
GND                      J24              281      SCONN288_ADR50001P003C01-SCONNA
GND                      J24              284      SCONN288_ADR50001P003C01-SCONNA
GND                      J24              286      SCONN288_ADR50001P003C01-SCONNA
GND                      J24              288      SCONN288_ADR50001P003C01-SCONNA
GND                      J24              G1       SCONN288_ADR50001P003C01-SCONNA
GND                      J24              G2       SCONN288_ADR50001P003C01-SCONNA
GND                      J24              G3       SCONN288_ADR50001P003C01-SCONNA
GND                      J25              6        SCONN288_ADR50001P013C01-SCONNA
GND                      J25              8        SCONN288_ADR50001P013C01-SCONNA
GND                      J25              10       SCONN288_ADR50001P013C01-SCONNA
GND                      J25              13       SCONN288_ADR50001P013C01-SCONNA
GND                      J25              15       SCONN288_ADR50001P013C01-SCONNA
GND                      J25              17       SCONN288_ADR50001P013C01-SCONNA
GND                      J25              19       SCONN288_ADR50001P013C01-SCONNA
GND                      J25              21       SCONN288_ADR50001P013C01-SCONNA
GND                      J25              24       SCONN288_ADR50001P013C01-SCONNA
GND                      J25              26       SCONN288_ADR50001P013C01-SCONNA
GND                      J25              28       SCONN288_ADR50001P013C01-SCONNA
GND                      J25              30       SCONN288_ADR50001P013C01-SCONNA
GND                      J25              32       SCONN288_ADR50001P013C01-SCONNA
GND                      J25              35       SCONN288_ADR50001P013C01-SCONNA
GND                      J25              37       SCONN288_ADR50001P013C01-SCONNA
GND                      J25              39       SCONN288_ADR50001P013C01-SCONNA
GND                      J25              41       SCONN288_ADR50001P013C01-SCONNA
GND                      J25              43       SCONN288_ADR50001P013C01-SCONNA
GND                      J25              46       SCONN288_ADR50001P013C01-SCONNA
GND                      J25              48       SCONN288_ADR50001P013C01-SCONNA
GND                      J25              50       SCONN288_ADR50001P013C01-SCONNA
GND                      J25              52       SCONN288_ADR50001P013C01-SCONNA
GND                      J25              54       SCONN288_ADR50001P013C01-SCONNA
GND                      J25              57       SCONN288_ADR50001P013C01-SCONNA
GND                      J25              59       SCONN288_ADR50001P013C01-SCONNA
GND                      J25              61       SCONN288_ADR50001P013C01-SCONNA
GND                      J25              63       SCONN288_ADR50001P013C01-SCONNA
GND                      J25              65       SCONN288_ADR50001P013C01-SCONNA
GND                      J25              67       SCONN288_ADR50001P013C01-SCONNA
GND                      J25              69       SCONN288_ADR50001P013C01-SCONNA
GND                      J25              71       SCONN288_ADR50001P013C01-SCONNA
GND                      J25              73       SCONN288_ADR50001P013C01-SCONNA
GND                      J25              75       SCONN288_ADR50001P013C01-SCONNA
GND                      J25              77       SCONN288_ADR50001P013C01-SCONNA
GND                      J25              79       SCONN288_ADR50001P013C01-SCONNA
GND                      J25              81       SCONN288_ADR50001P013C01-SCONNA
GND                      J25              83       SCONN288_ADR50001P013C01-SCONNA
GND                      J25              85       SCONN288_ADR50001P013C01-SCONNA
GND                      J25              88       SCONN288_ADR50001P013C01-SCONNA
GND                      J25              90       SCONN288_ADR50001P013C01-SCONNA
GND                      J25              92       SCONN288_ADR50001P013C01-SCONNA
GND                      J25              95       SCONN288_ADR50001P013C01-SCONNA
GND                      J25              97       SCONN288_ADR50001P013C01-SCONNA
GND                      J25              99       SCONN288_ADR50001P013C01-SCONNA
GND                      J25              101      SCONN288_ADR50001P013C01-SCONNA
GND                      J25              103      SCONN288_ADR50001P013C01-SCONNA
GND                      J25              106      SCONN288_ADR50001P013C01-SCONNA
GND                      J25              108      SCONN288_ADR50001P013C01-SCONNA
GND                      J25              110      SCONN288_ADR50001P013C01-SCONNA
GND                      J25              112      SCONN288_ADR50001P013C01-SCONNA
GND                      J25              114      SCONN288_ADR50001P013C01-SCONNA
GND                      J25              117      SCONN288_ADR50001P013C01-SCONNA
GND                      J25              119      SCONN288_ADR50001P013C01-SCONNA
GND                      J25              121      SCONN288_ADR50001P013C01-SCONNA
GND                      J25              123      SCONN288_ADR50001P013C01-SCONNA
GND                      J25              125      SCONN288_ADR50001P013C01-SCONNA
GND                      J25              128      SCONN288_ADR50001P013C01-SCONNA
GND                      J25              130      SCONN288_ADR50001P013C01-SCONNA
GND                      J25              132      SCONN288_ADR50001P013C01-SCONNA
GND                      J25              134      SCONN288_ADR50001P013C01-SCONNA
GND                      J25              136      SCONN288_ADR50001P013C01-SCONNA
GND                      J25              139      SCONN288_ADR50001P013C01-SCONNA
GND                      J25              141      SCONN288_ADR50001P013C01-SCONNA
GND                      J25              143      SCONN288_ADR50001P013C01-SCONNA
GND                      J25              151      SCONN288_ADR50001P013C01-SCONNA
GND                      J25              153      SCONN288_ADR50001P013C01-SCONNA
GND                      J25              155      SCONN288_ADR50001P013C01-SCONNA
GND                      J25              158      SCONN288_ADR50001P013C01-SCONNA
GND                      J25              160      SCONN288_ADR50001P013C01-SCONNA
GND                      J25              162      SCONN288_ADR50001P013C01-SCONNA
GND                      J25              164      SCONN288_ADR50001P013C01-SCONNA
GND                      J25              166      SCONN288_ADR50001P013C01-SCONNA
GND                      J25              169      SCONN288_ADR50001P013C01-SCONNA
GND                      J25              171      SCONN288_ADR50001P013C01-SCONNA
GND                      J25              173      SCONN288_ADR50001P013C01-SCONNA
GND                      J25              175      SCONN288_ADR50001P013C01-SCONNA
GND                      J25              177      SCONN288_ADR50001P013C01-SCONNA
GND                      J25              180      SCONN288_ADR50001P013C01-SCONNA
GND                      J25              182      SCONN288_ADR50001P013C01-SCONNA
GND                      J25              184      SCONN288_ADR50001P013C01-SCONNA
GND                      J25              186      SCONN288_ADR50001P013C01-SCONNA
GND                      J25              188      SCONN288_ADR50001P013C01-SCONNA
GND                      J25              191      SCONN288_ADR50001P013C01-SCONNA
GND                      J25              193      SCONN288_ADR50001P013C01-SCONNA
GND                      J25              195      SCONN288_ADR50001P013C01-SCONNA
GND                      J25              197      SCONN288_ADR50001P013C01-SCONNA
GND                      J25              199      SCONN288_ADR50001P013C01-SCONNA
GND                      J25              202      SCONN288_ADR50001P013C01-SCONNA
GND                      J25              204      SCONN288_ADR50001P013C01-SCONNA
GND                      J25              206      SCONN288_ADR50001P013C01-SCONNA
GND                      J25              208      SCONN288_ADR50001P013C01-SCONNA
GND                      J25              210      SCONN288_ADR50001P013C01-SCONNA
GND                      J25              212      SCONN288_ADR50001P013C01-SCONNA
GND                      J25              214      SCONN288_ADR50001P013C01-SCONNA
GND                      J25              216      SCONN288_ADR50001P013C01-SCONNA
GND                      J25              219      SCONN288_ADR50001P013C01-SCONNA
GND                      J25              222      SCONN288_ADR50001P013C01-SCONNA
GND                      J25              224      SCONN288_ADR50001P013C01-SCONNA
GND                      J25              226      SCONN288_ADR50001P013C01-SCONNA
GND                      J25              228      SCONN288_ADR50001P013C01-SCONNA
GND                      J25              230      SCONN288_ADR50001P013C01-SCONNA
GND                      J25              233      SCONN288_ADR50001P013C01-SCONNA
GND                      J25              235      SCONN288_ADR50001P013C01-SCONNA
GND                      J25              237      SCONN288_ADR50001P013C01-SCONNA
GND                      J25              240      SCONN288_ADR50001P013C01-SCONNA
GND                      J25              242      SCONN288_ADR50001P013C01-SCONNA
GND                      J25              244      SCONN288_ADR50001P013C01-SCONNA
GND                      J25              246      SCONN288_ADR50001P013C01-SCONNA
GND                      J25              248      SCONN288_ADR50001P013C01-SCONNA
GND                      J25              251      SCONN288_ADR50001P013C01-SCONNA
GND                      J25              253      SCONN288_ADR50001P013C01-SCONNA
GND                      J25              255      SCONN288_ADR50001P013C01-SCONNA
GND                      J25              257      SCONN288_ADR50001P013C01-SCONNA
GND                      J25              259      SCONN288_ADR50001P013C01-SCONNA
GND                      J25              262      SCONN288_ADR50001P013C01-SCONNA
GND                      J25              264      SCONN288_ADR50001P013C01-SCONNA
GND                      J25              266      SCONN288_ADR50001P013C01-SCONNA
GND                      J25              268      SCONN288_ADR50001P013C01-SCONNA
GND                      J25              270      SCONN288_ADR50001P013C01-SCONNA
GND                      J25              273      SCONN288_ADR50001P013C01-SCONNA
GND                      J25              275      SCONN288_ADR50001P013C01-SCONNA
GND                      J25              277      SCONN288_ADR50001P013C01-SCONNA
GND                      J25              279      SCONN288_ADR50001P013C01-SCONNA
GND                      J25              281      SCONN288_ADR50001P013C01-SCONNA
GND                      J25              284      SCONN288_ADR50001P013C01-SCONNA
GND                      J25              286      SCONN288_ADR50001P013C01-SCONNA
GND                      J25              288      SCONN288_ADR50001P013C01-SCONNA
GND                      J25              G1       SCONN288_ADR50001P013C01-SCONNA
GND                      J25              G2       SCONN288_ADR50001P013C01-SCONNA
GND                      J25              G3       SCONN288_ADR50001P013C01-SCONNA
GND                      J26              6        SCONN288_ADR50001P003C01-SCONNA
GND                      J26              8        SCONN288_ADR50001P003C01-SCONNA
GND                      J26              10       SCONN288_ADR50001P003C01-SCONNA
GND                      J26              13       SCONN288_ADR50001P003C01-SCONNA
GND                      J26              15       SCONN288_ADR50001P003C01-SCONNA
GND                      J26              17       SCONN288_ADR50001P003C01-SCONNA
GND                      J26              19       SCONN288_ADR50001P003C01-SCONNA
GND                      J26              21       SCONN288_ADR50001P003C01-SCONNA
GND                      J26              24       SCONN288_ADR50001P003C01-SCONNA
GND                      J26              26       SCONN288_ADR50001P003C01-SCONNA
GND                      J26              28       SCONN288_ADR50001P003C01-SCONNA
GND                      J26              30       SCONN288_ADR50001P003C01-SCONNA
GND                      J26              32       SCONN288_ADR50001P003C01-SCONNA
GND                      J26              35       SCONN288_ADR50001P003C01-SCONNA
GND                      J26              37       SCONN288_ADR50001P003C01-SCONNA
GND                      J26              39       SCONN288_ADR50001P003C01-SCONNA
GND                      J26              41       SCONN288_ADR50001P003C01-SCONNA
GND                      J26              43       SCONN288_ADR50001P003C01-SCONNA
GND                      J26              46       SCONN288_ADR50001P003C01-SCONNA
GND                      J26              48       SCONN288_ADR50001P003C01-SCONNA
GND                      J26              50       SCONN288_ADR50001P003C01-SCONNA
GND                      J26              52       SCONN288_ADR50001P003C01-SCONNA
GND                      J26              54       SCONN288_ADR50001P003C01-SCONNA
GND                      J26              57       SCONN288_ADR50001P003C01-SCONNA
GND                      J26              59       SCONN288_ADR50001P003C01-SCONNA
GND                      J26              61       SCONN288_ADR50001P003C01-SCONNA
GND                      J26              63       SCONN288_ADR50001P003C01-SCONNA
GND                      J26              65       SCONN288_ADR50001P003C01-SCONNA
GND                      J26              67       SCONN288_ADR50001P003C01-SCONNA
GND                      J26              69       SCONN288_ADR50001P003C01-SCONNA
GND                      J26              71       SCONN288_ADR50001P003C01-SCONNA
GND                      J26              73       SCONN288_ADR50001P003C01-SCONNA
GND                      J26              75       SCONN288_ADR50001P003C01-SCONNA
GND                      J26              77       SCONN288_ADR50001P003C01-SCONNA
GND                      J26              79       SCONN288_ADR50001P003C01-SCONNA
GND                      J26              81       SCONN288_ADR50001P003C01-SCONNA
GND                      J26              83       SCONN288_ADR50001P003C01-SCONNA
GND                      J26              85       SCONN288_ADR50001P003C01-SCONNA
GND                      J26              88       SCONN288_ADR50001P003C01-SCONNA
GND                      J26              90       SCONN288_ADR50001P003C01-SCONNA
GND                      J26              92       SCONN288_ADR50001P003C01-SCONNA
GND                      J26              95       SCONN288_ADR50001P003C01-SCONNA
GND                      J26              97       SCONN288_ADR50001P003C01-SCONNA
GND                      J26              99       SCONN288_ADR50001P003C01-SCONNA
GND                      J26              101      SCONN288_ADR50001P003C01-SCONNA
GND                      J26              103      SCONN288_ADR50001P003C01-SCONNA
GND                      J26              106      SCONN288_ADR50001P003C01-SCONNA
GND                      J26              108      SCONN288_ADR50001P003C01-SCONNA
GND                      J26              110      SCONN288_ADR50001P003C01-SCONNA
GND                      J26              112      SCONN288_ADR50001P003C01-SCONNA
GND                      J26              114      SCONN288_ADR50001P003C01-SCONNA
GND                      J26              117      SCONN288_ADR50001P003C01-SCONNA
GND                      J26              119      SCONN288_ADR50001P003C01-SCONNA
GND                      J26              121      SCONN288_ADR50001P003C01-SCONNA
GND                      J26              123      SCONN288_ADR50001P003C01-SCONNA
GND                      J26              125      SCONN288_ADR50001P003C01-SCONNA
GND                      J26              128      SCONN288_ADR50001P003C01-SCONNA
GND                      J26              130      SCONN288_ADR50001P003C01-SCONNA
GND                      J26              132      SCONN288_ADR50001P003C01-SCONNA
GND                      J26              134      SCONN288_ADR50001P003C01-SCONNA
GND                      J26              136      SCONN288_ADR50001P003C01-SCONNA
GND                      J26              139      SCONN288_ADR50001P003C01-SCONNA
GND                      J26              141      SCONN288_ADR50001P003C01-SCONNA
GND                      J26              143      SCONN288_ADR50001P003C01-SCONNA
GND                      J26              151      SCONN288_ADR50001P003C01-SCONNA
GND                      J26              153      SCONN288_ADR50001P003C01-SCONNA
GND                      J26              155      SCONN288_ADR50001P003C01-SCONNA
GND                      J26              158      SCONN288_ADR50001P003C01-SCONNA
GND                      J26              160      SCONN288_ADR50001P003C01-SCONNA
GND                      J26              162      SCONN288_ADR50001P003C01-SCONNA
GND                      J26              164      SCONN288_ADR50001P003C01-SCONNA
GND                      J26              166      SCONN288_ADR50001P003C01-SCONNA
GND                      J26              169      SCONN288_ADR50001P003C01-SCONNA
GND                      J26              171      SCONN288_ADR50001P003C01-SCONNA
GND                      J26              173      SCONN288_ADR50001P003C01-SCONNA
GND                      J26              175      SCONN288_ADR50001P003C01-SCONNA
GND                      J26              177      SCONN288_ADR50001P003C01-SCONNA
GND                      J26              180      SCONN288_ADR50001P003C01-SCONNA
GND                      J26              182      SCONN288_ADR50001P003C01-SCONNA
GND                      J26              184      SCONN288_ADR50001P003C01-SCONNA
GND                      J26              186      SCONN288_ADR50001P003C01-SCONNA
GND                      J26              188      SCONN288_ADR50001P003C01-SCONNA
GND                      J26              191      SCONN288_ADR50001P003C01-SCONNA
GND                      J26              193      SCONN288_ADR50001P003C01-SCONNA
GND                      J26              195      SCONN288_ADR50001P003C01-SCONNA
GND                      J26              197      SCONN288_ADR50001P003C01-SCONNA
GND                      J26              199      SCONN288_ADR50001P003C01-SCONNA
GND                      J26              202      SCONN288_ADR50001P003C01-SCONNA
GND                      J26              204      SCONN288_ADR50001P003C01-SCONNA
GND                      J26              206      SCONN288_ADR50001P003C01-SCONNA
GND                      J26              208      SCONN288_ADR50001P003C01-SCONNA
GND                      J26              210      SCONN288_ADR50001P003C01-SCONNA
GND                      J26              212      SCONN288_ADR50001P003C01-SCONNA
GND                      J26              214      SCONN288_ADR50001P003C01-SCONNA
GND                      J26              216      SCONN288_ADR50001P003C01-SCONNA
GND                      J26              219      SCONN288_ADR50001P003C01-SCONNA
GND                      J26              222      SCONN288_ADR50001P003C01-SCONNA
GND                      J26              224      SCONN288_ADR50001P003C01-SCONNA
GND                      J26              226      SCONN288_ADR50001P003C01-SCONNA
GND                      J26              228      SCONN288_ADR50001P003C01-SCONNA
GND                      J26              230      SCONN288_ADR50001P003C01-SCONNA
GND                      J26              233      SCONN288_ADR50001P003C01-SCONNA
GND                      J26              235      SCONN288_ADR50001P003C01-SCONNA
GND                      J26              237      SCONN288_ADR50001P003C01-SCONNA
GND                      J26              240      SCONN288_ADR50001P003C01-SCONNA
GND                      J26              242      SCONN288_ADR50001P003C01-SCONNA
GND                      J26              244      SCONN288_ADR50001P003C01-SCONNA
GND                      J26              246      SCONN288_ADR50001P003C01-SCONNA
GND                      J26              248      SCONN288_ADR50001P003C01-SCONNA
GND                      J26              251      SCONN288_ADR50001P003C01-SCONNA
GND                      J26              253      SCONN288_ADR50001P003C01-SCONNA
GND                      J26              255      SCONN288_ADR50001P003C01-SCONNA
GND                      J26              257      SCONN288_ADR50001P003C01-SCONNA
GND                      J26              259      SCONN288_ADR50001P003C01-SCONNA
GND                      J26              262      SCONN288_ADR50001P003C01-SCONNA
GND                      J26              264      SCONN288_ADR50001P003C01-SCONNA
GND                      J26              266      SCONN288_ADR50001P003C01-SCONNA
GND                      J26              268      SCONN288_ADR50001P003C01-SCONNA
GND                      J26              270      SCONN288_ADR50001P003C01-SCONNA
GND                      J26              273      SCONN288_ADR50001P003C01-SCONNA
GND                      J26              275      SCONN288_ADR50001P003C01-SCONNA
GND                      J26              277      SCONN288_ADR50001P003C01-SCONNA
GND                      J26              279      SCONN288_ADR50001P003C01-SCONNA
GND                      J26              281      SCONN288_ADR50001P003C01-SCONNA
GND                      J26              284      SCONN288_ADR50001P003C01-SCONNA
GND                      J26              286      SCONN288_ADR50001P003C01-SCONNA
GND                      J26              288      SCONN288_ADR50001P003C01-SCONNA
GND                      J26              G1       SCONN288_ADR50001P003C01-SCONNA
GND                      J26              G2       SCONN288_ADR50001P003C01-SCONNA
GND                      J26              G3       SCONN288_ADR50001P003C01-SCONNA
GND                      J27              6        SCONN288_ADR50001P013C01-SCONNA
GND                      J27              8        SCONN288_ADR50001P013C01-SCONNA
GND                      J27              10       SCONN288_ADR50001P013C01-SCONNA
GND                      J27              13       SCONN288_ADR50001P013C01-SCONNA
GND                      J27              15       SCONN288_ADR50001P013C01-SCONNA
GND                      J27              17       SCONN288_ADR50001P013C01-SCONNA
GND                      J27              19       SCONN288_ADR50001P013C01-SCONNA
GND                      J27              21       SCONN288_ADR50001P013C01-SCONNA
GND                      J27              24       SCONN288_ADR50001P013C01-SCONNA
GND                      J27              26       SCONN288_ADR50001P013C01-SCONNA
GND                      J27              28       SCONN288_ADR50001P013C01-SCONNA
GND                      J27              30       SCONN288_ADR50001P013C01-SCONNA
GND                      J27              32       SCONN288_ADR50001P013C01-SCONNA
GND                      J27              35       SCONN288_ADR50001P013C01-SCONNA
GND                      J27              37       SCONN288_ADR50001P013C01-SCONNA
GND                      J27              39       SCONN288_ADR50001P013C01-SCONNA
GND                      J27              41       SCONN288_ADR50001P013C01-SCONNA
GND                      J27              43       SCONN288_ADR50001P013C01-SCONNA
GND                      J27              46       SCONN288_ADR50001P013C01-SCONNA
GND                      J27              48       SCONN288_ADR50001P013C01-SCONNA
GND                      J27              50       SCONN288_ADR50001P013C01-SCONNA
GND                      J27              52       SCONN288_ADR50001P013C01-SCONNA
GND                      J27              54       SCONN288_ADR50001P013C01-SCONNA
GND                      J27              57       SCONN288_ADR50001P013C01-SCONNA
GND                      J27              59       SCONN288_ADR50001P013C01-SCONNA
GND                      J27              61       SCONN288_ADR50001P013C01-SCONNA
GND                      J27              63       SCONN288_ADR50001P013C01-SCONNA
GND                      J27              65       SCONN288_ADR50001P013C01-SCONNA
GND                      J27              67       SCONN288_ADR50001P013C01-SCONNA
GND                      J27              69       SCONN288_ADR50001P013C01-SCONNA
GND                      J27              71       SCONN288_ADR50001P013C01-SCONNA
GND                      J27              73       SCONN288_ADR50001P013C01-SCONNA
GND                      J27              75       SCONN288_ADR50001P013C01-SCONNA
GND                      J27              77       SCONN288_ADR50001P013C01-SCONNA
GND                      J27              79       SCONN288_ADR50001P013C01-SCONNA
GND                      J27              81       SCONN288_ADR50001P013C01-SCONNA
GND                      J27              83       SCONN288_ADR50001P013C01-SCONNA
GND                      J27              85       SCONN288_ADR50001P013C01-SCONNA
GND                      J27              88       SCONN288_ADR50001P013C01-SCONNA
GND                      J27              90       SCONN288_ADR50001P013C01-SCONNA
GND                      J27              92       SCONN288_ADR50001P013C01-SCONNA
GND                      J27              95       SCONN288_ADR50001P013C01-SCONNA
GND                      J27              97       SCONN288_ADR50001P013C01-SCONNA
GND                      J27              99       SCONN288_ADR50001P013C01-SCONNA
GND                      J27              101      SCONN288_ADR50001P013C01-SCONNA
GND                      J27              103      SCONN288_ADR50001P013C01-SCONNA
GND                      J27              106      SCONN288_ADR50001P013C01-SCONNA
GND                      J27              108      SCONN288_ADR50001P013C01-SCONNA
GND                      J27              110      SCONN288_ADR50001P013C01-SCONNA
GND                      J27              112      SCONN288_ADR50001P013C01-SCONNA
GND                      J27              114      SCONN288_ADR50001P013C01-SCONNA
GND                      J27              117      SCONN288_ADR50001P013C01-SCONNA
GND                      J27              119      SCONN288_ADR50001P013C01-SCONNA
GND                      J27              121      SCONN288_ADR50001P013C01-SCONNA
GND                      J27              123      SCONN288_ADR50001P013C01-SCONNA
GND                      J27              125      SCONN288_ADR50001P013C01-SCONNA
GND                      J27              128      SCONN288_ADR50001P013C01-SCONNA
GND                      J27              130      SCONN288_ADR50001P013C01-SCONNA
GND                      J27              132      SCONN288_ADR50001P013C01-SCONNA
GND                      J27              134      SCONN288_ADR50001P013C01-SCONNA
GND                      J27              136      SCONN288_ADR50001P013C01-SCONNA
GND                      J27              139      SCONN288_ADR50001P013C01-SCONNA
GND                      J27              141      SCONN288_ADR50001P013C01-SCONNA
GND                      J27              143      SCONN288_ADR50001P013C01-SCONNA
GND                      J27              151      SCONN288_ADR50001P013C01-SCONNA
GND                      J27              153      SCONN288_ADR50001P013C01-SCONNA
GND                      J27              155      SCONN288_ADR50001P013C01-SCONNA
GND                      J27              158      SCONN288_ADR50001P013C01-SCONNA
GND                      J27              160      SCONN288_ADR50001P013C01-SCONNA
GND                      J27              162      SCONN288_ADR50001P013C01-SCONNA
GND                      J27              164      SCONN288_ADR50001P013C01-SCONNA
GND                      J27              166      SCONN288_ADR50001P013C01-SCONNA
GND                      J27              169      SCONN288_ADR50001P013C01-SCONNA
GND                      J27              171      SCONN288_ADR50001P013C01-SCONNA
GND                      J27              173      SCONN288_ADR50001P013C01-SCONNA
GND                      J27              175      SCONN288_ADR50001P013C01-SCONNA
GND                      J27              177      SCONN288_ADR50001P013C01-SCONNA
GND                      J27              180      SCONN288_ADR50001P013C01-SCONNA
GND                      J27              182      SCONN288_ADR50001P013C01-SCONNA
GND                      J27              184      SCONN288_ADR50001P013C01-SCONNA
GND                      J27              186      SCONN288_ADR50001P013C01-SCONNA
GND                      J27              188      SCONN288_ADR50001P013C01-SCONNA
GND                      J27              191      SCONN288_ADR50001P013C01-SCONNA
GND                      J27              193      SCONN288_ADR50001P013C01-SCONNA
GND                      J27              195      SCONN288_ADR50001P013C01-SCONNA
GND                      J27              197      SCONN288_ADR50001P013C01-SCONNA
GND                      J27              199      SCONN288_ADR50001P013C01-SCONNA
GND                      J27              202      SCONN288_ADR50001P013C01-SCONNA
GND                      J27              204      SCONN288_ADR50001P013C01-SCONNA
GND                      J27              206      SCONN288_ADR50001P013C01-SCONNA
GND                      J27              208      SCONN288_ADR50001P013C01-SCONNA
GND                      J27              210      SCONN288_ADR50001P013C01-SCONNA
GND                      J27              212      SCONN288_ADR50001P013C01-SCONNA
GND                      J27              214      SCONN288_ADR50001P013C01-SCONNA
GND                      J27              216      SCONN288_ADR50001P013C01-SCONNA
GND                      J27              219      SCONN288_ADR50001P013C01-SCONNA
GND                      J27              222      SCONN288_ADR50001P013C01-SCONNA
GND                      J27              224      SCONN288_ADR50001P013C01-SCONNA
GND                      J27              226      SCONN288_ADR50001P013C01-SCONNA
GND                      J27              228      SCONN288_ADR50001P013C01-SCONNA
GND                      J27              230      SCONN288_ADR50001P013C01-SCONNA
GND                      J27              233      SCONN288_ADR50001P013C01-SCONNA
GND                      J27              235      SCONN288_ADR50001P013C01-SCONNA
GND                      J27              237      SCONN288_ADR50001P013C01-SCONNA
GND                      J27              240      SCONN288_ADR50001P013C01-SCONNA
GND                      J27              242      SCONN288_ADR50001P013C01-SCONNA
GND                      J27              244      SCONN288_ADR50001P013C01-SCONNA
GND                      J27              246      SCONN288_ADR50001P013C01-SCONNA
GND                      J27              248      SCONN288_ADR50001P013C01-SCONNA
GND                      J27              251      SCONN288_ADR50001P013C01-SCONNA
GND                      J27              253      SCONN288_ADR50001P013C01-SCONNA
GND                      J27              255      SCONN288_ADR50001P013C01-SCONNA
GND                      J27              257      SCONN288_ADR50001P013C01-SCONNA
GND                      J27              259      SCONN288_ADR50001P013C01-SCONNA
GND                      J27              262      SCONN288_ADR50001P013C01-SCONNA
GND                      J27              264      SCONN288_ADR50001P013C01-SCONNA
GND                      J27              266      SCONN288_ADR50001P013C01-SCONNA
GND                      J27              268      SCONN288_ADR50001P013C01-SCONNA
GND                      J27              270      SCONN288_ADR50001P013C01-SCONNA
GND                      J27              273      SCONN288_ADR50001P013C01-SCONNA
GND                      J27              275      SCONN288_ADR50001P013C01-SCONNA
GND                      J27              277      SCONN288_ADR50001P013C01-SCONNA
GND                      J27              279      SCONN288_ADR50001P013C01-SCONNA
GND                      J27              281      SCONN288_ADR50001P013C01-SCONNA
GND                      J27              284      SCONN288_ADR50001P013C01-SCONNA
GND                      J27              286      SCONN288_ADR50001P013C01-SCONNA
GND                      J27              288      SCONN288_ADR50001P013C01-SCONNA
GND                      J27              G1       SCONN288_ADR50001P013C01-SCONNA
GND                      J27              G2       SCONN288_ADR50001P013C01-SCONNA
GND                      J27              G3       SCONN288_ADR50001P013C01-SCONNA
GND                      J28              6        SCONN288_ADR50001P003C01-SCONNA
GND                      J28              8        SCONN288_ADR50001P003C01-SCONNA
GND                      J28              10       SCONN288_ADR50001P003C01-SCONNA
GND                      J28              13       SCONN288_ADR50001P003C01-SCONNA
GND                      J28              15       SCONN288_ADR50001P003C01-SCONNA
GND                      J28              17       SCONN288_ADR50001P003C01-SCONNA
GND                      J28              19       SCONN288_ADR50001P003C01-SCONNA
GND                      J28              21       SCONN288_ADR50001P003C01-SCONNA
GND                      J28              24       SCONN288_ADR50001P003C01-SCONNA
GND                      J28              26       SCONN288_ADR50001P003C01-SCONNA
GND                      J28              28       SCONN288_ADR50001P003C01-SCONNA
GND                      J28              30       SCONN288_ADR50001P003C01-SCONNA
GND                      J28              32       SCONN288_ADR50001P003C01-SCONNA
GND                      J28              35       SCONN288_ADR50001P003C01-SCONNA
GND                      J28              37       SCONN288_ADR50001P003C01-SCONNA
GND                      J28              39       SCONN288_ADR50001P003C01-SCONNA
GND                      J28              41       SCONN288_ADR50001P003C01-SCONNA
GND                      J28              43       SCONN288_ADR50001P003C01-SCONNA
GND                      J28              46       SCONN288_ADR50001P003C01-SCONNA
GND                      J28              48       SCONN288_ADR50001P003C01-SCONNA
GND                      J28              50       SCONN288_ADR50001P003C01-SCONNA
GND                      J28              52       SCONN288_ADR50001P003C01-SCONNA
GND                      J28              54       SCONN288_ADR50001P003C01-SCONNA
GND                      J28              57       SCONN288_ADR50001P003C01-SCONNA
GND                      J28              59       SCONN288_ADR50001P003C01-SCONNA
GND                      J28              61       SCONN288_ADR50001P003C01-SCONNA
GND                      J28              63       SCONN288_ADR50001P003C01-SCONNA
GND                      J28              65       SCONN288_ADR50001P003C01-SCONNA
GND                      J28              67       SCONN288_ADR50001P003C01-SCONNA
GND                      J28              69       SCONN288_ADR50001P003C01-SCONNA
GND                      J28              71       SCONN288_ADR50001P003C01-SCONNA
GND                      J28              73       SCONN288_ADR50001P003C01-SCONNA
GND                      J28              75       SCONN288_ADR50001P003C01-SCONNA
GND                      J28              77       SCONN288_ADR50001P003C01-SCONNA
GND                      J28              79       SCONN288_ADR50001P003C01-SCONNA
GND                      J28              81       SCONN288_ADR50001P003C01-SCONNA
GND                      J28              83       SCONN288_ADR50001P003C01-SCONNA
GND                      J28              85       SCONN288_ADR50001P003C01-SCONNA
GND                      J28              88       SCONN288_ADR50001P003C01-SCONNA
GND                      J28              90       SCONN288_ADR50001P003C01-SCONNA
GND                      J28              92       SCONN288_ADR50001P003C01-SCONNA
GND                      J28              95       SCONN288_ADR50001P003C01-SCONNA
GND                      J28              97       SCONN288_ADR50001P003C01-SCONNA
GND                      J28              99       SCONN288_ADR50001P003C01-SCONNA
GND                      J28              101      SCONN288_ADR50001P003C01-SCONNA
GND                      J28              103      SCONN288_ADR50001P003C01-SCONNA
GND                      J28              106      SCONN288_ADR50001P003C01-SCONNA
GND                      J28              108      SCONN288_ADR50001P003C01-SCONNA
GND                      J28              110      SCONN288_ADR50001P003C01-SCONNA
GND                      J28              112      SCONN288_ADR50001P003C01-SCONNA
GND                      J28              114      SCONN288_ADR50001P003C01-SCONNA
GND                      J28              117      SCONN288_ADR50001P003C01-SCONNA
GND                      J28              119      SCONN288_ADR50001P003C01-SCONNA
GND                      J28              121      SCONN288_ADR50001P003C01-SCONNA
GND                      J28              123      SCONN288_ADR50001P003C01-SCONNA
GND                      J28              125      SCONN288_ADR50001P003C01-SCONNA
GND                      J28              128      SCONN288_ADR50001P003C01-SCONNA
GND                      J28              130      SCONN288_ADR50001P003C01-SCONNA
GND                      J28              132      SCONN288_ADR50001P003C01-SCONNA
GND                      J28              134      SCONN288_ADR50001P003C01-SCONNA
GND                      J28              136      SCONN288_ADR50001P003C01-SCONNA
GND                      J28              139      SCONN288_ADR50001P003C01-SCONNA
GND                      J28              141      SCONN288_ADR50001P003C01-SCONNA
GND                      J28              143      SCONN288_ADR50001P003C01-SCONNA
GND                      J28              151      SCONN288_ADR50001P003C01-SCONNA
GND                      J28              153      SCONN288_ADR50001P003C01-SCONNA
GND                      J28              155      SCONN288_ADR50001P003C01-SCONNA
GND                      J28              158      SCONN288_ADR50001P003C01-SCONNA
GND                      J28              160      SCONN288_ADR50001P003C01-SCONNA
GND                      J28              162      SCONN288_ADR50001P003C01-SCONNA
GND                      J28              164      SCONN288_ADR50001P003C01-SCONNA
GND                      J28              166      SCONN288_ADR50001P003C01-SCONNA
GND                      J28              169      SCONN288_ADR50001P003C01-SCONNA
GND                      J28              171      SCONN288_ADR50001P003C01-SCONNA
GND                      J28              173      SCONN288_ADR50001P003C01-SCONNA
GND                      J28              175      SCONN288_ADR50001P003C01-SCONNA
GND                      J28              177      SCONN288_ADR50001P003C01-SCONNA
GND                      J28              180      SCONN288_ADR50001P003C01-SCONNA
GND                      J28              182      SCONN288_ADR50001P003C01-SCONNA
GND                      J28              184      SCONN288_ADR50001P003C01-SCONNA
GND                      J28              186      SCONN288_ADR50001P003C01-SCONNA
GND                      J28              188      SCONN288_ADR50001P003C01-SCONNA
GND                      J28              191      SCONN288_ADR50001P003C01-SCONNA
GND                      J28              193      SCONN288_ADR50001P003C01-SCONNA
GND                      J28              195      SCONN288_ADR50001P003C01-SCONNA
GND                      J28              197      SCONN288_ADR50001P003C01-SCONNA
GND                      J28              199      SCONN288_ADR50001P003C01-SCONNA
GND                      J28              202      SCONN288_ADR50001P003C01-SCONNA
GND                      J28              204      SCONN288_ADR50001P003C01-SCONNA
GND                      J28              206      SCONN288_ADR50001P003C01-SCONNA
GND                      J28              208      SCONN288_ADR50001P003C01-SCONNA
GND                      J28              210      SCONN288_ADR50001P003C01-SCONNA
GND                      J28              212      SCONN288_ADR50001P003C01-SCONNA
GND                      J28              214      SCONN288_ADR50001P003C01-SCONNA
GND                      J28              216      SCONN288_ADR50001P003C01-SCONNA
GND                      J28              219      SCONN288_ADR50001P003C01-SCONNA
GND                      J28              222      SCONN288_ADR50001P003C01-SCONNA
GND                      J28              224      SCONN288_ADR50001P003C01-SCONNA
GND                      J28              226      SCONN288_ADR50001P003C01-SCONNA
GND                      J28              228      SCONN288_ADR50001P003C01-SCONNA
GND                      J28              230      SCONN288_ADR50001P003C01-SCONNA
GND                      J28              233      SCONN288_ADR50001P003C01-SCONNA
GND                      J28              235      SCONN288_ADR50001P003C01-SCONNA
GND                      J28              237      SCONN288_ADR50001P003C01-SCONNA
GND                      J28              240      SCONN288_ADR50001P003C01-SCONNA
GND                      J28              242      SCONN288_ADR50001P003C01-SCONNA
GND                      J28              244      SCONN288_ADR50001P003C01-SCONNA
GND                      J28              246      SCONN288_ADR50001P003C01-SCONNA
GND                      J28              248      SCONN288_ADR50001P003C01-SCONNA
GND                      J28              251      SCONN288_ADR50001P003C01-SCONNA
GND                      J28              253      SCONN288_ADR50001P003C01-SCONNA
GND                      J28              255      SCONN288_ADR50001P003C01-SCONNA
GND                      J28              257      SCONN288_ADR50001P003C01-SCONNA
GND                      J28              259      SCONN288_ADR50001P003C01-SCONNA
GND                      J28              262      SCONN288_ADR50001P003C01-SCONNA
GND                      J28              264      SCONN288_ADR50001P003C01-SCONNA
GND                      J28              266      SCONN288_ADR50001P003C01-SCONNA
GND                      J28              268      SCONN288_ADR50001P003C01-SCONNA
GND                      J28              270      SCONN288_ADR50001P003C01-SCONNA
GND                      J28              273      SCONN288_ADR50001P003C01-SCONNA
GND                      J28              275      SCONN288_ADR50001P003C01-SCONNA
GND                      J28              277      SCONN288_ADR50001P003C01-SCONNA
GND                      J28              279      SCONN288_ADR50001P003C01-SCONNA
GND                      J28              281      SCONN288_ADR50001P003C01-SCONNA
GND                      J28              284      SCONN288_ADR50001P003C01-SCONNA
GND                      J28              286      SCONN288_ADR50001P003C01-SCONNA
GND                      J28              288      SCONN288_ADR50001P003C01-SCONNA
GND                      J28              G1       SCONN288_ADR50001P003C01-SCONNA
GND                      J28              G2       SCONN288_ADR50001P003C01-SCONNA
GND                      J28              G3       SCONN288_ADR50001P003C01-SCONNA
GND                      J29              6        SCONN288_ADR50001P013C01-SCONNA
GND                      J29              8        SCONN288_ADR50001P013C01-SCONNA
GND                      J29              10       SCONN288_ADR50001P013C01-SCONNA
GND                      J29              13       SCONN288_ADR50001P013C01-SCONNA
GND                      J29              15       SCONN288_ADR50001P013C01-SCONNA
GND                      J29              17       SCONN288_ADR50001P013C01-SCONNA
GND                      J29              19       SCONN288_ADR50001P013C01-SCONNA
GND                      J29              21       SCONN288_ADR50001P013C01-SCONNA
GND                      J29              24       SCONN288_ADR50001P013C01-SCONNA
GND                      J29              26       SCONN288_ADR50001P013C01-SCONNA
GND                      J29              28       SCONN288_ADR50001P013C01-SCONNA
GND                      J29              30       SCONN288_ADR50001P013C01-SCONNA
GND                      J29              32       SCONN288_ADR50001P013C01-SCONNA
GND                      J29              35       SCONN288_ADR50001P013C01-SCONNA
GND                      J29              37       SCONN288_ADR50001P013C01-SCONNA
GND                      J29              39       SCONN288_ADR50001P013C01-SCONNA
GND                      J29              41       SCONN288_ADR50001P013C01-SCONNA
GND                      J29              43       SCONN288_ADR50001P013C01-SCONNA
GND                      J29              46       SCONN288_ADR50001P013C01-SCONNA
GND                      J29              48       SCONN288_ADR50001P013C01-SCONNA
GND                      J29              50       SCONN288_ADR50001P013C01-SCONNA
GND                      J29              52       SCONN288_ADR50001P013C01-SCONNA
GND                      J29              54       SCONN288_ADR50001P013C01-SCONNA
GND                      J29              57       SCONN288_ADR50001P013C01-SCONNA
GND                      J29              59       SCONN288_ADR50001P013C01-SCONNA
GND                      J29              61       SCONN288_ADR50001P013C01-SCONNA
GND                      J29              63       SCONN288_ADR50001P013C01-SCONNA
GND                      J29              65       SCONN288_ADR50001P013C01-SCONNA
GND                      J29              67       SCONN288_ADR50001P013C01-SCONNA
GND                      J29              69       SCONN288_ADR50001P013C01-SCONNA
GND                      J29              71       SCONN288_ADR50001P013C01-SCONNA
GND                      J29              73       SCONN288_ADR50001P013C01-SCONNA
GND                      J29              75       SCONN288_ADR50001P013C01-SCONNA
GND                      J29              77       SCONN288_ADR50001P013C01-SCONNA
GND                      J29              79       SCONN288_ADR50001P013C01-SCONNA
GND                      J29              81       SCONN288_ADR50001P013C01-SCONNA
GND                      J29              83       SCONN288_ADR50001P013C01-SCONNA
GND                      J29              85       SCONN288_ADR50001P013C01-SCONNA
GND                      J29              88       SCONN288_ADR50001P013C01-SCONNA
GND                      J29              90       SCONN288_ADR50001P013C01-SCONNA
GND                      J29              92       SCONN288_ADR50001P013C01-SCONNA
GND                      J29              95       SCONN288_ADR50001P013C01-SCONNA
GND                      J29              97       SCONN288_ADR50001P013C01-SCONNA
GND                      J29              99       SCONN288_ADR50001P013C01-SCONNA
GND                      J29              101      SCONN288_ADR50001P013C01-SCONNA
GND                      J29              103      SCONN288_ADR50001P013C01-SCONNA
GND                      J29              106      SCONN288_ADR50001P013C01-SCONNA
GND                      J29              108      SCONN288_ADR50001P013C01-SCONNA
GND                      J29              110      SCONN288_ADR50001P013C01-SCONNA
GND                      J29              112      SCONN288_ADR50001P013C01-SCONNA
GND                      J29              114      SCONN288_ADR50001P013C01-SCONNA
GND                      J29              117      SCONN288_ADR50001P013C01-SCONNA
GND                      J29              119      SCONN288_ADR50001P013C01-SCONNA
GND                      J29              121      SCONN288_ADR50001P013C01-SCONNA
GND                      J29              123      SCONN288_ADR50001P013C01-SCONNA
GND                      J29              125      SCONN288_ADR50001P013C01-SCONNA
GND                      J29              128      SCONN288_ADR50001P013C01-SCONNA
GND                      J29              130      SCONN288_ADR50001P013C01-SCONNA
GND                      J29              132      SCONN288_ADR50001P013C01-SCONNA
GND                      J29              134      SCONN288_ADR50001P013C01-SCONNA
GND                      J29              136      SCONN288_ADR50001P013C01-SCONNA
GND                      J29              139      SCONN288_ADR50001P013C01-SCONNA
GND                      J29              141      SCONN288_ADR50001P013C01-SCONNA
GND                      J29              143      SCONN288_ADR50001P013C01-SCONNA
GND                      J29              151      SCONN288_ADR50001P013C01-SCONNA
GND                      J29              153      SCONN288_ADR50001P013C01-SCONNA
GND                      J29              155      SCONN288_ADR50001P013C01-SCONNA
GND                      J29              158      SCONN288_ADR50001P013C01-SCONNA
GND                      J29              160      SCONN288_ADR50001P013C01-SCONNA
GND                      J29              162      SCONN288_ADR50001P013C01-SCONNA
GND                      J29              164      SCONN288_ADR50001P013C01-SCONNA
GND                      J29              166      SCONN288_ADR50001P013C01-SCONNA
GND                      J29              169      SCONN288_ADR50001P013C01-SCONNA
GND                      J29              171      SCONN288_ADR50001P013C01-SCONNA
GND                      J29              173      SCONN288_ADR50001P013C01-SCONNA
GND                      J29              175      SCONN288_ADR50001P013C01-SCONNA
GND                      J29              177      SCONN288_ADR50001P013C01-SCONNA
GND                      J29              180      SCONN288_ADR50001P013C01-SCONNA
GND                      J29              182      SCONN288_ADR50001P013C01-SCONNA
GND                      J29              184      SCONN288_ADR50001P013C01-SCONNA
GND                      J29              186      SCONN288_ADR50001P013C01-SCONNA
GND                      J29              188      SCONN288_ADR50001P013C01-SCONNA
GND                      J29              191      SCONN288_ADR50001P013C01-SCONNA
GND                      J29              193      SCONN288_ADR50001P013C01-SCONNA
GND                      J29              195      SCONN288_ADR50001P013C01-SCONNA
GND                      J29              197      SCONN288_ADR50001P013C01-SCONNA
GND                      J29              199      SCONN288_ADR50001P013C01-SCONNA
GND                      J29              202      SCONN288_ADR50001P013C01-SCONNA
GND                      J29              204      SCONN288_ADR50001P013C01-SCONNA
GND                      J29              206      SCONN288_ADR50001P013C01-SCONNA
GND                      J29              208      SCONN288_ADR50001P013C01-SCONNA
GND                      J29              210      SCONN288_ADR50001P013C01-SCONNA
GND                      J29              212      SCONN288_ADR50001P013C01-SCONNA
GND                      J29              214      SCONN288_ADR50001P013C01-SCONNA
GND                      J29              216      SCONN288_ADR50001P013C01-SCONNA
GND                      J29              219      SCONN288_ADR50001P013C01-SCONNA
GND                      J29              222      SCONN288_ADR50001P013C01-SCONNA
GND                      J29              224      SCONN288_ADR50001P013C01-SCONNA
GND                      J29              226      SCONN288_ADR50001P013C01-SCONNA
GND                      J29              228      SCONN288_ADR50001P013C01-SCONNA
GND                      J29              230      SCONN288_ADR50001P013C01-SCONNA
GND                      J29              233      SCONN288_ADR50001P013C01-SCONNA
GND                      J29              235      SCONN288_ADR50001P013C01-SCONNA
GND                      J29              237      SCONN288_ADR50001P013C01-SCONNA
GND                      J29              240      SCONN288_ADR50001P013C01-SCONNA
GND                      J29              242      SCONN288_ADR50001P013C01-SCONNA
GND                      J29              244      SCONN288_ADR50001P013C01-SCONNA
GND                      J29              246      SCONN288_ADR50001P013C01-SCONNA
GND                      J29              248      SCONN288_ADR50001P013C01-SCONNA
GND                      J29              251      SCONN288_ADR50001P013C01-SCONNA
GND                      J29              253      SCONN288_ADR50001P013C01-SCONNA
GND                      J29              255      SCONN288_ADR50001P013C01-SCONNA
GND                      J29              257      SCONN288_ADR50001P013C01-SCONNA
GND                      J29              259      SCONN288_ADR50001P013C01-SCONNA
GND                      J29              262      SCONN288_ADR50001P013C01-SCONNA
GND                      J29              264      SCONN288_ADR50001P013C01-SCONNA
GND                      J29              266      SCONN288_ADR50001P013C01-SCONNA
GND                      J29              268      SCONN288_ADR50001P013C01-SCONNA
GND                      J29              270      SCONN288_ADR50001P013C01-SCONNA
GND                      J29              273      SCONN288_ADR50001P013C01-SCONNA
GND                      J29              275      SCONN288_ADR50001P013C01-SCONNA
GND                      J29              277      SCONN288_ADR50001P013C01-SCONNA
GND                      J29              279      SCONN288_ADR50001P013C01-SCONNA
GND                      J29              281      SCONN288_ADR50001P013C01-SCONNA
GND                      J29              284      SCONN288_ADR50001P013C01-SCONNA
GND                      J29              286      SCONN288_ADR50001P013C01-SCONNA
GND                      J29              288      SCONN288_ADR50001P013C01-SCONNA
GND                      J29              G1       SCONN288_ADR50001P013C01-SCONNA
GND                      J29              G2       SCONN288_ADR50001P013C01-SCONNA
GND                      J29              G3       SCONN288_ADR50001P013C01-SCONNA
GND                      J30              6        SCONN288_ADR50001P003C01-SCONNA
GND                      J30              8        SCONN288_ADR50001P003C01-SCONNA
GND                      J30              10       SCONN288_ADR50001P003C01-SCONNA
GND                      J30              13       SCONN288_ADR50001P003C01-SCONNA
GND                      J30              15       SCONN288_ADR50001P003C01-SCONNA
GND                      J30              17       SCONN288_ADR50001P003C01-SCONNA
GND                      J30              19       SCONN288_ADR50001P003C01-SCONNA
GND                      J30              21       SCONN288_ADR50001P003C01-SCONNA
GND                      J30              24       SCONN288_ADR50001P003C01-SCONNA
GND                      J30              26       SCONN288_ADR50001P003C01-SCONNA
GND                      J30              28       SCONN288_ADR50001P003C01-SCONNA
GND                      J30              30       SCONN288_ADR50001P003C01-SCONNA
GND                      J30              32       SCONN288_ADR50001P003C01-SCONNA
GND                      J30              35       SCONN288_ADR50001P003C01-SCONNA
GND                      J30              37       SCONN288_ADR50001P003C01-SCONNA
GND                      J30              39       SCONN288_ADR50001P003C01-SCONNA
GND                      J30              41       SCONN288_ADR50001P003C01-SCONNA
GND                      J30              43       SCONN288_ADR50001P003C01-SCONNA
GND                      J30              46       SCONN288_ADR50001P003C01-SCONNA
GND                      J30              48       SCONN288_ADR50001P003C01-SCONNA
GND                      J30              50       SCONN288_ADR50001P003C01-SCONNA
GND                      J30              52       SCONN288_ADR50001P003C01-SCONNA
GND                      J30              54       SCONN288_ADR50001P003C01-SCONNA
GND                      J30              57       SCONN288_ADR50001P003C01-SCONNA
GND                      J30              59       SCONN288_ADR50001P003C01-SCONNA
GND                      J30              61       SCONN288_ADR50001P003C01-SCONNA
GND                      J30              63       SCONN288_ADR50001P003C01-SCONNA
GND                      J30              65       SCONN288_ADR50001P003C01-SCONNA
GND                      J30              67       SCONN288_ADR50001P003C01-SCONNA
GND                      J30              69       SCONN288_ADR50001P003C01-SCONNA
GND                      J30              71       SCONN288_ADR50001P003C01-SCONNA
GND                      J30              73       SCONN288_ADR50001P003C01-SCONNA
GND                      J30              75       SCONN288_ADR50001P003C01-SCONNA
GND                      J30              77       SCONN288_ADR50001P003C01-SCONNA
GND                      J30              79       SCONN288_ADR50001P003C01-SCONNA
GND                      J30              81       SCONN288_ADR50001P003C01-SCONNA
GND                      J30              83       SCONN288_ADR50001P003C01-SCONNA
GND                      J30              85       SCONN288_ADR50001P003C01-SCONNA
GND                      J30              88       SCONN288_ADR50001P003C01-SCONNA
GND                      J30              90       SCONN288_ADR50001P003C01-SCONNA
GND                      J30              92       SCONN288_ADR50001P003C01-SCONNA
GND                      J30              95       SCONN288_ADR50001P003C01-SCONNA
GND                      J30              97       SCONN288_ADR50001P003C01-SCONNA
GND                      J30              99       SCONN288_ADR50001P003C01-SCONNA
GND                      J30              101      SCONN288_ADR50001P003C01-SCONNA
GND                      J30              103      SCONN288_ADR50001P003C01-SCONNA
GND                      J30              106      SCONN288_ADR50001P003C01-SCONNA
GND                      J30              108      SCONN288_ADR50001P003C01-SCONNA
GND                      J30              110      SCONN288_ADR50001P003C01-SCONNA
GND                      J30              112      SCONN288_ADR50001P003C01-SCONNA
GND                      J30              114      SCONN288_ADR50001P003C01-SCONNA
GND                      J30              117      SCONN288_ADR50001P003C01-SCONNA
GND                      J30              119      SCONN288_ADR50001P003C01-SCONNA
GND                      J30              121      SCONN288_ADR50001P003C01-SCONNA
GND                      J30              123      SCONN288_ADR50001P003C01-SCONNA
GND                      J30              125      SCONN288_ADR50001P003C01-SCONNA
GND                      J30              128      SCONN288_ADR50001P003C01-SCONNA
GND                      J30              130      SCONN288_ADR50001P003C01-SCONNA
GND                      J30              132      SCONN288_ADR50001P003C01-SCONNA
GND                      J30              134      SCONN288_ADR50001P003C01-SCONNA
GND                      J30              136      SCONN288_ADR50001P003C01-SCONNA
GND                      J30              139      SCONN288_ADR50001P003C01-SCONNA
GND                      J30              141      SCONN288_ADR50001P003C01-SCONNA
GND                      J30              143      SCONN288_ADR50001P003C01-SCONNA
GND                      J30              151      SCONN288_ADR50001P003C01-SCONNA
GND                      J30              153      SCONN288_ADR50001P003C01-SCONNA
GND                      J30              155      SCONN288_ADR50001P003C01-SCONNA
GND                      J30              158      SCONN288_ADR50001P003C01-SCONNA
GND                      J30              160      SCONN288_ADR50001P003C01-SCONNA
GND                      J30              162      SCONN288_ADR50001P003C01-SCONNA
GND                      J30              164      SCONN288_ADR50001P003C01-SCONNA
GND                      J30              166      SCONN288_ADR50001P003C01-SCONNA
GND                      J30              169      SCONN288_ADR50001P003C01-SCONNA
GND                      J30              171      SCONN288_ADR50001P003C01-SCONNA
GND                      J30              173      SCONN288_ADR50001P003C01-SCONNA
GND                      J30              175      SCONN288_ADR50001P003C01-SCONNA
GND                      J30              177      SCONN288_ADR50001P003C01-SCONNA
GND                      J30              180      SCONN288_ADR50001P003C01-SCONNA
GND                      J30              182      SCONN288_ADR50001P003C01-SCONNA
GND                      J30              184      SCONN288_ADR50001P003C01-SCONNA
GND                      J30              186      SCONN288_ADR50001P003C01-SCONNA
GND                      J30              188      SCONN288_ADR50001P003C01-SCONNA
GND                      J30              191      SCONN288_ADR50001P003C01-SCONNA
GND                      J30              193      SCONN288_ADR50001P003C01-SCONNA
GND                      J30              195      SCONN288_ADR50001P003C01-SCONNA
GND                      J30              197      SCONN288_ADR50001P003C01-SCONNA
GND                      J30              199      SCONN288_ADR50001P003C01-SCONNA
GND                      J30              202      SCONN288_ADR50001P003C01-SCONNA
GND                      J30              204      SCONN288_ADR50001P003C01-SCONNA
GND                      J30              206      SCONN288_ADR50001P003C01-SCONNA
GND                      J30              208      SCONN288_ADR50001P003C01-SCONNA
GND                      J30              210      SCONN288_ADR50001P003C01-SCONNA
GND                      J30              212      SCONN288_ADR50001P003C01-SCONNA
GND                      J30              214      SCONN288_ADR50001P003C01-SCONNA
GND                      J30              216      SCONN288_ADR50001P003C01-SCONNA
GND                      J30              219      SCONN288_ADR50001P003C01-SCONNA
GND                      J30              222      SCONN288_ADR50001P003C01-SCONNA
GND                      J30              224      SCONN288_ADR50001P003C01-SCONNA
GND                      J30              226      SCONN288_ADR50001P003C01-SCONNA
GND                      J30              228      SCONN288_ADR50001P003C01-SCONNA
GND                      J30              230      SCONN288_ADR50001P003C01-SCONNA
GND                      J30              233      SCONN288_ADR50001P003C01-SCONNA
GND                      J30              235      SCONN288_ADR50001P003C01-SCONNA
GND                      J30              237      SCONN288_ADR50001P003C01-SCONNA
GND                      J30              240      SCONN288_ADR50001P003C01-SCONNA
GND                      J30              242      SCONN288_ADR50001P003C01-SCONNA
GND                      J30              244      SCONN288_ADR50001P003C01-SCONNA
GND                      J30              246      SCONN288_ADR50001P003C01-SCONNA
GND                      J30              248      SCONN288_ADR50001P003C01-SCONNA
GND                      J30              251      SCONN288_ADR50001P003C01-SCONNA
GND                      J30              253      SCONN288_ADR50001P003C01-SCONNA
GND                      J30              255      SCONN288_ADR50001P003C01-SCONNA
GND                      J30              257      SCONN288_ADR50001P003C01-SCONNA
GND                      J30              259      SCONN288_ADR50001P003C01-SCONNA
GND                      J30              262      SCONN288_ADR50001P003C01-SCONNA
GND                      J30              264      SCONN288_ADR50001P003C01-SCONNA
GND                      J30              266      SCONN288_ADR50001P003C01-SCONNA
GND                      J30              268      SCONN288_ADR50001P003C01-SCONNA
GND                      J30              270      SCONN288_ADR50001P003C01-SCONNA
GND                      J30              273      SCONN288_ADR50001P003C01-SCONNA
GND                      J30              275      SCONN288_ADR50001P003C01-SCONNA
GND                      J30              277      SCONN288_ADR50001P003C01-SCONNA
GND                      J30              279      SCONN288_ADR50001P003C01-SCONNA
GND                      J30              281      SCONN288_ADR50001P003C01-SCONNA
GND                      J30              284      SCONN288_ADR50001P003C01-SCONNA
GND                      J30              286      SCONN288_ADR50001P003C01-SCONNA
GND                      J30              288      SCONN288_ADR50001P003C01-SCONNA
GND                      J30              G1       SCONN288_ADR50001P003C01-SCONNA
GND                      J30              G2       SCONN288_ADR50001P003C01-SCONNA
GND                      J30              G3       SCONN288_ADR50001P003C01-SCONNA
GND                      J31              6        SCONN288_ADR50001P013C01-SCONNA
GND                      J31              8        SCONN288_ADR50001P013C01-SCONNA
GND                      J31              10       SCONN288_ADR50001P013C01-SCONNA
GND                      J31              13       SCONN288_ADR50001P013C01-SCONNA
GND                      J31              15       SCONN288_ADR50001P013C01-SCONNA
GND                      J31              17       SCONN288_ADR50001P013C01-SCONNA
GND                      J31              19       SCONN288_ADR50001P013C01-SCONNA
GND                      J31              21       SCONN288_ADR50001P013C01-SCONNA
GND                      J31              24       SCONN288_ADR50001P013C01-SCONNA
GND                      J31              26       SCONN288_ADR50001P013C01-SCONNA
GND                      J31              28       SCONN288_ADR50001P013C01-SCONNA
GND                      J31              30       SCONN288_ADR50001P013C01-SCONNA
GND                      J31              32       SCONN288_ADR50001P013C01-SCONNA
GND                      J31              35       SCONN288_ADR50001P013C01-SCONNA
GND                      J31              37       SCONN288_ADR50001P013C01-SCONNA
GND                      J31              39       SCONN288_ADR50001P013C01-SCONNA
GND                      J31              41       SCONN288_ADR50001P013C01-SCONNA
GND                      J31              43       SCONN288_ADR50001P013C01-SCONNA
GND                      J31              46       SCONN288_ADR50001P013C01-SCONNA
GND                      J31              48       SCONN288_ADR50001P013C01-SCONNA
GND                      J31              50       SCONN288_ADR50001P013C01-SCONNA
GND                      J31              52       SCONN288_ADR50001P013C01-SCONNA
GND                      J31              54       SCONN288_ADR50001P013C01-SCONNA
GND                      J31              57       SCONN288_ADR50001P013C01-SCONNA
GND                      J31              59       SCONN288_ADR50001P013C01-SCONNA
GND                      J31              61       SCONN288_ADR50001P013C01-SCONNA
GND                      J31              63       SCONN288_ADR50001P013C01-SCONNA
GND                      J31              65       SCONN288_ADR50001P013C01-SCONNA
GND                      J31              67       SCONN288_ADR50001P013C01-SCONNA
GND                      J31              69       SCONN288_ADR50001P013C01-SCONNA
GND                      J31              71       SCONN288_ADR50001P013C01-SCONNA
GND                      J31              73       SCONN288_ADR50001P013C01-SCONNA
GND                      J31              75       SCONN288_ADR50001P013C01-SCONNA
GND                      J31              77       SCONN288_ADR50001P013C01-SCONNA
GND                      J31              79       SCONN288_ADR50001P013C01-SCONNA
GND                      J31              81       SCONN288_ADR50001P013C01-SCONNA
GND                      J31              83       SCONN288_ADR50001P013C01-SCONNA
GND                      J31              85       SCONN288_ADR50001P013C01-SCONNA
GND                      J31              88       SCONN288_ADR50001P013C01-SCONNA
GND                      J31              90       SCONN288_ADR50001P013C01-SCONNA
GND                      J31              92       SCONN288_ADR50001P013C01-SCONNA
GND                      J31              95       SCONN288_ADR50001P013C01-SCONNA
GND                      J31              97       SCONN288_ADR50001P013C01-SCONNA
GND                      J31              99       SCONN288_ADR50001P013C01-SCONNA
GND                      J31              101      SCONN288_ADR50001P013C01-SCONNA
GND                      J31              103      SCONN288_ADR50001P013C01-SCONNA
GND                      J31              106      SCONN288_ADR50001P013C01-SCONNA
GND                      J31              108      SCONN288_ADR50001P013C01-SCONNA
GND                      J31              110      SCONN288_ADR50001P013C01-SCONNA
GND                      J31              112      SCONN288_ADR50001P013C01-SCONNA
GND                      J31              114      SCONN288_ADR50001P013C01-SCONNA
GND                      J31              117      SCONN288_ADR50001P013C01-SCONNA
GND                      J31              119      SCONN288_ADR50001P013C01-SCONNA
GND                      J31              121      SCONN288_ADR50001P013C01-SCONNA
GND                      J31              123      SCONN288_ADR50001P013C01-SCONNA
GND                      J31              125      SCONN288_ADR50001P013C01-SCONNA
GND                      J31              128      SCONN288_ADR50001P013C01-SCONNA
GND                      J31              130      SCONN288_ADR50001P013C01-SCONNA
GND                      J31              132      SCONN288_ADR50001P013C01-SCONNA
GND                      J31              134      SCONN288_ADR50001P013C01-SCONNA
GND                      J31              136      SCONN288_ADR50001P013C01-SCONNA
GND                      J31              139      SCONN288_ADR50001P013C01-SCONNA
GND                      J31              141      SCONN288_ADR50001P013C01-SCONNA
GND                      J31              143      SCONN288_ADR50001P013C01-SCONNA
GND                      J31              151      SCONN288_ADR50001P013C01-SCONNA
GND                      J31              153      SCONN288_ADR50001P013C01-SCONNA
GND                      J31              155      SCONN288_ADR50001P013C01-SCONNA
GND                      J31              158      SCONN288_ADR50001P013C01-SCONNA
GND                      J31              160      SCONN288_ADR50001P013C01-SCONNA
GND                      J31              162      SCONN288_ADR50001P013C01-SCONNA
GND                      J31              164      SCONN288_ADR50001P013C01-SCONNA
GND                      J31              166      SCONN288_ADR50001P013C01-SCONNA
GND                      J31              169      SCONN288_ADR50001P013C01-SCONNA
GND                      J31              171      SCONN288_ADR50001P013C01-SCONNA
GND                      J31              173      SCONN288_ADR50001P013C01-SCONNA
GND                      J31              175      SCONN288_ADR50001P013C01-SCONNA
GND                      J31              177      SCONN288_ADR50001P013C01-SCONNA
GND                      J31              180      SCONN288_ADR50001P013C01-SCONNA
GND                      J31              182      SCONN288_ADR50001P013C01-SCONNA
GND                      J31              184      SCONN288_ADR50001P013C01-SCONNA
GND                      J31              186      SCONN288_ADR50001P013C01-SCONNA
GND                      J31              188      SCONN288_ADR50001P013C01-SCONNA
GND                      J31              191      SCONN288_ADR50001P013C01-SCONNA
GND                      J31              193      SCONN288_ADR50001P013C01-SCONNA
GND                      J31              195      SCONN288_ADR50001P013C01-SCONNA
GND                      J31              197      SCONN288_ADR50001P013C01-SCONNA
GND                      J31              199      SCONN288_ADR50001P013C01-SCONNA
GND                      J31              202      SCONN288_ADR50001P013C01-SCONNA
GND                      J31              204      SCONN288_ADR50001P013C01-SCONNA
GND                      J31              206      SCONN288_ADR50001P013C01-SCONNA
GND                      J31              208      SCONN288_ADR50001P013C01-SCONNA
GND                      J31              210      SCONN288_ADR50001P013C01-SCONNA
GND                      J31              212      SCONN288_ADR50001P013C01-SCONNA
GND                      J31              214      SCONN288_ADR50001P013C01-SCONNA
GND                      J31              216      SCONN288_ADR50001P013C01-SCONNA
GND                      J31              219      SCONN288_ADR50001P013C01-SCONNA
GND                      J31              222      SCONN288_ADR50001P013C01-SCONNA
GND                      J31              224      SCONN288_ADR50001P013C01-SCONNA
GND                      J31              226      SCONN288_ADR50001P013C01-SCONNA
GND                      J31              228      SCONN288_ADR50001P013C01-SCONNA
GND                      J31              230      SCONN288_ADR50001P013C01-SCONNA
GND                      J31              233      SCONN288_ADR50001P013C01-SCONNA
GND                      J31              235      SCONN288_ADR50001P013C01-SCONNA
GND                      J31              237      SCONN288_ADR50001P013C01-SCONNA
GND                      J31              240      SCONN288_ADR50001P013C01-SCONNA
GND                      J31              242      SCONN288_ADR50001P013C01-SCONNA
GND                      J31              244      SCONN288_ADR50001P013C01-SCONNA
GND                      J31              246      SCONN288_ADR50001P013C01-SCONNA
GND                      J31              248      SCONN288_ADR50001P013C01-SCONNA
GND                      J31              251      SCONN288_ADR50001P013C01-SCONNA
GND                      J31              253      SCONN288_ADR50001P013C01-SCONNA
GND                      J31              255      SCONN288_ADR50001P013C01-SCONNA
GND                      J31              257      SCONN288_ADR50001P013C01-SCONNA
GND                      J31              259      SCONN288_ADR50001P013C01-SCONNA
GND                      J31              262      SCONN288_ADR50001P013C01-SCONNA
GND                      J31              264      SCONN288_ADR50001P013C01-SCONNA
GND                      J31              266      SCONN288_ADR50001P013C01-SCONNA
GND                      J31              268      SCONN288_ADR50001P013C01-SCONNA
GND                      J31              270      SCONN288_ADR50001P013C01-SCONNA
GND                      J31              273      SCONN288_ADR50001P013C01-SCONNA
GND                      J31              275      SCONN288_ADR50001P013C01-SCONNA
GND                      J31              277      SCONN288_ADR50001P013C01-SCONNA
GND                      J31              279      SCONN288_ADR50001P013C01-SCONNA
GND                      J31              281      SCONN288_ADR50001P013C01-SCONNA
GND                      J31              284      SCONN288_ADR50001P013C01-SCONNA
GND                      J31              286      SCONN288_ADR50001P013C01-SCONNA
GND                      J31              288      SCONN288_ADR50001P013C01-SCONNA
GND                      J31              G1       SCONN288_ADR50001P013C01-SCONNA
GND                      J31              G2       SCONN288_ADR50001P013C01-SCONNA
GND                      J31              G3       SCONN288_ADR50001P013C01-SCONNA
GND                      J32              6        SCONN288_ADR50001P003C01-SCONNA
GND                      J32              8        SCONN288_ADR50001P003C01-SCONNA
GND                      J32              10       SCONN288_ADR50001P003C01-SCONNA
GND                      J32              13       SCONN288_ADR50001P003C01-SCONNA
GND                      J32              15       SCONN288_ADR50001P003C01-SCONNA
GND                      J32              17       SCONN288_ADR50001P003C01-SCONNA
GND                      J32              19       SCONN288_ADR50001P003C01-SCONNA
GND                      J32              21       SCONN288_ADR50001P003C01-SCONNA
GND                      J32              24       SCONN288_ADR50001P003C01-SCONNA
GND                      J32              26       SCONN288_ADR50001P003C01-SCONNA
GND                      J32              28       SCONN288_ADR50001P003C01-SCONNA
GND                      J32              30       SCONN288_ADR50001P003C01-SCONNA
GND                      J32              32       SCONN288_ADR50001P003C01-SCONNA
GND                      J32              35       SCONN288_ADR50001P003C01-SCONNA
GND                      J32              37       SCONN288_ADR50001P003C01-SCONNA
GND                      J32              39       SCONN288_ADR50001P003C01-SCONNA
GND                      J32              41       SCONN288_ADR50001P003C01-SCONNA
GND                      J32              43       SCONN288_ADR50001P003C01-SCONNA
GND                      J32              46       SCONN288_ADR50001P003C01-SCONNA
GND                      J32              48       SCONN288_ADR50001P003C01-SCONNA
GND                      J32              50       SCONN288_ADR50001P003C01-SCONNA
GND                      J32              52       SCONN288_ADR50001P003C01-SCONNA
GND                      J32              54       SCONN288_ADR50001P003C01-SCONNA
GND                      J32              57       SCONN288_ADR50001P003C01-SCONNA
GND                      J32              59       SCONN288_ADR50001P003C01-SCONNA
GND                      J32              61       SCONN288_ADR50001P003C01-SCONNA
GND                      J32              63       SCONN288_ADR50001P003C01-SCONNA
GND                      J32              65       SCONN288_ADR50001P003C01-SCONNA
GND                      J32              67       SCONN288_ADR50001P003C01-SCONNA
GND                      J32              69       SCONN288_ADR50001P003C01-SCONNA
GND                      J32              71       SCONN288_ADR50001P003C01-SCONNA
GND                      J32              73       SCONN288_ADR50001P003C01-SCONNA
GND                      J32              75       SCONN288_ADR50001P003C01-SCONNA
GND                      J32              77       SCONN288_ADR50001P003C01-SCONNA
GND                      J32              79       SCONN288_ADR50001P003C01-SCONNA
GND                      J32              81       SCONN288_ADR50001P003C01-SCONNA
GND                      J32              83       SCONN288_ADR50001P003C01-SCONNA
GND                      J32              85       SCONN288_ADR50001P003C01-SCONNA
GND                      J32              88       SCONN288_ADR50001P003C01-SCONNA
GND                      J32              90       SCONN288_ADR50001P003C01-SCONNA
GND                      J32              92       SCONN288_ADR50001P003C01-SCONNA
GND                      J32              95       SCONN288_ADR50001P003C01-SCONNA
GND                      J32              97       SCONN288_ADR50001P003C01-SCONNA
GND                      J32              99       SCONN288_ADR50001P003C01-SCONNA
GND                      J32              101      SCONN288_ADR50001P003C01-SCONNA
GND                      J32              103      SCONN288_ADR50001P003C01-SCONNA
GND                      J32              106      SCONN288_ADR50001P003C01-SCONNA
GND                      J32              108      SCONN288_ADR50001P003C01-SCONNA
GND                      J32              110      SCONN288_ADR50001P003C01-SCONNA
GND                      J32              112      SCONN288_ADR50001P003C01-SCONNA
GND                      J32              114      SCONN288_ADR50001P003C01-SCONNA
GND                      J32              117      SCONN288_ADR50001P003C01-SCONNA
GND                      J32              119      SCONN288_ADR50001P003C01-SCONNA
GND                      J32              121      SCONN288_ADR50001P003C01-SCONNA
GND                      J32              123      SCONN288_ADR50001P003C01-SCONNA
GND                      J32              125      SCONN288_ADR50001P003C01-SCONNA
GND                      J32              128      SCONN288_ADR50001P003C01-SCONNA
GND                      J32              130      SCONN288_ADR50001P003C01-SCONNA
GND                      J32              132      SCONN288_ADR50001P003C01-SCONNA
GND                      J32              134      SCONN288_ADR50001P003C01-SCONNA
GND                      J32              136      SCONN288_ADR50001P003C01-SCONNA
GND                      J32              139      SCONN288_ADR50001P003C01-SCONNA
GND                      J32              141      SCONN288_ADR50001P003C01-SCONNA
GND                      J32              143      SCONN288_ADR50001P003C01-SCONNA
GND                      J32              151      SCONN288_ADR50001P003C01-SCONNA
GND                      J32              153      SCONN288_ADR50001P003C01-SCONNA
GND                      J32              155      SCONN288_ADR50001P003C01-SCONNA
GND                      J32              158      SCONN288_ADR50001P003C01-SCONNA
GND                      J32              160      SCONN288_ADR50001P003C01-SCONNA
GND                      J32              162      SCONN288_ADR50001P003C01-SCONNA
GND                      J32              164      SCONN288_ADR50001P003C01-SCONNA
GND                      J32              166      SCONN288_ADR50001P003C01-SCONNA
GND                      J32              169      SCONN288_ADR50001P003C01-SCONNA
GND                      J32              171      SCONN288_ADR50001P003C01-SCONNA
GND                      J32              173      SCONN288_ADR50001P003C01-SCONNA
GND                      J32              175      SCONN288_ADR50001P003C01-SCONNA
GND                      J32              177      SCONN288_ADR50001P003C01-SCONNA
GND                      J32              180      SCONN288_ADR50001P003C01-SCONNA
GND                      J32              182      SCONN288_ADR50001P003C01-SCONNA
GND                      J32              184      SCONN288_ADR50001P003C01-SCONNA
GND                      J32              186      SCONN288_ADR50001P003C01-SCONNA
GND                      J32              188      SCONN288_ADR50001P003C01-SCONNA
GND                      J32              191      SCONN288_ADR50001P003C01-SCONNA
GND                      J32              193      SCONN288_ADR50001P003C01-SCONNA
GND                      J32              195      SCONN288_ADR50001P003C01-SCONNA
GND                      J32              197      SCONN288_ADR50001P003C01-SCONNA
GND                      J32              199      SCONN288_ADR50001P003C01-SCONNA
GND                      J32              202      SCONN288_ADR50001P003C01-SCONNA
GND                      J32              204      SCONN288_ADR50001P003C01-SCONNA
GND                      J32              206      SCONN288_ADR50001P003C01-SCONNA
GND                      J32              208      SCONN288_ADR50001P003C01-SCONNA
GND                      J32              210      SCONN288_ADR50001P003C01-SCONNA
GND                      J32              212      SCONN288_ADR50001P003C01-SCONNA
GND                      J32              214      SCONN288_ADR50001P003C01-SCONNA
GND                      J32              216      SCONN288_ADR50001P003C01-SCONNA
GND                      J32              219      SCONN288_ADR50001P003C01-SCONNA
GND                      J32              222      SCONN288_ADR50001P003C01-SCONNA
GND                      J32              224      SCONN288_ADR50001P003C01-SCONNA
GND                      J32              226      SCONN288_ADR50001P003C01-SCONNA
GND                      J32              228      SCONN288_ADR50001P003C01-SCONNA
GND                      J32              230      SCONN288_ADR50001P003C01-SCONNA
GND                      J32              233      SCONN288_ADR50001P003C01-SCONNA
GND                      J32              235      SCONN288_ADR50001P003C01-SCONNA
GND                      J32              237      SCONN288_ADR50001P003C01-SCONNA
GND                      J32              240      SCONN288_ADR50001P003C01-SCONNA
GND                      J32              242      SCONN288_ADR50001P003C01-SCONNA
GND                      J32              244      SCONN288_ADR50001P003C01-SCONNA
GND                      J32              246      SCONN288_ADR50001P003C01-SCONNA
GND                      J32              248      SCONN288_ADR50001P003C01-SCONNA
GND                      J32              251      SCONN288_ADR50001P003C01-SCONNA
GND                      J32              253      SCONN288_ADR50001P003C01-SCONNA
GND                      J32              255      SCONN288_ADR50001P003C01-SCONNA
GND                      J32              257      SCONN288_ADR50001P003C01-SCONNA
GND                      J32              259      SCONN288_ADR50001P003C01-SCONNA
GND                      J32              262      SCONN288_ADR50001P003C01-SCONNA
GND                      J32              264      SCONN288_ADR50001P003C01-SCONNA
GND                      J32              266      SCONN288_ADR50001P003C01-SCONNA
GND                      J32              268      SCONN288_ADR50001P003C01-SCONNA
GND                      J32              270      SCONN288_ADR50001P003C01-SCONNA
GND                      J32              273      SCONN288_ADR50001P003C01-SCONNA
GND                      J32              275      SCONN288_ADR50001P003C01-SCONNA
GND                      J32              277      SCONN288_ADR50001P003C01-SCONNA
GND                      J32              279      SCONN288_ADR50001P003C01-SCONNA
GND                      J32              281      SCONN288_ADR50001P003C01-SCONNA
GND                      J32              284      SCONN288_ADR50001P003C01-SCONNA
GND                      J32              286      SCONN288_ADR50001P003C01-SCONNA
GND                      J32              288      SCONN288_ADR50001P003C01-SCONNA
GND                      J32              G1       SCONN288_ADR50001P003C01-SCONNA
GND                      J32              G2       SCONN288_ADR50001P003C01-SCONNA
GND                      J32              G3       SCONN288_ADR50001P003C01-SCONNA
GND                      J33              A1       SCONN84_123318136-SCONN84_1-23A
GND                      J33              A2       SCONN84_123318136-SCONN84_1-23A
GND                      J33              A3       SCONN84_123318136-SCONN84_1-23A
GND                      J33              A4       SCONN84_123318136-SCONN84_1-23A
GND                      J33              A5       SCONN84_123318136-SCONN84_1-23A
GND                      J33              A6       SCONN84_123318136-SCONN84_1-23A
GND                      J33              A13      SCONN84_123318136-SCONN84_1-23A
GND                      J33              A16      SCONN84_123318136-SCONN84_1-23A
GND                      J33              A19      SCONN84_123318136-SCONN84_1-23A
GND                      J33              A22      SCONN84_123318136-SCONN84_1-23A
GND                      J33              A25      SCONN84_123318136-SCONN84_1-23A
GND                      J33              A28      SCONN84_123318136-SCONN84_1-23A
GND                      J33              A29      SCONN84_123318136-SCONN84_1-23A
GND                      J33              A32      SCONN84_123318136-SCONN84_1-23A
GND                      J33              A35      SCONN84_123318136-SCONN84_1-23A
GND                      J33              A38      SCONN84_123318136-SCONN84_1-23A
GND                      J33              A41      SCONN84_123318136-SCONN84_1-23A
GND                      J33              B13      SCONN84_123318136-SCONN84_1-23A
GND                      J33              B16      SCONN84_123318136-SCONN84_1-23A
GND                      J33              B19      SCONN84_123318136-SCONN84_1-23A
GND                      J33              B22      SCONN84_123318136-SCONN84_1-23A
GND                      J33              B25      SCONN84_123318136-SCONN84_1-23A
GND                      J33              B28      SCONN84_123318136-SCONN84_1-23A
GND                      J33              B29      SCONN84_123318136-SCONN84_1-23A
GND                      J33              B32      SCONN84_123318136-SCONN84_1-23A
GND                      J33              B35      SCONN84_123318136-SCONN84_1-23A
GND                      J33              B38      SCONN84_123318136-SCONN84_1-23A
GND                      J33              B41      SCONN84_123318136-SCONN84_1-23A
GND                      J33              G1       SCONN84_123318136-SCONN84_1-23A
GND                      J33              G2       SCONN84_123318136-SCONN84_1-23A
GND                      J33              G3       SCONN84_123318136-SCONN84_1-23A
GND                      J33              G4       SCONN84_123318136-SCONN84_1-23A
GND                      J33              G5       SCONN84_123318136-SCONN84_1-23A
GND                      J34              A1       SCONN84_123318136-SCONN84_1-23A
GND                      J34              A2       SCONN84_123318136-SCONN84_1-23A
GND                      J34              A3       SCONN84_123318136-SCONN84_1-23A
GND                      J34              A4       SCONN84_123318136-SCONN84_1-23A
GND                      J34              A5       SCONN84_123318136-SCONN84_1-23A
GND                      J34              A6       SCONN84_123318136-SCONN84_1-23A
GND                      J34              A13      SCONN84_123318136-SCONN84_1-23A
GND                      J34              A16      SCONN84_123318136-SCONN84_1-23A
GND                      J34              A19      SCONN84_123318136-SCONN84_1-23A
GND                      J34              A22      SCONN84_123318136-SCONN84_1-23A
GND                      J34              A25      SCONN84_123318136-SCONN84_1-23A
GND                      J34              A28      SCONN84_123318136-SCONN84_1-23A
GND                      J34              A29      SCONN84_123318136-SCONN84_1-23A
GND                      J34              A32      SCONN84_123318136-SCONN84_1-23A
GND                      J34              A35      SCONN84_123318136-SCONN84_1-23A
GND                      J34              A38      SCONN84_123318136-SCONN84_1-23A
GND                      J34              A41      SCONN84_123318136-SCONN84_1-23A
GND                      J34              B13      SCONN84_123318136-SCONN84_1-23A
GND                      J34              B16      SCONN84_123318136-SCONN84_1-23A
GND                      J34              B19      SCONN84_123318136-SCONN84_1-23A
GND                      J34              B22      SCONN84_123318136-SCONN84_1-23A
GND                      J34              B25      SCONN84_123318136-SCONN84_1-23A
GND                      J34              B28      SCONN84_123318136-SCONN84_1-23A
GND                      J34              B29      SCONN84_123318136-SCONN84_1-23A
GND                      J34              B32      SCONN84_123318136-SCONN84_1-23A
GND                      J34              B35      SCONN84_123318136-SCONN84_1-23A
GND                      J34              B38      SCONN84_123318136-SCONN84_1-23A
GND                      J34              B41      SCONN84_123318136-SCONN84_1-23A
GND                      J34              G1       SCONN84_123318136-SCONN84_1-23A
GND                      J34              G2       SCONN84_123318136-SCONN84_1-23A
GND                      J34              G3       SCONN84_123318136-SCONN84_1-23A
GND                      J34              G4       SCONN84_123318136-SCONN84_1-23A
GND                      J34              G5       SCONN84_123318136-SCONN84_1-23A
GND                      J35              A2       SCONN140_G64V3431BHR-SCONN140_B
GND                      J35              A5       SCONN140_G64V3431BHR-SCONN140_B
GND                      J35              A6       SCONN140_G64V3431BHR-SCONN140_B
GND                      J35              A7       SCONN140_G64V3431BHR-SCONN140_B
GND                      J35              A8       SCONN140_G64V3431BHR-SCONN140_B
GND                      J35              A10      SCONN140_G64V3431BHR-SCONN140_B
GND                      J35              A13      SCONN140_G64V3431BHR-SCONN140_B
GND                      J35              A16      SCONN140_G64V3431BHR-SCONN140_B
GND                      J35              A19      SCONN140_G64V3431BHR-SCONN140_B
GND                      J35              A22      SCONN140_G64V3431BHR-SCONN140_B
GND                      J35              A25      SCONN140_G64V3431BHR-SCONN140_B
GND                      J35              A28      SCONN140_G64V3431BHR-SCONN140_B
GND                      J35              A29      SCONN140_G64V3431BHR-SCONN140_B
GND                      J35              A32      SCONN140_G64V3431BHR-SCONN140_B
GND                      J35              A35      SCONN140_G64V3431BHR-SCONN140_B
GND                      J35              A38      SCONN140_G64V3431BHR-SCONN140_B
GND                      J35              A41      SCONN140_G64V3431BHR-SCONN140_B
GND                      J35              A43      SCONN140_G64V3431BHR-SCONN140_B
GND                      J35              A46      SCONN140_G64V3431BHR-SCONN140_B
GND                      J35              A49      SCONN140_G64V3431BHR-SCONN140_B
GND                      J35              A52      SCONN140_G64V3431BHR-SCONN140_B
GND                      J35              A55      SCONN140_G64V3431BHR-SCONN140_B
GND                      J35              A58      SCONN140_G64V3431BHR-SCONN140_B
GND                      J35              A61      SCONN140_G64V3431BHR-SCONN140_B
GND                      J35              A64      SCONN140_G64V3431BHR-SCONN140_B
GND                      J35              A67      SCONN140_G64V3431BHR-SCONN140_B
GND                      J35              A70      SCONN140_G64V3431BHR-SCONN140_B
GND                      J35              B6       SCONN140_G64V3431BHR-SCONN140_B
GND                      J35              B7       SCONN140_G64V3431BHR-SCONN140_B
GND                      J35              B13      SCONN140_G64V3431BHR-SCONN140_B
GND                      J35              B16      SCONN140_G64V3431BHR-SCONN140_B
GND                      J35              B19      SCONN140_G64V3431BHR-SCONN140_B
GND                      J35              B22      SCONN140_G64V3431BHR-SCONN140_B
GND                      J35              B25      SCONN140_G64V3431BHR-SCONN140_B
GND                      J35              B28      SCONN140_G64V3431BHR-SCONN140_B
GND                      J35              B29      SCONN140_G64V3431BHR-SCONN140_B
GND                      J35              B32      SCONN140_G64V3431BHR-SCONN140_B
GND                      J35              B35      SCONN140_G64V3431BHR-SCONN140_B
GND                      J35              B38      SCONN140_G64V3431BHR-SCONN140_B
GND                      J35              B41      SCONN140_G64V3431BHR-SCONN140_B
GND                      J35              B43      SCONN140_G64V3431BHR-SCONN140_B
GND                      J35              B46      SCONN140_G64V3431BHR-SCONN140_B
GND                      J35              B49      SCONN140_G64V3431BHR-SCONN140_B
GND                      J35              B52      SCONN140_G64V3431BHR-SCONN140_B
GND                      J35              B55      SCONN140_G64V3431BHR-SCONN140_B
GND                      J35              B58      SCONN140_G64V3431BHR-SCONN140_B
GND                      J35              B61      SCONN140_G64V3431BHR-SCONN140_B
GND                      J35              B64      SCONN140_G64V3431BHR-SCONN140_B
GND                      J35              B67      SCONN140_G64V3431BHR-SCONN140_B
GND                      J35              B70      SCONN140_G64V3431BHR-SCONN140_B
GND                      J35              G1       SCONN140_G64V3431BHR-SCONN140_B
GND                      J35              G2       SCONN140_G64V3431BHR-SCONN140_B
GND                      J35              G3       SCONN140_G64V3431BHR-SCONN140_B
GND                      J35              G4       SCONN140_G64V3431BHR-SCONN140_B
GND                      J35              G5       SCONN140_G64V3431BHR-SCONN140_B
GND                      J35              G6       SCONN140_G64V3431BHR-SCONN140_B
GND                      J35              G7       SCONN140_G64V3431BHR-SCONN140_B
GND                      J35              G8       SCONN140_G64V3431BHR-SCONN140_B
GND                      J37              A1       SCONN168_623403212-SCONN168_6-A
GND                      J37              A2       SCONN168_623403212-SCONN168_6-A
GND                      J37              A3       SCONN168_623403212-SCONN168_6-A
GND                      J37              A4       SCONN168_623403212-SCONN168_6-A
GND                      J37              A5       SCONN168_623403212-SCONN168_6-A
GND                      J37              A6       SCONN168_623403212-SCONN168_6-A
GND                      J37              A13      SCONN168_623403212-SCONN168_6-A
GND                      J37              A16      SCONN168_623403212-SCONN168_6-A
GND                      J37              A19      SCONN168_623403212-SCONN168_6-A
GND                      J37              A22      SCONN168_623403212-SCONN168_6-A
GND                      J37              A25      SCONN168_623403212-SCONN168_6-A
GND                      J37              A28      SCONN168_623403212-SCONN168_6-A
GND                      J37              A29      SCONN168_623403212-SCONN168_6-A
GND                      J37              A32      SCONN168_623403212-SCONN168_6-A
GND                      J37              A35      SCONN168_623403212-SCONN168_6-A
GND                      J37              A38      SCONN168_623403212-SCONN168_6-A
GND                      J37              A41      SCONN168_623403212-SCONN168_6-A
GND                      J37              A43      SCONN168_623403212-SCONN168_6-A
GND                      J37              A46      SCONN168_623403212-SCONN168_6-A
GND                      J37              A49      SCONN168_623403212-SCONN168_6-A
GND                      J37              A52      SCONN168_623403212-SCONN168_6-A
GND                      J37              A55      SCONN168_623403212-SCONN168_6-A
GND                      J37              A58      SCONN168_623403212-SCONN168_6-A
GND                      J37              A61      SCONN168_623403212-SCONN168_6-A
GND                      J37              A64      SCONN168_623403212-SCONN168_6-A
GND                      J37              A67      SCONN168_623403212-SCONN168_6-A
GND                      J37              B13      SCONN168_623403212-SCONN168_6-A
GND                      J37              B16      SCONN168_623403212-SCONN168_6-A
GND                      J37              B19      SCONN168_623403212-SCONN168_6-A
GND                      J37              B22      SCONN168_623403212-SCONN168_6-A
GND                      J37              B25      SCONN168_623403212-SCONN168_6-A
GND                      J37              B28      SCONN168_623403212-SCONN168_6-A
GND                      J37              B29      SCONN168_623403212-SCONN168_6-A
GND                      J37              B32      SCONN168_623403212-SCONN168_6-A
GND                      J37              B35      SCONN168_623403212-SCONN168_6-A
GND                      J37              B38      SCONN168_623403212-SCONN168_6-A
GND                      J37              B41      SCONN168_623403212-SCONN168_6-A
GND                      J37              B43      SCONN168_623403212-SCONN168_6-A
GND                      J37              B46      SCONN168_623403212-SCONN168_6-A
GND                      J37              B49      SCONN168_623403212-SCONN168_6-A
GND                      J37              B52      SCONN168_623403212-SCONN168_6-A
GND                      J37              B55      SCONN168_623403212-SCONN168_6-A
GND                      J37              B58      SCONN168_623403212-SCONN168_6-A
GND                      J37              B61      SCONN168_623403212-SCONN168_6-A
GND                      J37              B64      SCONN168_623403212-SCONN168_6-A
GND                      J37              B67      SCONN168_623403212-SCONN168_6-A
GND                      J37              OCP_A10  SCONN168_623403212-SCONN168_6-A
GND                      J37              OCP_A13  SCONN168_623403212-SCONN168_6-A
GND                      J37              OCP_B10  SCONN168_623403212-SCONN168_6-A
GND                      J37              OCP_B13  SCONN168_623403212-SCONN168_6-A
GND                      J41              A11      SCONN168_623403212-SCONN168_6-A
GND                      J41              A14      SCONN168_623403212-SCONN168_6-A
GND                      J41              A17      SCONN168_623403212-SCONN168_6-A
GND                      J41              A20      SCONN168_623403212-SCONN168_6-A
GND                      J41              A33      SCONN168_623403212-SCONN168_6-A
GND                      J41              A42      SCONN168_623403212-SCONN168_6-A
GND                      J41              A43      SCONN168_623403212-SCONN168_6-A
GND                      J41              A52      SCONN168_623403212-SCONN168_6-A
GND                      J41              A55      SCONN168_623403212-SCONN168_6-A
GND                      J41              A58      SCONN168_623403212-SCONN168_6-A
GND                      J41              A61      SCONN168_623403212-SCONN168_6-A
GND                      J41              A64      SCONN168_623403212-SCONN168_6-A
GND                      J41              A67      SCONN168_623403212-SCONN168_6-A
GND                      J41              A70      SCONN168_623403212-SCONN168_6-A
GND                      J41              B10      SCONN168_623403212-SCONN168_6-A
GND                      J41              B17      SCONN168_623403212-SCONN168_6-A
GND                      J41              B26      SCONN168_623403212-SCONN168_6-A
GND                      J41              B33      SCONN168_623403212-SCONN168_6-A
GND                      J41              B38      SCONN168_623403212-SCONN168_6-A
GND                      J41              B49      SCONN168_623403212-SCONN168_6-A
GND                      J41              B52      SCONN168_623403212-SCONN168_6-A
GND                      J41              B55      SCONN168_623403212-SCONN168_6-A
GND                      J41              B58      SCONN168_623403212-SCONN168_6-A
GND                      J41              B61      SCONN168_623403212-SCONN168_6-A
GND                      J41              B64      SCONN168_623403212-SCONN168_6-A
GND                      J41              B67      SCONN168_623403212-SCONN168_6-A
GND                      J41              B70      SCONN168_623403212-SCONN168_6-A
GND                      J41              OCP_A3   SCONN168_623403212-SCONN168_6-A
GND                      J41              OCP_A4   SCONN168_623403212-SCONN168_6-A
GND                      J41              OCP_A13  SCONN168_623403212-SCONN168_6-A
GND                      J41              OCP_B4   SCONN168_623403212-SCONN168_6-A
GND                      J41              OCP_B7   SCONN168_623403212-SCONN168_6-A
GND                      J41              OCP_B10  SCONN168_623403212-SCONN168_6-A
GND                      J42              14       SCONN60_QSH03001LDAKTR-SCONN60A
GND                      J42              16       SCONN60_QSH03001LDAKTR-SCONN60A
GND                      J42              57       SCONN60_QSH03001LDAKTR-SCONN60A
GND                      J42              58       SCONN60_QSH03001LDAKTR-SCONN60A
GND                      J42              60       SCONN60_QSH03001LDAKTR-SCONN60A
GND                      J42              G1       SCONN60_QSH03001LDAKTR-SCONN60A
GND                      J42              G2       SCONN60_QSH03001LDAKTR-SCONN60A
GND                      J42              G3       SCONN60_QSH03001LDAKTR-SCONN60A
GND                      J42              G4       SCONN60_QSH03001LDAKTR-SCONN60A
GND                      J43              2        CONN10_G2100HT0038071-CONN10_GA
GND                      J43              10       CONN10_G2100HT0038071-CONN10_GA
GND                      J44              4        CONN24_52SH90245BRD-CONN24_52SA
GND                      J44              5        CONN24_52SH90245BRD-CONN24_52SA
GND                      J44              8        CONN24_52SH90245BRD-CONN24_52SA
GND                      J44              12       CONN24_52SH90245BRD-CONN24_52SA
GND                      J44              16       CONN24_52SH90245BRD-CONN24_52SA
GND                      J44              20       CONN24_52SH90245BRD-CONN24_52SA
GND                      J48              4        CONN9_2UB3903013101F-CONN9_2UBA
GND                      J48              7        CONN9_2UB3903013101F-CONN9_2UBA
GND                      J48              G1       CONN9_2UB3903013101F-CONN9_2UBA
GND                      J48              G2       CONN9_2UB3903013101F-CONN9_2UBA
GND                      J48              G3       CONN9_2UB3903013101F-CONN9_2UBA
GND                      J48              G4       CONN9_2UB3903013101F-CONN9_2UBA
GND                      J49              1        CONN10_10142708102011LF-CONN10A
GND                      J49              2        CONN10_10142708102011LF-CONN10A
GND                      J49              3        CONN10_10142708102011LF-CONN10A
GND                      J49              4        CONN10_10142708102011LF-CONN10A
GND                      J49              5        CONN10_10142708102011LF-CONN10A
GND                      J50              1        CONN10_10142708102011LF-CONN10A
GND                      J50              2        CONN10_10142708102011LF-CONN10A
GND                      J50              3        CONN10_10142708102011LF-CONN10A
GND                      J50              4        CONN10_10142708102011LF-CONN10A
GND                      J50              5        CONN10_10142708102011LF-CONN10A
GND                      J54              1        CONN7_ABASAT054KA1-CONN7_ABA-SA
GND                      J54              4        CONN7_ABASAT054KA1-CONN7_ABA-SA
GND                      J54              7        CONN7_ABASAT054KA1-CONN7_ABA-SA
GND                      J54              G1       CONN7_ABASAT054KA1-CONN7_ABA-SA
GND                      J54              G2       CONN7_ABASAT054KA1-CONN7_ABA-SA
GND                      J55              A13      SCONN140_G64V3431BHR-SCONN140_A
GND                      J55              A16      SCONN140_G64V3431BHR-SCONN140_A
GND                      J55              A19      SCONN140_G64V3431BHR-SCONN140_A
GND                      J55              A22      SCONN140_G64V3431BHR-SCONN140_A
GND                      J55              A25      SCONN140_G64V3431BHR-SCONN140_A
GND                      J55              A28      SCONN140_G64V3431BHR-SCONN140_A
GND                      J55              A29      SCONN140_G64V3431BHR-SCONN140_A
GND                      J55              A32      SCONN140_G64V3431BHR-SCONN140_A
GND                      J55              A35      SCONN140_G64V3431BHR-SCONN140_A
GND                      J55              A38      SCONN140_G64V3431BHR-SCONN140_A
GND                      J55              A41      SCONN140_G64V3431BHR-SCONN140_A
GND                      J55              A42      SCONN140_G64V3431BHR-SCONN140_A
GND                      J55              A43      SCONN140_G64V3431BHR-SCONN140_A
GND                      J55              A46      SCONN140_G64V3431BHR-SCONN140_A
GND                      J55              A49      SCONN140_G64V3431BHR-SCONN140_A
GND                      J55              A52      SCONN140_G64V3431BHR-SCONN140_A
GND                      J55              A55      SCONN140_G64V3431BHR-SCONN140_A
GND                      J55              A58      SCONN140_G64V3431BHR-SCONN140_A
GND                      J55              A61      SCONN140_G64V3431BHR-SCONN140_A
GND                      J55              A64      SCONN140_G64V3431BHR-SCONN140_A
GND                      J55              A67      SCONN140_G64V3431BHR-SCONN140_A
GND                      J55              B5       SCONN140_G64V3431BHR-SCONN140_A
GND                      J55              B6       SCONN140_G64V3431BHR-SCONN140_A
GND                      J55              B13      SCONN140_G64V3431BHR-SCONN140_A
GND                      J55              B16      SCONN140_G64V3431BHR-SCONN140_A
GND                      J55              B19      SCONN140_G64V3431BHR-SCONN140_A
GND                      J55              B22      SCONN140_G64V3431BHR-SCONN140_A
GND                      J55              B25      SCONN140_G64V3431BHR-SCONN140_A
GND                      J55              B28      SCONN140_G64V3431BHR-SCONN140_A
GND                      J55              B29      SCONN140_G64V3431BHR-SCONN140_A
GND                      J55              B32      SCONN140_G64V3431BHR-SCONN140_A
GND                      J55              B35      SCONN140_G64V3431BHR-SCONN140_A
GND                      J55              B38      SCONN140_G64V3431BHR-SCONN140_A
GND                      J55              B41      SCONN140_G64V3431BHR-SCONN140_A
GND                      J55              B43      SCONN140_G64V3431BHR-SCONN140_A
GND                      J55              B46      SCONN140_G64V3431BHR-SCONN140_A
GND                      J55              B49      SCONN140_G64V3431BHR-SCONN140_A
GND                      J55              B52      SCONN140_G64V3431BHR-SCONN140_A
GND                      J55              B55      SCONN140_G64V3431BHR-SCONN140_A
GND                      J55              B58      SCONN140_G64V3431BHR-SCONN140_A
GND                      J55              B61      SCONN140_G64V3431BHR-SCONN140_A
GND                      J55              B64      SCONN140_G64V3431BHR-SCONN140_A
GND                      J55              B67      SCONN140_G64V3431BHR-SCONN140_A
GND                      J55              G1       SCONN140_G64V3431BHR-SCONN140_A
GND                      J55              G2       SCONN140_G64V3431BHR-SCONN140_A
GND                      J55              G3       SCONN140_G64V3431BHR-SCONN140_A
GND                      J55              G4       SCONN140_G64V3431BHR-SCONN140_A
GND                      J55              G5       SCONN140_G64V3431BHR-SCONN140_A
GND                      J55              G6       SCONN140_G64V3431BHR-SCONN140_A
GND                      J55              G7       SCONN140_G64V3431BHR-SCONN140_A
GND                      J55              G8       SCONN140_G64V3431BHR-SCONN140_A
GND                      J57              A13      SCONN140_G64V3431BHR-SCONN140_A
GND                      J57              A16      SCONN140_G64V3431BHR-SCONN140_A
GND                      J57              A19      SCONN140_G64V3431BHR-SCONN140_A
GND                      J57              A22      SCONN140_G64V3431BHR-SCONN140_A
GND                      J57              A25      SCONN140_G64V3431BHR-SCONN140_A
GND                      J57              A28      SCONN140_G64V3431BHR-SCONN140_A
GND                      J57              A29      SCONN140_G64V3431BHR-SCONN140_A
GND                      J57              A32      SCONN140_G64V3431BHR-SCONN140_A
GND                      J57              A35      SCONN140_G64V3431BHR-SCONN140_A
GND                      J57              A38      SCONN140_G64V3431BHR-SCONN140_A
GND                      J57              A41      SCONN140_G64V3431BHR-SCONN140_A
GND                      J57              A42      SCONN140_G64V3431BHR-SCONN140_A
GND                      J57              A43      SCONN140_G64V3431BHR-SCONN140_A
GND                      J57              A46      SCONN140_G64V3431BHR-SCONN140_A
GND                      J57              A49      SCONN140_G64V3431BHR-SCONN140_A
GND                      J57              A52      SCONN140_G64V3431BHR-SCONN140_A
GND                      J57              A55      SCONN140_G64V3431BHR-SCONN140_A
GND                      J57              A58      SCONN140_G64V3431BHR-SCONN140_A
GND                      J57              A61      SCONN140_G64V3431BHR-SCONN140_A
GND                      J57              A64      SCONN140_G64V3431BHR-SCONN140_A
GND                      J57              A67      SCONN140_G64V3431BHR-SCONN140_A
GND                      J57              B5       SCONN140_G64V3431BHR-SCONN140_A
GND                      J57              B6       SCONN140_G64V3431BHR-SCONN140_A
GND                      J57              B13      SCONN140_G64V3431BHR-SCONN140_A
GND                      J57              B16      SCONN140_G64V3431BHR-SCONN140_A
GND                      J57              B19      SCONN140_G64V3431BHR-SCONN140_A
GND                      J57              B22      SCONN140_G64V3431BHR-SCONN140_A
GND                      J57              B25      SCONN140_G64V3431BHR-SCONN140_A
GND                      J57              B28      SCONN140_G64V3431BHR-SCONN140_A
GND                      J57              B29      SCONN140_G64V3431BHR-SCONN140_A
GND                      J57              B32      SCONN140_G64V3431BHR-SCONN140_A
GND                      J57              B35      SCONN140_G64V3431BHR-SCONN140_A
GND                      J57              B38      SCONN140_G64V3431BHR-SCONN140_A
GND                      J57              B41      SCONN140_G64V3431BHR-SCONN140_A
GND                      J57              B43      SCONN140_G64V3431BHR-SCONN140_A
GND                      J57              B46      SCONN140_G64V3431BHR-SCONN140_A
GND                      J57              B49      SCONN140_G64V3431BHR-SCONN140_A
GND                      J57              B52      SCONN140_G64V3431BHR-SCONN140_A
GND                      J57              B55      SCONN140_G64V3431BHR-SCONN140_A
GND                      J57              B58      SCONN140_G64V3431BHR-SCONN140_A
GND                      J57              B61      SCONN140_G64V3431BHR-SCONN140_A
GND                      J57              B64      SCONN140_G64V3431BHR-SCONN140_A
GND                      J57              B67      SCONN140_G64V3431BHR-SCONN140_A
GND                      J57              G1       SCONN140_G64V3431BHR-SCONN140_A
GND                      J57              G2       SCONN140_G64V3431BHR-SCONN140_A
GND                      J57              G3       SCONN140_G64V3431BHR-SCONN140_A
GND                      J57              G4       SCONN140_G64V3431BHR-SCONN140_A
GND                      J57              G5       SCONN140_G64V3431BHR-SCONN140_A
GND                      J57              G6       SCONN140_G64V3431BHR-SCONN140_A
GND                      J57              G7       SCONN140_G64V3431BHR-SCONN140_A
GND                      J57              G8       SCONN140_G64V3431BHR-SCONN140_A
GND                      J59              3        SCONN75K_APCI0155P004A-SCONN75A
GND                      J59              9        SCONN75K_APCI0155P004A-SCONN75A
GND                      J59              15       SCONN75K_APCI0155P004A-SCONN75A
GND                      J59              21       SCONN75K_APCI0155P004A-SCONN75A
GND                      J59              27       SCONN75K_APCI0155P004A-SCONN75A
GND                      J59              33       SCONN75K_APCI0155P004A-SCONN75A
GND                      J59              39       SCONN75K_APCI0155P004A-SCONN75A
GND                      J59              45       SCONN75K_APCI0155P004A-SCONN75A
GND                      J59              51       SCONN75K_APCI0155P004A-SCONN75A
GND                      J59              57       SCONN75K_APCI0155P004A-SCONN75A
GND                      J59              71       SCONN75K_APCI0155P004A-SCONN75A
GND                      J59              73       SCONN75K_APCI0155P004A-SCONN75A
GND                      J59              75       SCONN75K_APCI0155P004A-SCONN75A
GND                      J59              G1       SCONN75K_APCI0155P004A-SCONN75A
GND                      J59              G2       SCONN75K_APCI0155P004A-SCONN75A
GND                      J61              A1       SCONN84_123318136-SCONN84_1-23A
GND                      J61              A2       SCONN84_123318136-SCONN84_1-23A
GND                      J61              A3       SCONN84_123318136-SCONN84_1-23A
GND                      J61              A4       SCONN84_123318136-SCONN84_1-23A
GND                      J61              A5       SCONN84_123318136-SCONN84_1-23A
GND                      J61              A6       SCONN84_123318136-SCONN84_1-23A
GND                      J61              A13      SCONN84_123318136-SCONN84_1-23A
GND                      J61              A16      SCONN84_123318136-SCONN84_1-23A
GND                      J61              A19      SCONN84_123318136-SCONN84_1-23A
GND                      J61              A22      SCONN84_123318136-SCONN84_1-23A
GND                      J61              A25      SCONN84_123318136-SCONN84_1-23A
GND                      J61              A28      SCONN84_123318136-SCONN84_1-23A
GND                      J61              A29      SCONN84_123318136-SCONN84_1-23A
GND                      J61              A32      SCONN84_123318136-SCONN84_1-23A
GND                      J61              A35      SCONN84_123318136-SCONN84_1-23A
GND                      J61              A38      SCONN84_123318136-SCONN84_1-23A
GND                      J61              A41      SCONN84_123318136-SCONN84_1-23A
GND                      J61              B13      SCONN84_123318136-SCONN84_1-23A
GND                      J61              B16      SCONN84_123318136-SCONN84_1-23A
GND                      J61              B19      SCONN84_123318136-SCONN84_1-23A
GND                      J61              B22      SCONN84_123318136-SCONN84_1-23A
GND                      J61              B25      SCONN84_123318136-SCONN84_1-23A
GND                      J61              B28      SCONN84_123318136-SCONN84_1-23A
GND                      J61              B29      SCONN84_123318136-SCONN84_1-23A
GND                      J61              B32      SCONN84_123318136-SCONN84_1-23A
GND                      J61              B35      SCONN84_123318136-SCONN84_1-23A
GND                      J61              B38      SCONN84_123318136-SCONN84_1-23A
GND                      J61              B41      SCONN84_123318136-SCONN84_1-23A
GND                      J61              G1       SCONN84_123318136-SCONN84_1-23A
GND                      J61              G2       SCONN84_123318136-SCONN84_1-23A
GND                      J61              G3       SCONN84_123318136-SCONN84_1-23A
GND                      J61              G4       SCONN84_123318136-SCONN84_1-23A
GND                      J61              G5       SCONN84_123318136-SCONN84_1-23A
GND                      J62              A1       SCONN84_123318136-SCONN84_1-23A
GND                      J62              A2       SCONN84_123318136-SCONN84_1-23A
GND                      J62              A3       SCONN84_123318136-SCONN84_1-23A
GND                      J62              A4       SCONN84_123318136-SCONN84_1-23A
GND                      J62              A5       SCONN84_123318136-SCONN84_1-23A
GND                      J62              A6       SCONN84_123318136-SCONN84_1-23A
GND                      J62              A13      SCONN84_123318136-SCONN84_1-23A
GND                      J62              A16      SCONN84_123318136-SCONN84_1-23A
GND                      J62              A19      SCONN84_123318136-SCONN84_1-23A
GND                      J62              A22      SCONN84_123318136-SCONN84_1-23A
GND                      J62              A25      SCONN84_123318136-SCONN84_1-23A
GND                      J62              A28      SCONN84_123318136-SCONN84_1-23A
GND                      J62              A29      SCONN84_123318136-SCONN84_1-23A
GND                      J62              A32      SCONN84_123318136-SCONN84_1-23A
GND                      J62              A35      SCONN84_123318136-SCONN84_1-23A
GND                      J62              A38      SCONN84_123318136-SCONN84_1-23A
GND                      J62              A41      SCONN84_123318136-SCONN84_1-23A
GND                      J62              B13      SCONN84_123318136-SCONN84_1-23A
GND                      J62              B16      SCONN84_123318136-SCONN84_1-23A
GND                      J62              B19      SCONN84_123318136-SCONN84_1-23A
GND                      J62              B22      SCONN84_123318136-SCONN84_1-23A
GND                      J62              B25      SCONN84_123318136-SCONN84_1-23A
GND                      J62              B28      SCONN84_123318136-SCONN84_1-23A
GND                      J62              B29      SCONN84_123318136-SCONN84_1-23A
GND                      J62              B32      SCONN84_123318136-SCONN84_1-23A
GND                      J62              B35      SCONN84_123318136-SCONN84_1-23A
GND                      J62              B38      SCONN84_123318136-SCONN84_1-23A
GND                      J62              B41      SCONN84_123318136-SCONN84_1-23A
GND                      J62              G1       SCONN84_123318136-SCONN84_1-23A
GND                      J62              G2       SCONN84_123318136-SCONN84_1-23A
GND                      J62              G3       SCONN84_123318136-SCONN84_1-23A
GND                      J62              G4       SCONN84_123318136-SCONN84_1-23A
GND                      J62              G5       SCONN84_123318136-SCONN84_1-23A
GND                      J87              A1       SCONN84_123318136-SCONN84_1-23A
GND                      J87              A2       SCONN84_123318136-SCONN84_1-23A
GND                      J87              A3       SCONN84_123318136-SCONN84_1-23A
GND                      J87              A4       SCONN84_123318136-SCONN84_1-23A
GND                      J87              A5       SCONN84_123318136-SCONN84_1-23A
GND                      J87              A6       SCONN84_123318136-SCONN84_1-23A
GND                      J87              A13      SCONN84_123318136-SCONN84_1-23A
GND                      J87              A16      SCONN84_123318136-SCONN84_1-23A
GND                      J87              A19      SCONN84_123318136-SCONN84_1-23A
GND                      J87              A22      SCONN84_123318136-SCONN84_1-23A
GND                      J87              A25      SCONN84_123318136-SCONN84_1-23A
GND                      J87              A28      SCONN84_123318136-SCONN84_1-23A
GND                      J87              A29      SCONN84_123318136-SCONN84_1-23A
GND                      J87              A32      SCONN84_123318136-SCONN84_1-23A
GND                      J87              A35      SCONN84_123318136-SCONN84_1-23A
GND                      J87              A38      SCONN84_123318136-SCONN84_1-23A
GND                      J87              A41      SCONN84_123318136-SCONN84_1-23A
GND                      J87              B13      SCONN84_123318136-SCONN84_1-23A
GND                      J87              B16      SCONN84_123318136-SCONN84_1-23A
GND                      J87              B19      SCONN84_123318136-SCONN84_1-23A
GND                      J87              B22      SCONN84_123318136-SCONN84_1-23A
GND                      J87              B25      SCONN84_123318136-SCONN84_1-23A
GND                      J87              B28      SCONN84_123318136-SCONN84_1-23A
GND                      J87              B29      SCONN84_123318136-SCONN84_1-23A
GND                      J87              B32      SCONN84_123318136-SCONN84_1-23A
GND                      J87              B35      SCONN84_123318136-SCONN84_1-23A
GND                      J87              B38      SCONN84_123318136-SCONN84_1-23A
GND                      J87              B41      SCONN84_123318136-SCONN84_1-23A
GND                      J87              G1       SCONN84_123318136-SCONN84_1-23A
GND                      J87              G2       SCONN84_123318136-SCONN84_1-23A
GND                      J87              G3       SCONN84_123318136-SCONN84_1-23A
GND                      J87              G4       SCONN84_123318136-SCONN84_1-23A
GND                      J87              G5       SCONN84_123318136-SCONN84_1-23A
GND                      J88              A1       SCONN84_123318136-SCONN84_1-23A
GND                      J88              A2       SCONN84_123318136-SCONN84_1-23A
GND                      J88              A3       SCONN84_123318136-SCONN84_1-23A
GND                      J88              A4       SCONN84_123318136-SCONN84_1-23A
GND                      J88              A5       SCONN84_123318136-SCONN84_1-23A
GND                      J88              A6       SCONN84_123318136-SCONN84_1-23A
GND                      J88              A13      SCONN84_123318136-SCONN84_1-23A
GND                      J88              A16      SCONN84_123318136-SCONN84_1-23A
GND                      J88              A19      SCONN84_123318136-SCONN84_1-23A
GND                      J88              A22      SCONN84_123318136-SCONN84_1-23A
GND                      J88              A25      SCONN84_123318136-SCONN84_1-23A
GND                      J88              A28      SCONN84_123318136-SCONN84_1-23A
GND                      J88              A29      SCONN84_123318136-SCONN84_1-23A
GND                      J88              A32      SCONN84_123318136-SCONN84_1-23A
GND                      J88              A35      SCONN84_123318136-SCONN84_1-23A
GND                      J88              A38      SCONN84_123318136-SCONN84_1-23A
GND                      J88              A41      SCONN84_123318136-SCONN84_1-23A
GND                      J88              B13      SCONN84_123318136-SCONN84_1-23A
GND                      J88              B16      SCONN84_123318136-SCONN84_1-23A
GND                      J88              B19      SCONN84_123318136-SCONN84_1-23A
GND                      J88              B22      SCONN84_123318136-SCONN84_1-23A
GND                      J88              B25      SCONN84_123318136-SCONN84_1-23A
GND                      J88              B28      SCONN84_123318136-SCONN84_1-23A
GND                      J88              B29      SCONN84_123318136-SCONN84_1-23A
GND                      J88              B32      SCONN84_123318136-SCONN84_1-23A
GND                      J88              B35      SCONN84_123318136-SCONN84_1-23A
GND                      J88              B38      SCONN84_123318136-SCONN84_1-23A
GND                      J88              B41      SCONN84_123318136-SCONN84_1-23A
GND                      J88              G1       SCONN84_123318136-SCONN84_1-23A
GND                      J88              G2       SCONN84_123318136-SCONN84_1-23A
GND                      J88              G3       SCONN84_123318136-SCONN84_1-23A
GND                      J88              G4       SCONN84_123318136-SCONN84_1-23A
GND                      J88              G5       SCONN84_123318136-SCONN84_1-23A
GND                      J89              A8       SCONN280_ME1028040102011-SCONNA
GND                      J89              A9       SCONN280_ME1028040102011-SCONNA
GND                      J89              A10      SCONN280_ME1028040102011-SCONNA
GND                      J89              A11      SCONN280_ME1028040102011-SCONNA
GND                      J89              A12      SCONN280_ME1028040102011-SCONNA
GND                      J89              A13      SCONN280_ME1028040102011-SCONNA
GND                      J89              A14      SCONN280_ME1028040102011-SCONNA
GND                      J89              A15      SCONN280_ME1028040102011-SCONNA
GND                      J89              A16      SCONN280_ME1028040102011-SCONNA
GND                      J89              A17      SCONN280_ME1028040102011-SCONNA
GND                      J89              A18      SCONN280_ME1028040102011-SCONNA
GND                      J89              A19      SCONN280_ME1028040102011-SCONNA
GND                      J89              A28      SCONN280_ME1028040102011-SCONNA
GND                      J89              A29      SCONN280_ME1028040102011-SCONNA
GND                      J89              A32      SCONN280_ME1028040102011-SCONNA
GND                      J89              A35      SCONN280_ME1028040102011-SCONNA
GND                      J89              A38      SCONN280_ME1028040102011-SCONNA
GND                      J89              A41      SCONN280_ME1028040102011-SCONNA
GND                      J89              A44      SCONN280_ME1028040102011-SCONNA
GND                      J89              A47      SCONN280_ME1028040102011-SCONNA
GND                      J89              A50      SCONN280_ME1028040102011-SCONNA
GND                      J89              A53      SCONN280_ME1028040102011-SCONNA
GND                      J89              A56      SCONN280_ME1028040102011-SCONNA
GND                      J89              A57      SCONN280_ME1028040102011-SCONNA
GND                      J89              A60      SCONN280_ME1028040102011-SCONNA
GND                      J89              A63      SCONN280_ME1028040102011-SCONNA
GND                      J89              A66      SCONN280_ME1028040102011-SCONNA
GND                      J89              A69      SCONN280_ME1028040102011-SCONNA
GND                      J89              A72      SCONN280_ME1028040102011-SCONNA
GND                      J89              A75      SCONN280_ME1028040102011-SCONNA
GND                      J89              A78      SCONN280_ME1028040102011-SCONNA
GND                      J89              A81      SCONN280_ME1028040102011-SCONNA
GND                      J89              A84      SCONN280_ME1028040102011-SCONNA
GND                      J89              A85      SCONN280_ME1028040102011-SCONNA
GND                      J89              A88      SCONN280_ME1028040102011-SCONNA
GND                      J89              A91      SCONN280_ME1028040102011-SCONNA
GND                      J89              A94      SCONN280_ME1028040102011-SCONNA
GND                      J89              A97      SCONN280_ME1028040102011-SCONNA
GND                      J89              A100     SCONN280_ME1028040102011-SCONNA
GND                      J89              A103     SCONN280_ME1028040102011-SCONNA
GND                      J89              A106     SCONN280_ME1028040102011-SCONNA
GND                      J89              A109     SCONN280_ME1028040102011-SCONNA
GND                      J89              A112     SCONN280_ME1028040102011-SCONNA
GND                      J89              A113     SCONN280_ME1028040102011-SCONNA
GND                      J89              A116     SCONN280_ME1028040102011-SCONNA
GND                      J89              A119     SCONN280_ME1028040102011-SCONNA
GND                      J89              A122     SCONN280_ME1028040102011-SCONNA
GND                      J89              A125     SCONN280_ME1028040102011-SCONNA
GND                      J89              A128     SCONN280_ME1028040102011-SCONNA
GND                      J89              A131     SCONN280_ME1028040102011-SCONNA
GND                      J89              A134     SCONN280_ME1028040102011-SCONNA
GND                      J89              A135     SCONN280_ME1028040102011-SCONNA
GND                      J89              A136     SCONN280_ME1028040102011-SCONNA
GND                      J89              A137     SCONN280_ME1028040102011-SCONNA
GND                      J89              A138     SCONN280_ME1028040102011-SCONNA
GND                      J89              A139     SCONN280_ME1028040102011-SCONNA
GND                      J89              B8       SCONN280_ME1028040102011-SCONNA
GND                      J89              B9       SCONN280_ME1028040102011-SCONNA
GND                      J89              B10      SCONN280_ME1028040102011-SCONNA
GND                      J89              B11      SCONN280_ME1028040102011-SCONNA
GND                      J89              B12      SCONN280_ME1028040102011-SCONNA
GND                      J89              B19      SCONN280_ME1028040102011-SCONNA
GND                      J89              B23      SCONN280_ME1028040102011-SCONNA
GND                      J89              B26      SCONN280_ME1028040102011-SCONNA
GND                      J89              B29      SCONN280_ME1028040102011-SCONNA
GND                      J89              B32      SCONN280_ME1028040102011-SCONNA
GND                      J89              B35      SCONN280_ME1028040102011-SCONNA
GND                      J89              B38      SCONN280_ME1028040102011-SCONNA
GND                      J89              B41      SCONN280_ME1028040102011-SCONNA
GND                      J89              B44      SCONN280_ME1028040102011-SCONNA
GND                      J89              B47      SCONN280_ME1028040102011-SCONNA
GND                      J89              B50      SCONN280_ME1028040102011-SCONNA
GND                      J89              B53      SCONN280_ME1028040102011-SCONNA
GND                      J89              B56      SCONN280_ME1028040102011-SCONNA
GND                      J89              B57      SCONN280_ME1028040102011-SCONNA
GND                      J89              B60      SCONN280_ME1028040102011-SCONNA
GND                      J89              B63      SCONN280_ME1028040102011-SCONNA
GND                      J89              B66      SCONN280_ME1028040102011-SCONNA
GND                      J89              B69      SCONN280_ME1028040102011-SCONNA
GND                      J89              B72      SCONN280_ME1028040102011-SCONNA
GND                      J89              B75      SCONN280_ME1028040102011-SCONNA
GND                      J89              B78      SCONN280_ME1028040102011-SCONNA
GND                      J89              B81      SCONN280_ME1028040102011-SCONNA
GND                      J89              B84      SCONN280_ME1028040102011-SCONNA
GND                      J89              B85      SCONN280_ME1028040102011-SCONNA
GND                      J89              B88      SCONN280_ME1028040102011-SCONNA
GND                      J89              B91      SCONN280_ME1028040102011-SCONNA
GND                      J89              B94      SCONN280_ME1028040102011-SCONNA
GND                      J89              B97      SCONN280_ME1028040102011-SCONNA
GND                      J89              B100     SCONN280_ME1028040102011-SCONNA
GND                      J89              B103     SCONN280_ME1028040102011-SCONNA
GND                      J89              B106     SCONN280_ME1028040102011-SCONNA
GND                      J89              B109     SCONN280_ME1028040102011-SCONNA
GND                      J89              B112     SCONN280_ME1028040102011-SCONNA
GND                      J89              B113     SCONN280_ME1028040102011-SCONNA
GND                      J89              B116     SCONN280_ME1028040102011-SCONNA
GND                      J89              B119     SCONN280_ME1028040102011-SCONNA
GND                      J89              B122     SCONN280_ME1028040102011-SCONNA
GND                      J89              B125     SCONN280_ME1028040102011-SCONNA
GND                      J89              B128     SCONN280_ME1028040102011-SCONNA
GND                      J89              B131     SCONN280_ME1028040102011-SCONNA
GND                      J89              B134     SCONN280_ME1028040102011-SCONNA
GND                      J89              G1       SCONN280_ME1028040102011-SCONNA
GND                      J89              G2       SCONN280_ME1028040102011-SCONNA
GND                      J89              G3       SCONN280_ME1028040102011-SCONNA
GND                      J89              G4       SCONN280_ME1028040102011-SCONNA
GND                      J90              A1       CONN56_ME2005602311011-CONN56_A
GND                      J90              A2       CONN56_ME2005602311011-CONN56_A
GND                      J90              A3       CONN56_ME2005602311011-CONN56_A
GND                      J90              A4       CONN56_ME2005602311011-CONN56_A
GND                      J90              A5       CONN56_ME2005602311011-CONN56_A
GND                      J90              A6       CONN56_ME2005602311011-CONN56_A
GND                      J90              A13      CONN56_ME2005602311011-CONN56_A
GND                      J90              A16      CONN56_ME2005602311011-CONN56_A
GND                      J90              A19      CONN56_ME2005602311011-CONN56_A
GND                      J90              A22      CONN56_ME2005602311011-CONN56_A
GND                      J90              A25      CONN56_ME2005602311011-CONN56_A
GND                      J90              A28      CONN56_ME2005602311011-CONN56_A
GND                      J90              B13      CONN56_ME2005602311011-CONN56_A
GND                      J90              B16      CONN56_ME2005602311011-CONN56_A
GND                      J90              B19      CONN56_ME2005602311011-CONN56_A
GND                      J90              B22      CONN56_ME2005602311011-CONN56_A
GND                      J90              B25      CONN56_ME2005602311011-CONN56_A
GND                      J90              B28      CONN56_ME2005602311011-CONN56_A
GND                      J91              A1       CONN56_ME2005602311011-CONN56_A
GND                      J91              A2       CONN56_ME2005602311011-CONN56_A
GND                      J91              A3       CONN56_ME2005602311011-CONN56_A
GND                      J91              A4       CONN56_ME2005602311011-CONN56_A
GND                      J91              A5       CONN56_ME2005602311011-CONN56_A
GND                      J91              A6       CONN56_ME2005602311011-CONN56_A
GND                      J91              A13      CONN56_ME2005602311011-CONN56_A
GND                      J91              A16      CONN56_ME2005602311011-CONN56_A
GND                      J91              A19      CONN56_ME2005602311011-CONN56_A
GND                      J91              A22      CONN56_ME2005602311011-CONN56_A
GND                      J91              A25      CONN56_ME2005602311011-CONN56_A
GND                      J91              A28      CONN56_ME2005602311011-CONN56_A
GND                      J91              B13      CONN56_ME2005602311011-CONN56_A
GND                      J91              B16      CONN56_ME2005602311011-CONN56_A
GND                      J91              B19      CONN56_ME2005602311011-CONN56_A
GND                      J91              B22      CONN56_ME2005602311011-CONN56_A
GND                      J91              B25      CONN56_ME2005602311011-CONN56_A
GND                      J91              B28      CONN56_ME2005602311011-CONN56_A
GND                      J92              A1       CONN56_ME2005602311011-CONN56_A
GND                      J92              A2       CONN56_ME2005602311011-CONN56_A
GND                      J92              A3       CONN56_ME2005602311011-CONN56_A
GND                      J92              A4       CONN56_ME2005602311011-CONN56_A
GND                      J92              A5       CONN56_ME2005602311011-CONN56_A
GND                      J92              A6       CONN56_ME2005602311011-CONN56_A
GND                      J92              A13      CONN56_ME2005602311011-CONN56_A
GND                      J92              A16      CONN56_ME2005602311011-CONN56_A
GND                      J92              A19      CONN56_ME2005602311011-CONN56_A
GND                      J92              A22      CONN56_ME2005602311011-CONN56_A
GND                      J92              A25      CONN56_ME2005602311011-CONN56_A
GND                      J92              A28      CONN56_ME2005602311011-CONN56_A
GND                      J92              B13      CONN56_ME2005602311011-CONN56_A
GND                      J92              B16      CONN56_ME2005602311011-CONN56_A
GND                      J92              B19      CONN56_ME2005602311011-CONN56_A
GND                      J92              B22      CONN56_ME2005602311011-CONN56_A
GND                      J92              B25      CONN56_ME2005602311011-CONN56_A
GND                      J92              B28      CONN56_ME2005602311011-CONN56_A
GND                      J93              A1       CONN56_ME2005602311011-CONN56_A
GND                      J93              A2       CONN56_ME2005602311011-CONN56_A
GND                      J93              A3       CONN56_ME2005602311011-CONN56_A
GND                      J93              A4       CONN56_ME2005602311011-CONN56_A
GND                      J93              A5       CONN56_ME2005602311011-CONN56_A
GND                      J93              A6       CONN56_ME2005602311011-CONN56_A
GND                      J93              A13      CONN56_ME2005602311011-CONN56_A
GND                      J93              A16      CONN56_ME2005602311011-CONN56_A
GND                      J93              A19      CONN56_ME2005602311011-CONN56_A
GND                      J93              A22      CONN56_ME2005602311011-CONN56_A
GND                      J93              A25      CONN56_ME2005602311011-CONN56_A
GND                      J93              A28      CONN56_ME2005602311011-CONN56_A
GND                      J93              B13      CONN56_ME2005602311011-CONN56_A
GND                      J93              B16      CONN56_ME2005602311011-CONN56_A
GND                      J93              B19      CONN56_ME2005602311011-CONN56_A
GND                      J93              B22      CONN56_ME2005602311011-CONN56_A
GND                      J93              B25      CONN56_ME2005602311011-CONN56_A
GND                      J93              B28      CONN56_ME2005602311011-CONN56_A
GND                      JP1              1        CONN3_210HP1030BR1-CONN3_210-HA
GND                      JP5              2        CONN3_HFK1030G000LAF-CONN3_HFKA
GND                      JP7              2        CONN3_210HP1030BR1-CONN3_210-HA
GND                      JP8              1        CONN3_HFK1030G000LAF-CONN3_HFKA
GND                      OSC1             2        OSC4_SIT1602AI2233E50000000D-5A
GND                      OSC2             2        Q_OSC4P_SMLF-25MHZ,OSC,BF62500A
GND                      PC16             2        Q_CAPP_THLF-560UF,2.5V,20%,OSCA
GND                      PC113            2        Q_CAP_C0402-1UF,25V,10%,X6S,CHA
GND                      PC117            2        Q_CAPP_SMLF-470UF,2V,20%,POSCAA
GND                      PC175            2        Q_CAP_C0402-2.2UF,10V,10%,X6S,A
GND                      PC176            2        Q_CAP_0402-3300PF,50V,10%,X7R,A
GND                      PC177            2        Q_CAP_C0402-1UF,16V,10%,X6S,CHA
GND                      PC179            2        Q_CAP_C0805-22UF,16V,20%,X6S,CA
GND                      PC180            2        Q_CAP_C0805-22UF,16V,20%,X6S,CA
GND                      PC181            2        Q_CAP_C0402-100NF,50V,10%,X7R,A
GND                      PC184            2        Q_CAP_0805-22UF,4V,20%,X6S,TMPA
GND                      PC186            2        Q_CAP_0805-22UF,4V,20%,X6S,TMPA
GND                      PC187            2        Q_CAP_C0402-2.2UF,10V,10%,X6S,A
GND                      PC188            2        Q_CAP_C0402-2.2UF,10V,10%,X6S,A
GND                      PC189            2        Q_CAPP_SMLF-470UF,2.5V,20%,EMPA
GND                      PC207            2        Q_CAPP_THLF-270UF,16V,20%,OSCOA
GND                      PC208            2        Q_CAPP_THLF-270UF,16V,20%,OSCOA
GND                      PC214            2        Q_CAP_0402-0.1UF,25V,10%,EMPTYA
GND                      PC217            2        Q_CAP_0402-1000PF,50V,5%,X7R,TA
GND                      PC218            2        Q_CAP_0402-1000PF,50V,5%,EMPTYA
GND                      PC219            2        Q_CAP_0402-1000PF,50V,5%,X7R,TA
GND                      PC220            2        Q_CAP_0402-1000PF,50V,5%,EMPTYA
GND                      PC221            2        Q_CAP_0402-0.1UF,25V,10%,X7R,CA
GND                      PC222            2        Q_CAP_0402-470PF,50V,10%,X7R,TA
GND                      PC223            2        Q_CAP_C0402-100NF,50V,10%,EMPTA
GND                      PC224            2        Q_CAP_0402-4.7UF,6.3V,20%,X6S,A
GND                      PC225            2        Q_CAP_C0402-1UF,16V,10%,X6S,CHA
GND                      PC226            2        Q_CAP_C0402-2.2UF,10V,10%,X6S,A
GND                      PC227            2        Q_CAP_C0402-2.2UF,10V,10%,X6S,A
GND                      PC1171           2        Q_CAP_C0402-2.2UF,10V,10%,EMPTA
GND                      PC1172           2        Q_CAP_C0402-2.2UF,10V,10%,EMPTA
GND                      PC1173           2        Q_CAP_C0402-1UF,16V,10%,X6S,CHA
GND                      PC1173_P0_3      2        Q_CAP_0402-3300PF,50V,10%,EMPTA
GND                      PC1174_P0_4      2        Q_CAP_0402-3300PF,50V,10%,EMPTA
GND                      PC1175_P0_3      2        Q_CAP_C0402-1UF,16V,10%,EMPTY,A
GND                      PC1176_P0_4      2        Q_CAP_C0402-1UF,16V,10%,EMPTY,A
GND                      PC1179_P0_3      2        Q_CAP_C0805-22UF,16V,20%,EMPTYA
GND                      PC1180_P0_4      2        Q_CAP_C0805-22UF,16V,20%,EMPTYA
GND                      PC1181_P0_3      2        Q_CAP_C0805-22UF,16V,20%,EMPTYA
GND                      PC1182_P0_4      2        Q_CAP_C0805-22UF,16V,20%,EMPTYA
GND                      PC1183           2        Q_CAPP_THLF-560UF,2.5V,20%,OSCA
GND                      PC1183_P0_3      2        Q_CAP_C0402-1UF,16V,10%,EMPTY,A
GND                      PC1183_P0_4      2        Q_CAP_C0402-100NF,50V,10%,EMPTA
GND                      PC1185           2        Q_CAPP_THLF-560UF,2.5V,20%,OSCA
GND                      PC1185_P0_3      2        Q_CAP_0805-22UF,4V,20%,EMPTY,TA
GND                      PC1186           2        Q_CAPP_THLF-560UF,2.5V,20%,EMPA
GND                      PC1186_P0_4      2        Q_CAP_0805-22UF,4V,20%,EMPTY,TA
GND                      PC1187           2        Q_CAPP_SMLF-470UF,2.5V,20%,EMPA
GND                      PC1187_P0_3      2        Q_CAP_0805-22UF,4V,20%,EMPTY,TA
GND                      PC1188_P0_4      2        Q_CAP_0805-22UF,4V,20%,EMPTY,TA
GND                      PC1189           2        Q_CAPP_THLF-270UF,16V,20%,OSCOA
GND                      PC1191           2        Q_CAP_C0402-2.2UF,10V,10%,X6S,A
GND                      PC1192           2        Q_CAP_C0402-2.2UF,10V,10%,X6S,A
GND                      PC1193           2        Q_CAP_C0402-1UF,16V,10%,X6S,CHA
GND                      PC1193_P1_3      2        Q_CAP_0402-3300PF,50V,10%,X7R,A
GND                      PC1194           2        Q_CAP_C0402-1UF,16V,10%,X6S,CHA
GND                      PC1194_P1_4      2        Q_CAP_0402-3300PF,50V,10%,X7R,A
GND                      PC1195_P1_3      2        Q_CAP_C0402-1UF,16V,10%,X6S,CHA
GND                      PC1196           2        Q_CAP_C0402-1UF,16V,10%,X6S,CHA
GND                      PC1196_P1_4      2        Q_CAP_C0402-1UF,16V,10%,X6S,CHA
GND                      PC1199_P1_3      2        Q_CAP_C0805-22UF,16V,20%,X6S,CA
GND                      PC1200_P1_4      2        Q_CAP_C0805-22UF,16V,20%,X6S,CA
GND                      PC1201           2        Q_CAPP_THLF-560UF,2.5V,20%,OSCA
GND                      PC1201_P1_3      2        Q_CAP_C0805-22UF,16V,20%,X6S,CA
GND                      PC1202_P1_4      2        Q_CAP_C0805-22UF,16V,20%,X6S,CA
GND                      PC1203           2        Q_CAPP_THLF-560UF,2.5V,20%,OSCA
GND                      PC1203_P1_4      2        Q_CAP_C0402-100NF,50V,10%,X7R,A
GND                      PC1204           2        Q_CAPP_THLF-560UF,2.5V,20%,OSCA
GND                      PC1204_P1_3      2        Q_CAP_C0402-1UF,16V,10%,X6S,CHA
GND                      PC1205           2        Q_CAPP_SMLF-470UF,2.5V,20%,EMPA
GND                      PC1206           2        Q_CAP_0805-22UF,4V,20%,X6S,TMPA
GND                      PC1206_P1_3      2        Q_CAP_0805-22UF,4V,20%,X6S,TMPA
GND                      PC1207           2        Q_CAP_0805-22UF,4V,20%,X6S,TMPA
GND                      PC1207_P1_4      2        Q_CAP_0805-22UF,4V,20%,X6S,TMPA
GND                      PC1208_P1_3      2        Q_CAP_0805-22UF,4V,20%,X6S,TMPA
GND                      PC1209_P1_4      2        Q_CAP_0805-22UF,4V,20%,X6S,TMPA
GND                      PC1210           2        Q_CAPP_THLF-270UF,16V,20%,OSCOA
GND                      PC1211_P0_1      2        Q_CAP_C0402-2.2UF,10V,10%,X6S,A
GND                      PC1212_P0_2      2        Q_CAP_C0402-2.2UF,10V,10%,X6S,A
GND                      PC1213_P0_3      2        Q_CAP_C0402-2.2UF,10V,10%,EMPTA
GND                      PC1214_P0_4      2        Q_CAP_C0402-2.2UF,10V,10%,EMPTA
GND                      PC1215           2        Q_CAPP_SMLF-100UF,16V,20%,OSCOA
GND                      PC1216           2        Q_CAP_C0805-22UF,16V,20%,X6S,CA
GND                      PC1217           2        Q_CAP_C0805-22UF,16V,20%,X6S,CA
GND                      PC1218           2        Q_CAP_C0805-22UF,16V,20%,X6S,CA
GND                      PC1219           2        Q_CAP_0402-0.1UF,25V,10%,X7R,CA
GND                      PC1224           2        Q_CAP_0402-0.1UF,25V,10%,X7R,CA
GND                      PC1225           2        Q_CAP_0805-47UF,4V,20%,X6S,CH6A
GND                      PC1226           2        Q_CAP_0805-47UF,4V,20%,X6S,CH6A
GND                      PC1227           2        Q_CAPP_THLF-560UF,2.5V,20%,OSCA
GND                      PC1229           2        Q_CAPP_SMLF-470UF,2V,20%,EMPTYA
GND                      PC1230           2        Q_CAPP_THLF-560UF,2.5V,20%,OSCA
GND                      PC1232           2        Q_CAP_C0805-10UF,16V,10%,X6S,CA
GND                      PC1233           2        Q_CAP_C0805-10UF,16V,10%,X6S,CA
GND                      PC1234           2        Q_CAP_C0402-100NF,50V,10%,X7R,A
GND                      PC1236           2        Q_CAP_C0402-100NF,50V,10%,X7R,A
GND                      PC1237           2        Q_CAP_0805-22UF,4V,20%,X6S,TMPA
GND                      PC1238           2        Q_CAP_0805-22UF,4V,20%,X6S,TMPA
GND                      PC1239           2        Q_CAP_0805-22UF,4V,20%,X6S,TMPA
GND                      PC1240           2        Q_CAP_0805-22UF,4V,20%,X6S,TMPA
GND                      PC1241           2        Q_CAP_0805-22UF,4V,20%,X6S,TMPA
GND                      PC1242_P1_1      2        Q_CAP_C0402-2.2UF,10V,10%,X6S,A
GND                      PC1243_P1_2      2        Q_CAP_C0402-2.2UF,10V,10%,X6S,A
GND                      PC1244_P1_3      2        Q_CAP_C0402-2.2UF,10V,10%,X6S,A
GND                      PC1245_P1_4      2        Q_CAP_C0402-2.2UF,10V,10%,X6S,A
GND                      PC1247           2        Q_CAP_C0805-22UF,16V,20%,EMPTYA
GND                      PC1248           2        Q_CAP_C0805-22UF,16V,20%,EMPTYA
GND                      PC1249           2        Q_CAP_0402-0.1UF,25V,10%,EMPTYA
GND                      PC1254           2        Q_CAP_0402-0.1UF,25V,10%,EMPTYA
GND                      PC1255           2        Q_CAP_0805-22UF,4V,20%,EMPTY,TA
GND                      PC1256           2        Q_CAP_0805-22UF,4V,20%,EMPTY,TA
GND                      PC1257           2        Q_CAP_0805-22UF,4V,20%,EMPTY,TA
GND                      PC1258           2        Q_CAPP_THLF-560UF,6.3V,20%,EMPA
GND                      PC1259           2        Q_CAP_C0805-22UF,16V,20%,X6S,CA
GND                      PC1260           2        Q_CAP_C0805-22UF,16V,20%,X6S,CA
GND                      PC1261           2        Q_CAP_C0805-22UF,16V,20%,X6S,CA
GND                      PC1262           2        Q_CAP_0402-0.1UF,25V,10%,X7R,CA
GND                      PC1267           2        Q_CAP_0402-0.1UF,25V,10%,X7R,CA
GND                      PC1268           2        Q_CAP_0805-22UF,4V,20%,X6S,TMPA
GND                      PC1269           2        Q_CAP_0805-22UF,4V,20%,X6S,TMPA
GND                      PC1270           2        Q_CAP_0805-22UF,4V,20%,X6S,TMPA
GND                      PC1271           2        Q_CAP_0402-470PF,50V,10%,X7R,TA
GND                      PC1272           2        Q_CAP_C0805-22UF,16V,20%,X6S,CA
GND                      PC1273           2        Q_CAP_C0805-22UF,16V,20%,X6S,CA
GND                      PC1274           2        Q_CAP_C0402-100NF,50V,10%,X7R,A
GND                      PC1276           2        Q_CAP_C0402-100NF,50V,10%,X7R,A
GND                      PC1277           2        Q_CAP_0805-22UF,4V,20%,X6S,TMPA
GND                      PC1278           2        Q_CAP_0805-22UF,4V,20%,X6S,TMPA
GND                      PC1279           2        Q_CAP_0805-22UF,4V,20%,X6S,TMPA
GND                      PC1280           2        Q_CAP_C0805-22UF,16V,20%,X6S,CA
GND                      PC1281           2        Q_CAP_C0805-22UF,16V,20%,X6S,CA
GND                      PC1282           2        Q_CAP_C0402-100NF,50V,10%,X7R,A
GND                      PC1284           2        Q_CAP_C0402-100NF,50V,10%,X7R,A
GND                      PC1285           2        Q_CAP_0805-22UF,4V,20%,X6S,TMPA
GND                      PC1286           2        Q_CAP_0805-22UF,4V,20%,X6S,TMPA
GND                      PC1287           2        Q_CAP_0805-22UF,4V,20%,X6S,TMPA
GND                      PC1289           2        Q_CAP_C0402-1UF,16V,10%,X6S,CHA
GND                      PC1292           2        Q_CAP_0402-470PF,50V,10%,X7R,TA
GND                      PC1336           2        Q_CAP_C0402-10UF,6.3V,20%,X6S,A
GND                      PC1337           2        Q_CAP_0402-0.1UF,25V,10%,X7R,CA
GND                      PC1338           1        Q_CAP_0402-0.1UF,25V,10%,X7R,CA
GND                      PC1339           1        Q_CAP_0402-0.1UF,25V,10%,X7R,CA
GND                      PC1340           1        Q_CAP_0402-0.1UF,25V,10%,X7R,CA
GND                      PC1341           1        Q_CAP_0402-0.1UF,25V,10%,X7R,CA
GND                      PC1342           1        Q_CAP_0402-0.1UF,25V,10%,X7R,CA
GND                      PC1343           1        Q_CAP_0402-0.1UF,25V,10%,X7R,CA
GND                      PC1344           1        Q_CAP_0402-0.1UF,25V,10%,X7R,CA
GND                      PC1345           1        Q_CAP_0402-0.1UF,25V,10%,X7R,CA
GND                      PC1346           1        Q_CAP_0402-0.1UF,25V,10%,X7R,CA
GND                      PC1347           1        Q_CAP_0402-0.1UF,25V,10%,X7R,CA
GND                      PC1348           1        Q_CAP_0402-0.1UF,25V,10%,X7R,CA
GND                      PC1349           1        Q_CAP_0402-0.1UF,25V,10%,X7R,CA
GND                      PC1350           1        Q_CAP_0402-0.1UF,25V,10%,X7R,CA
GND                      PC1351           1        Q_CAP_0402-0.1UF,25V,10%,EMPTYA
GND                      PC1352           1        Q_CAP_0402-0.1UF,25V,10%,EMPTYA
GND                      PC1354           1        Q_CAP_0402-0.1UF,25V,10%,X7R,CA
GND                      PC1355           1        Q_CAP_0402-0.1UF,25V,10%,X7R,CA
GND                      PC1356           1        Q_CAP_0402-0.1UF,25V,10%,X7R,CA
GND                      PC1358           1        Q_CAP_0402-0.1UF,25V,10%,X7R,CA
GND                      PC1359           1        Q_CAP_0402-0.1UF,25V,10%,X7R,CA
GND                      PC1360           1        Q_CAP_0402-0.1UF,25V,10%,X7R,CA
GND                      PC1361           1        Q_CAP_0402-0.1UF,25V,10%,X7R,CA
GND                      PC1362           1        Q_CAP_0402-0.1UF,25V,10%,X7R,CA
GND                      PC1363           1        Q_CAP_0402-0.1UF,25V,10%,X7R,CA
GND                      PC1364           1        Q_CAP_0402-0.1UF,25V,10%,X7R,CA
GND                      PC1365           1        Q_CAP_0402-0.1UF,25V,10%,X7R,CA
GND                      PC1366           1        Q_CAP_0402-0.1UF,25V,10%,X7R,CA
GND                      PC1367           1        Q_CAP_0402-0.1UF,25V,10%,X7R,CA
GND                      PC1368           1        Q_CAP_0402-0.1UF,25V,10%,X7R,CA
GND                      PC1369           1        Q_CAP_0402-0.1UF,25V,10%,X7R,CA
GND                      PC1370           1        Q_CAP_0402-0.1UF,25V,10%,X7R,CA
GND                      PC1371           1        Q_CAP_0402-0.1UF,25V,10%,X7R,CA
GND                      PC1372           2        Q_CAP_C0402-1UF,16V,10%,X6S,CHA
GND                      PC1573           2        Q_CAPP_SMLF-330UF,2V,35%,SPCAPA
GND                      PC1574           2        Q_CAPP_THLF-560UF,2.5V,20%,OSCA
GND                      PC1575           2        Q_CAPP_SMLF-330UF,2V,35%,SPCAPA
GND                      PC1576           2        Q_CAPP_THLF-560UF,2.5V,20%,OSCA
GND                      PC1579           2        Q_CAPP_THLF-560UF,2.5V,20%,OSCA
GND                      PC1588           2        Q_CAPP_SMLF-330UF,2V,35%,SPCAPA
GND                      PC1593           2        Q_CAPP_THLF-560UF,2.5V,20%,OSCA
GND                      PC1594           2        Q_CAPP_SMLF-330UF,2V,35%,SPCAPA
GND                      PC1595           2        Q_CAPP_THLF-560UF,2.5V,20%,OSCA
GND                      PC1596           2        Q_CAPP_THLF-560UF,2.5V,20%,OSCA
GND                      PC1642           2        Q_CAP_C0402-1UF,25V,10%,X6S,CHA
GND                      PC1644           2        Q_CAPP_THLF-560UF,2.5V,20%,OSCA
GND                      PC1645           2        Q_CAPP_THLF-560UF,2.5V,20%,OSCA
GND                      PC1771           2        Q_CAPP_THLF-560UF,6.3V,20%,OSCA
GND                      PC1845           2        Q_CAPP_SMLF-220UF,6.3V,20%,ALUA
GND                      PC1846           2        Q_CAP_0402-0.1UF,25V,10%,X7R,CA
GND                      PC1848           2        Q_CAP_C0402-1UF,25V,10%,X6S,CHA
GND                      PC1849           2        Q_CAP_C0805-22UF,16V,20%,X6S,CA
GND                      PC1850           2        Q_CAP_C0805-22UF,16V,20%,X6S,CA
GND                      PC1852           2        Q_CAP_0402-0.1UF,25V,10%,X7R,CA
GND                      PC1853           2        Q_CAP_0402-0.1UF,25V,10%,X7R,CA
GND                      PC1855           2        Q_CAP_C0805-22UF,10V,20%,X6S,CA
GND                      PC1856           2        Q_CAP_C0805-22UF,10V,20%,X6S,CA
GND                      PC1866           2        Q_CAPP_THLF-560UF,6.3V,20%,OSCA
GND                      PC1867           2        Q_CAPP_THLF-560UF,6.3V,20%,OSCA
GND                      PC1868           2        Q_CAP_C0805-22UF,10V,20%,X6S,CA
GND                      PC1869           2        Q_CAP_0402-0.1UF,25V,10%,X7R,CA
GND                      PC1870           2        Q_CAP_0402-0.1UF,25V,10%,EMPTYA
GND                      PC1898           2        Q_CAP_C0805-22UF,16V,20%,X6S,CA
GND                      PC189_P0_1       2        Q_CAP_0402-3300PF,50V,10%,X7R,A
GND                      PC1900           2        Q_CAPP_SMLF-470UF,2.5V,20%,SPCA
GND                      PC190_P0_2       2        Q_CAP_0402-3300PF,50V,10%,X7R,A
GND                      PC1910           2        Q_CAPP_SMLF-330UF,2V,35%,SPCAPA
GND                      PC191_P0_1       2        Q_CAP_C0402-1UF,16V,10%,X6S,CHA
GND                      PC1920           2        Q_CAPP_SMLF-470UF,2.5V,20%,EMPA
GND                      PC192_P0_2       2        Q_CAP_C0402-1UF,16V,10%,X6S,CHA
GND                      PC1930           2        Q_CAPP_SMLF-470UF,2.5V,20%,SPCA
GND                      PC1940           2        Q_CAPP_SMLF-330UF,2V,35%,SPCAPA
GND                      PC195_P0_1       2        Q_CAP_C0805-22UF,16V,20%,X6S,CA
GND                      PC196_P0_2       2        Q_CAP_C0805-22UF,16V,20%,X6S,CA
GND                      PC197_P0_1       2        Q_CAP_C0805-22UF,16V,20%,X6S,CA
GND                      PC198_P0_2       2        Q_CAP_C0805-22UF,16V,20%,X6S,CA
GND                      PC1990           2        Q_CAPP_SMLF-470UF,2.5V,20%,EMPA
GND                      PC199_P0_1       2        Q_CAP_C0402-100NF,50V,10%,X7R,A
GND                      PC2000           2        Q_CAP_0402-0.022UF,16V,10%,X7RA
GND                      PC2001           2        Q_CAP_0402-0.022UF,16V,10%,EMPA
GND                      PC2002           2        Q_CAP_0402-0.022UF,16V,10%,X7RA
GND                      PC202_P0_1       2        Q_CAP_0805-22UF,4V,20%,X6S,TMPA
GND                      PC203_P0_2       2        Q_CAP_0805-22UF,4V,20%,X6S,TMPA
GND                      PC204_P0_1       2        Q_CAP_0805-22UF,4V,20%,X6S,TMPA
GND                      PC205_P0_2       2        Q_CAP_0805-22UF,4V,20%,X6S,TMPA
GND                      PC2170           2        Q_CAPP_SMLF-470UF,2.5V,20%,EMPA
GND                      PC2171           2        Q_CAPP_SMLF-470UF,2.5V,20%,EMPA
GND                      PC2172           2        Q_CAPP_SMLF-470UF,2.5V,20%,SPCA
GND                      PC2180           2        Q_CAPP_THLF-560UF,2.5V,20%,OSCA
GND                      PC2199           2        Q_CAPP_THLF-560UF,2.5V,20%,OSCA
GND                      PC2221           2        Q_CAP_C0402-1UF,25V,10%,X6S,CHA
GND                      PC2222           2        Q_CAP_C0402-1UF,25V,10%,X6S,CHA
GND                      PC2287           2        Q_CAP_0402-0.01UF,25V,10%,X7R,A
GND                      PC228_P0_8       2        Q_CAP_C0402-2.2UF,10V,10%,X6S,A
GND                      PC229_P0_7       2        Q_CAP_C0402-2.2UF,10V,10%,X6S,A
GND                      PC230_P0_8       2        Q_CAP_0402-3300PF,50V,10%,X7R,A
GND                      PC231_P0_7       2        Q_CAP_0402-3300PF,50V,10%,X7R,A
GND                      PC232_P0_8       2        Q_CAP_C0402-1UF,16V,10%,X6S,CHA
GND                      PC2336           2        Q_CAPP_SMLF-470UF,2.5V,20%,EMPA
GND                      PC233_P0_7       2        Q_CAP_C0402-1UF,16V,10%,X6S,CHA
GND                      PC236_P0_8       2        Q_CAP_C0805-22UF,16V,20%,X6S,CA
GND                      PC237_P0_7       2        Q_CAP_C0805-22UF,16V,20%,X6S,CA
GND                      PC238_P0_8       2        Q_CAP_C0805-22UF,16V,20%,X6S,CA
GND                      PC239_P0_7       2        Q_CAP_C0805-22UF,16V,20%,X6S,CA
GND                      PC240_P0_8       2        Q_CAP_C0805-22UF,16V,20%,X6S,CA
GND                      PC241_P0_7       2        Q_CAP_C0805-22UF,16V,20%,X6S,CA
GND                      PC242_P0_8       2        Q_CAP_C0402-1UF,16V,10%,X6S,CHA
GND                      PC243_P0_7       2        Q_CAP_C0402-1UF,16V,10%,X6S,CHA
GND                      PC244_P0_8       2        Q_CAP_0805-22UF,4V,20%,X6S,TMPA
GND                      PC245_P0_7       2        Q_CAP_0805-22UF,4V,20%,X6S,TMPA
GND                      PC246_P0_8       2        Q_CAP_0805-22UF,4V,20%,X6S,TMPA
GND                      PC247_P0_7       2        Q_CAP_0805-22UF,4V,20%,X6S,TMPA
GND                      PC248            2        Q_CAP_C0402-2.2UF,10V,10%,X6S,A
GND                      PC249            2        Q_CAP_C0402-2.2UF,10V,10%,X6S,A
GND                      PC250_P0_6       2        Q_CAP_C0402-2.2UF,10V,10%,X6S,A
GND                      PC251_P0_5       2        Q_CAP_C0402-2.2UF,10V,10%,X6S,A
GND                      PC252_P0_6       2        Q_CAP_0402-3300PF,50V,10%,X7R,A
GND                      PC253_P0_5       2        Q_CAP_0402-3300PF,50V,10%,X7R,A
GND                      PC254_P0_6       2        Q_CAP_C0402-1UF,16V,10%,X6S,CHA
GND                      PC255_P0_5       2        Q_CAP_C0402-1UF,16V,10%,X6S,CHA
GND                      PC258_P0_6       2        Q_CAP_C0805-22UF,16V,20%,X6S,CA
GND                      PC259_P0_5       2        Q_CAP_C0805-22UF,16V,20%,X6S,CA
GND                      PC260_P0_6       2        Q_CAP_C0805-22UF,16V,20%,X6S,CA
GND                      PC261_P0_5       2        Q_CAP_C0805-22UF,16V,20%,X6S,CA
GND                      PC262_P0_6       2        Q_CAP_C0805-22UF,16V,20%,X6S,CA
GND                      PC263_P0_5       2        Q_CAP_C0805-22UF,16V,20%,X6S,CA
GND                      PC266_P0_6       2        Q_CAP_0805-22UF,4V,20%,X6S,TMPA
GND                      PC267_P0_5       2        Q_CAP_0805-22UF,4V,20%,X6S,TMPA
GND                      PC268_P0_6       2        Q_CAP_0805-22UF,4V,20%,X6S,TMPA
GND                      PC269_P0_5       2        Q_CAP_0805-22UF,4V,20%,X6S,TMPA
GND                      PC27             2        Q_CAP_0402-3300PF,50V,10%,X7R,A
GND                      PC270            2        Q_CAP_C0402-2.2UF,10V,10%,X6S,A
GND                      PC271            2        Q_CAP_C0402-2.2UF,10V,10%,X6S,A
GND                      PC272_P0_4       2        Q_CAP_C0402-2.2UF,10V,10%,X6S,A
GND                      PC273_P0_3       2        Q_CAP_C0402-2.2UF,10V,10%,X6S,A
GND                      PC274_P0_4       2        Q_CAP_0402-3300PF,50V,10%,X7R,A
GND                      PC275_P0_3       2        Q_CAP_0402-3300PF,50V,10%,X7R,A
GND                      PC276_P0_4       2        Q_CAP_C0402-1UF,16V,10%,X6S,CHA
GND                      PC277_P0_3       2        Q_CAP_C0402-1UF,16V,10%,X6S,CHA
GND                      PC28             2        Q_CAP_0402-3300PF,50V,10%,X7R,A
GND                      PC280_P0_4       2        Q_CAP_C0805-22UF,16V,20%,X6S,CA
GND                      PC281_P0_3       2        Q_CAP_C0805-22UF,16V,20%,X6S,CA
GND                      PC282_P0_4       2        Q_CAP_C0805-22UF,16V,20%,X6S,CA
GND                      PC283_P0_3       2        Q_CAP_C0805-22UF,16V,20%,X6S,CA
GND                      PC284_P0_4       2        Q_CAP_C0805-22UF,16V,20%,X6S,CA
GND                      PC285_P0_3       2        Q_CAP_C0805-22UF,16V,20%,X6S,CA
GND                      PC288_P0_4       2        Q_CAP_0805-22UF,4V,20%,X6S,TMPA
GND                      PC289_P0_3       2        Q_CAP_0805-22UF,4V,20%,X6S,TMPA
GND                      PC290_P0_4       2        Q_CAP_0805-22UF,4V,20%,X6S,TMPA
GND                      PC291_P0_3       2        Q_CAP_0805-22UF,4V,20%,X6S,TMPA
GND                      PC292            2        Q_CAP_C0402-2.2UF,10V,10%,X6S,A
GND                      PC293            2        Q_CAP_C0402-2.2UF,10V,10%,X6S,A
GND                      PC294_P0_2       2        Q_CAP_C0402-2.2UF,10V,10%,X6S,A
GND                      PC295_P0_1       2        Q_CAP_C0402-2.2UF,10V,10%,X6S,A
GND                      PC296_P0_2       2        Q_CAP_0402-3300PF,50V,10%,X7R,A
GND                      PC297_P0_1       2        Q_CAP_0402-3300PF,50V,10%,X7R,A
GND                      PC298_P0_2       2        Q_CAP_C0402-1UF,16V,10%,X6S,CHA
GND                      PC299_P0_1       2        Q_CAP_C0402-1UF,16V,10%,X6S,CHA
GND                      PC302_P0_2       2        Q_CAP_C0805-22UF,16V,20%,X6S,CA
GND                      PC303_P0_1       2        Q_CAP_C0805-22UF,16V,20%,X6S,CA
GND                      PC304_P0_2       2        Q_CAP_C0805-22UF,16V,20%,X6S,CA
GND                      PC305_P0_1       2        Q_CAP_C0805-22UF,16V,20%,X6S,CA
GND                      PC306_P0_2       2        Q_CAP_C0805-22UF,16V,20%,X6S,CA
GND                      PC307_P0_1       2        Q_CAP_C0805-22UF,16V,20%,X6S,CA
GND                      PC308_P0_1       2        Q_CAP_C0402-100NF,50V,10%,X7R,A
GND                      PC310_P0_1       2        Q_CAP_C0402-1UF,16V,10%,X6S,CHA
GND                      PC311_P0_2       2        Q_CAP_0805-22UF,4V,20%,X6S,TMPA
GND                      PC312_P0_1       2        Q_CAP_0805-22UF,4V,20%,X6S,TMPA
GND                      PC313_P0_2       2        Q_CAP_0805-22UF,4V,20%,X6S,TMPA
GND                      PC314_P0_1       2        Q_CAP_0805-22UF,4V,20%,X6S,TMPA
GND                      PC315            2        Q_CAPP_THLF-270UF,16V,20%,OSCOA
GND                      PC316            2        Q_CAPP_THLF-560UF,2.5V,20%,OSCA
GND                      PC318            2        Q_CAPP_THLF-270UF,16V,20%,OSCOA
GND                      PC319            2        Q_CAPP_THLF-560UF,2.5V,20%,OSCA
GND                      PC321            2        Q_CAPP_THLF-270UF,16V,20%,OSCOA
GND                      PC322            2        Q_CAPP_THLF-560UF,2.5V,20%,OSCA
GND                      PC323            2        Q_CAPP_SMLF-470UF,2.5V,20%,EMPA
GND                      PC324            2        Q_CAPP_THLF-270UF,16V,20%,OSCOA
GND                      PC325            2        Q_CAPP_THLF-560UF,2.5V,20%,OSCA
GND                      PC326            2        Q_CAPP_SMLF-470UF,2.5V,20%,EMPA
GND                      PC327            2        Q_CAP_C0603-10UF,4V,20%,EMPTY,A
GND                      PC328            2        Q_CAP_C0402-100NF,50V,10%,X7R,A
GND                      PC329            2        Q_CAP_0402-0.1UF,25V,10%,EMPTYA
GND                      PC330            2        Q_CAP_0402-0.1UF,25V,10%,X7R,CA
GND                      PC332            2        Q_CAP_0402-1000PF,50V,5%,X7R,TA
GND                      PC333            2        Q_CAP_0402-1000PF,50V,5%,EMPTYA
GND                      PC334            2        Q_CAP_C0402-100NF,50V,10%,EMPTA
GND                      PC335            2        Q_CAP_0402-4.7UF,6.3V,20%,X6S,A
GND                      PC336            2        Q_CAP_0402-470PF,50V,10%,X7R,TA
GND                      PC337            2        Q_CAP_C0402-1UF,16V,10%,X6S,CHA
GND                      PC373            2        Q_CAP_C0402-2.2UF,10V,10%,X6S,A
GND                      PC374            2        Q_CAP_0402-3300PF,50V,10%,X7R,A
GND                      PC375            2        Q_CAP_C0402-1UF,16V,10%,X6S,CHA
GND                      PC377            2        Q_CAP_C0805-22UF,16V,20%,X6S,CA
GND                      PC378            2        Q_CAP_C0805-22UF,16V,20%,X6S,CA
GND                      PC379            2        Q_CAP_C0402-100NF,50V,10%,X7R,A
GND                      PC381            2        Q_CAP_0805-22UF,4V,20%,X6S,TMPA
GND                      PC382            2        Q_CAP_0805-22UF,4V,20%,X6S,TMPA
GND                      PC384            2        Q_CAPP_THLF-560UF,2.5V,20%,OSCA
GND                      PC385            2        Q_CAPP_THLF-560UF,2.5V,20%,OSCA
GND                      PC386            2        Q_CAP_0402-0.1UF,25V,10%,X7R,CA
GND                      PC388            2        Q_CAP_0402-1000PF,50V,5%,EMPTYA
GND                      PC390            2        Q_CAP_0402-0.1UF,25V,10%,X7R,CA
GND                      PC391            2        Q_CAP_C0402-100NF,50V,10%,EMPTA
GND                      PC392            2        Q_CAP_0402-4.7UF,6.3V,20%,X6S,A
GND                      PC393            2        Q_CAP_0402-470PF,50V,10%,X7R,TA
GND                      PC394            2        Q_CAP_C0402-1UF,16V,10%,X6S,CHA
GND                      PC395            2        Q_CAP_C0402-2.2UF,10V,10%,X6S,A
GND                      PC396            2        Q_CAP_C0402-2.2UF,10V,10%,X6S,A
GND                      PC2643           2        Q_CAP_C0402-1UF,25V,10%,EMPTY,A
GND                      PC2645           2        Q_CAPP_SMLF-470UF,2.5V,20%,EMPA
GND                      PC397_P1_1       2        Q_CAP_0402-3300PF,50V,10%,X7R,A
GND                      PC398_P1_2       2        Q_CAP_0402-3300PF,50V,10%,X7R,A
GND                      PC399_P1_1       2        Q_CAP_C0402-1UF,16V,10%,X6S,CHA
GND                      PC400_P1_2       2        Q_CAP_C0402-1UF,16V,10%,X6S,CHA
GND                      PC403_P1_1       2        Q_CAP_C0805-22UF,16V,20%,X6S,CA
GND                      PC404_P1_2       2        Q_CAP_C0805-22UF,16V,20%,X6S,CA
GND                      PC405_P1_1       2        Q_CAP_C0805-22UF,16V,20%,X6S,CA
GND                      PC406_P1_2       2        Q_CAP_C0805-22UF,16V,20%,X6S,CA
GND                      PC408_P1_2       2        Q_CAP_C0402-1UF,16V,10%,X6S,CHA
GND                      PC410_P1_1       2        Q_CAP_0805-22UF,4V,20%,X6S,TMPA
GND                      PC411_P1_2       2        Q_CAP_0805-22UF,4V,20%,X6S,TMPA
GND                      PC412_P1_1       2        Q_CAP_0805-22UF,4V,20%,X6S,TMPA
GND                      PC413_P1_2       2        Q_CAP_0805-22UF,4V,20%,X6S,TMPA
GND                      PC414            2        Q_CAPP_THLF-560UF,2.5V,20%,OSCA
GND                      PC415            2        Q_CAPP_THLF-560UF,2.5V,20%,OSCA
GND                      PC416            2        Q_CAPP_THLF-560UF,2.5V,20%,OSCA
GND                      PC417            2        Q_CAPP_THLF-270UF,16V,20%,OSCOA
GND                      PC418            2        Q_CAPP_SMLF-470UF,2.5V,20%,SPCA
GND                      PC420            2        Q_CAP_0402-1000PF,50V,5%,X7R,TA
GND                      PC421            2        Q_CAP_0402-1000PF,50V,5%,EMPTYA
GND                      PC428            2        Q_CAP_C0402-2.2UF,10V,10%,X6S,A
GND                      PC429            2        Q_CAP_0402-3300PF,50V,10%,X7R,A
GND                      PC430            2        Q_CAP_C0402-1UF,16V,10%,X6S,CHA
GND                      PC432            2        Q_CAP_C0805-22UF,16V,20%,X6S,CA
GND                      PC433            2        Q_CAP_C0805-22UF,16V,20%,X6S,CA
GND                      PC434            2        Q_CAP_C0402-100NF,50V,10%,X7R,A
GND                      PC435            2        Q_CAP_0805-22UF,4V,20%,X6S,TMPA
GND                      PC437            2        Q_CAP_0805-22UF,4V,20%,X6S,TMPA
GND                      PC440            2        Q_CAP_C0402-2.2UF,10V,10%,X6S,A
GND                      PC441            2        Q_CAP_C0402-2.2UF,10V,10%,X6S,A
GND                      PC442_P1_1       2        Q_CAP_0402-3300PF,50V,10%,X7R,A
GND                      PC443_P1_2       2        Q_CAP_0402-3300PF,50V,10%,X7R,A
GND                      PC444_P1_1       2        Q_CAP_C0402-1UF,16V,10%,X6S,CHA
GND                      PC445_P1_2       2        Q_CAP_C0402-1UF,16V,10%,X6S,CHA
GND                      PC448_P1_1       2        Q_CAP_C0805-22UF,16V,20%,X6S,CA
GND                      PC449_P1_2       2        Q_CAP_C0805-22UF,16V,20%,X6S,CA
GND                      PC450_P1_1       2        Q_CAP_C0805-22UF,16V,20%,X6S,CA
GND                      PC451_P1_2       2        Q_CAP_C0805-22UF,16V,20%,X6S,CA
GND                      PC452_P1_1       2        Q_CAP_C0402-100NF,50V,10%,X7R,A
GND                      PC455_P1_1       2        Q_CAP_0805-22UF,4V,20%,X6S,TMPA
GND                      PC456_P1_2       2        Q_CAP_0805-22UF,4V,20%,X6S,TMPA
GND                      PC457_P1_1       2        Q_CAP_0805-22UF,4V,20%,X6S,TMPA
GND                      PC458_P1_2       2        Q_CAP_0805-22UF,4V,20%,X6S,TMPA
GND                      PC460            2        Q_CAPP_THLF-270UF,16V,20%,OSCOA
GND                      PC461            2        Q_CAPP_THLF-270UF,16V,20%,OSCOA
GND                      PC467            2        Q_CAP_0402-0.1UF,25V,10%,EMPTYA
GND                      PC470            2        Q_CAP_0402-1000PF,50V,5%,X7R,TA
GND                      PC471            2        Q_CAP_0402-1000PF,50V,5%,EMPTYA
GND                      PC472            2        Q_CAP_0402-1000PF,50V,5%,X7R,TA
GND                      PC473            2        Q_CAP_0402-1000PF,50V,5%,EMPTYA
GND                      PC474            2        Q_CAP_0402-0.1UF,25V,10%,X7R,CA
GND                      PC475            2        Q_CAP_0402-470PF,50V,10%,X7R,TA
GND                      PC476            2        Q_CAP_C0402-100NF,50V,10%,EMPTA
GND                      PC477            2        Q_CAP_0402-4.7UF,6.3V,20%,X6S,A
GND                      PC478            2        Q_CAP_C0402-1UF,16V,10%,X6S,CHA
GND                      PC479            2        Q_CAP_C0402-2.2UF,10V,10%,X6S,A
GND                      PC480            2        Q_CAP_C0402-2.2UF,10V,10%,X6S,A
GND                      PC481_P1_8       2        Q_CAP_C0402-2.2UF,10V,10%,X6S,A
GND                      PC482_P1_7       2        Q_CAP_C0402-2.2UF,10V,10%,X6S,A
GND                      PC483_P1_8       2        Q_CAP_0402-3300PF,50V,10%,X7R,A
GND                      PC484_P1_7       2        Q_CAP_0402-3300PF,50V,10%,X7R,A
GND                      PC485_P1_8       2        Q_CAP_C0402-1UF,16V,10%,X6S,CHA
GND                      PC486_P1_7       2        Q_CAP_C0402-1UF,16V,10%,X6S,CHA
GND                      PC489_P1_8       2        Q_CAP_C0805-22UF,16V,20%,X6S,CA
GND                      PC490_P1_7       2        Q_CAP_C0805-22UF,16V,20%,X6S,CA
GND                      PC491_P1_8       2        Q_CAP_C0805-22UF,16V,20%,X6S,CA
GND                      PC492_P1_7       2        Q_CAP_C0805-22UF,16V,20%,X6S,CA
GND                      PC493_P1_8       2        Q_CAP_C0805-22UF,16V,20%,X6S,CA
GND                      PC494_P1_7       2        Q_CAP_C0805-22UF,16V,20%,X6S,CA
GND                      PC495_P1_8       2        Q_CAP_C0402-1UF,16V,10%,X6S,CHA
GND                      PC496_P1_7       2        Q_CAP_C0402-1UF,16V,10%,X6S,CHA
GND                      PC497_P1_8       2        Q_CAP_0805-22UF,4V,20%,X6S,TMPA
GND                      PC498_P1_7       2        Q_CAP_0805-22UF,4V,20%,X6S,TMPA
GND                      PC499_P1_8       2        Q_CAP_0805-22UF,4V,20%,X6S,TMPA
GND                      PC500_P1_7       2        Q_CAP_0805-22UF,4V,20%,X6S,TMPA
GND                      PC501            2        Q_CAP_C0402-2.2UF,10V,10%,X6S,A
GND                      PC502            2        Q_CAP_C0402-2.2UF,10V,10%,X6S,A
GND                      PC503_P1_6       2        Q_CAP_C0402-2.2UF,10V,10%,X6S,A
GND                      PC504_P1_5       2        Q_CAP_C0402-2.2UF,10V,10%,X6S,A
GND                      PC505_P1_6       2        Q_CAP_0402-3300PF,50V,10%,X7R,A
GND                      PC506_P1_5       2        Q_CAP_0402-3300PF,50V,10%,X7R,A
GND                      PC507_P1_6       2        Q_CAP_C0402-1UF,16V,10%,X6S,CHA
GND                      PC508_P1_5       2        Q_CAP_C0402-1UF,16V,10%,X6S,CHA
GND                      PC511_P1_6       2        Q_CAP_C0805-22UF,16V,20%,X6S,CA
GND                      PC512_P1_5       2        Q_CAP_C0805-22UF,16V,20%,X6S,CA
GND                      PC513_P1_6       2        Q_CAP_C0805-22UF,16V,20%,X6S,CA
GND                      PC514_P1_5       2        Q_CAP_C0805-22UF,16V,20%,X6S,CA
GND                      PC515_P1_6       2        Q_CAP_C0805-22UF,16V,20%,X6S,CA
GND                      PC516_P1_5       2        Q_CAP_C0805-22UF,16V,20%,X6S,CA
GND                      PC519_P1_6       2        Q_CAP_0805-22UF,4V,20%,X6S,TMPA
GND                      PC520_P1_5       2        Q_CAP_0805-22UF,4V,20%,X6S,TMPA
GND                      PC521_P1_6       2        Q_CAP_0805-22UF,4V,20%,X6S,TMPA
GND                      PC522_P1_5       2        Q_CAP_0805-22UF,4V,20%,X6S,TMPA
GND                      PC523            2        Q_CAP_C0402-2.2UF,10V,10%,X6S,A
GND                      PC524            2        Q_CAP_C0402-2.2UF,10V,10%,X6S,A
GND                      PC525_P1_4       2        Q_CAP_C0402-2.2UF,10V,10%,X6S,A
GND                      PC526_P1_3       2        Q_CAP_C0402-2.2UF,10V,10%,X6S,A
GND                      PC527_P1_4       2        Q_CAP_0402-3300PF,50V,10%,X7R,A
GND                      PC528_P1_3       2        Q_CAP_0402-3300PF,50V,10%,X7R,A
GND                      PC529_P1_4       2        Q_CAP_C0402-1UF,16V,10%,X6S,CHA
GND                      PC530_P1_3       2        Q_CAP_C0402-1UF,16V,10%,X6S,CHA
GND                      PC533_P1_4       2        Q_CAP_C0805-22UF,16V,20%,X6S,CA
GND                      PC534_P1_3       2        Q_CAP_C0805-22UF,16V,20%,X6S,CA
GND                      PC535_P1_4       2        Q_CAP_C0805-22UF,16V,20%,X6S,CA
GND                      PC536_P1_3       2        Q_CAP_C0805-22UF,16V,20%,X6S,CA
GND                      PC537_P1_4       2        Q_CAP_C0805-22UF,16V,20%,X6S,CA
GND                      PC538_P1_3       2        Q_CAP_C0805-22UF,16V,20%,X6S,CA
GND                      PC541_P1_4       2        Q_CAP_0805-22UF,4V,20%,X6S,TMPA
GND                      PC542_P1_3       2        Q_CAP_0805-22UF,4V,20%,X6S,TMPA
GND                      PC543_P1_4       2        Q_CAP_0805-22UF,4V,20%,X6S,TMPA
GND                      PC544_P1_3       2        Q_CAP_0805-22UF,4V,20%,X6S,TMPA
GND                      PC545            2        Q_CAP_C0603-10UF,4V,20%,EMPTY,A
GND                      PC546            2        Q_CAP_C0402-100NF,50V,10%,X7R,A
GND                      PC547            2        Q_CAP_0402-0.1UF,25V,10%,EMPTYA
GND                      PC548            2        Q_CAP_0402-0.1UF,25V,10%,X7R,CA
GND                      PC550            2        Q_CAP_0402-1000PF,50V,5%,X7R,TA
GND                      PC551            2        Q_CAP_0402-1000PF,50V,5%,EMPTYA
GND                      PC552            2        Q_CAP_C0402-100NF,50V,10%,EMPTA
GND                      PC553            2        Q_CAP_0402-4.7UF,6.3V,20%,X6S,A
GND                      PC554            2        Q_CAP_0402-470PF,50V,10%,X7R,TA
GND                      PC555            2        Q_CAP_C0402-1UF,16V,10%,X6S,CHA
GND                      PC556            2        Q_CAP_C0402-2.2UF,10V,10%,X6S,A
GND                      PC557            2        Q_CAP_C0402-2.2UF,10V,10%,X6S,A
GND                      PC558_P1_2       2        Q_CAP_C0402-2.2UF,10V,10%,X6S,A
GND                      PC559_P1_1       2        Q_CAP_C0402-2.2UF,10V,10%,X6S,A
GND                      PC560_P1_2       2        Q_CAP_0402-3300PF,50V,10%,X7R,A
GND                      PC561_P1_1       2        Q_CAP_0402-3300PF,50V,10%,X7R,A
GND                      PC562_P1_2       2        Q_CAP_C0402-1UF,16V,10%,X6S,CHA
GND                      PC563_P1_1       2        Q_CAP_C0402-1UF,16V,10%,X6S,CHA
GND                      PC566            2        Q_CAPP_SMLF-100UF,16V,20%,OSCOA
GND                      PC566_P1_2       2        Q_CAP_C0805-22UF,16V,20%,X6S,CA
GND                      PC567            2        Q_CAP_C0805-22UF,16V,20%,X6S,CA
GND                      PC567_P1_1       2        Q_CAP_C0805-22UF,16V,20%,X6S,CA
GND                      PC568_P1_2       2        Q_CAP_C0805-22UF,16V,20%,X6S,CA
GND                      PC569_P1_1       2        Q_CAP_C0805-22UF,16V,20%,X6S,CA
GND                      PC570            2        Q_CAP_C0805-22UF,16V,20%,X6S,CA
GND                      PC570_P1_2       2        Q_CAP_C0805-22UF,16V,20%,X6S,CA
GND                      PC571            2        Q_CAP_C0805-22UF,16V,20%,X6S,CA
GND                      PC571_P1_1       2        Q_CAP_C0805-22UF,16V,20%,X6S,CA
GND                      PC572_P1_1       2        Q_CAP_C0402-100NF,50V,10%,X7R,A
GND                      PC574_P1_1       2        Q_CAP_C0402-1UF,16V,10%,X6S,CHA
GND                      PC575_P1_2       2        Q_CAP_0805-22UF,4V,20%,X6S,TMPA
GND                      PC576            2        Q_CAP_C0805-22UF,16V,20%,X6S,CA
GND                      PC576_P1_1       2        Q_CAP_0805-22UF,4V,20%,X6S,TMPA
GND                      PC577            2        Q_CAP_0402-0.1UF,25V,10%,X7R,CA
GND                      PC577_P1_2       2        Q_CAP_0805-22UF,4V,20%,X6S,TMPA
GND                      PC578_P1_1       2        Q_CAP_0805-22UF,4V,20%,X6S,TMPA
GND                      PC579            2        Q_CAPP_THLF-270UF,16V,20%,OSCOA
GND                      PC580            2        Q_CAPP_THLF-560UF,2.5V,20%,OSCA
GND                      PC581            2        Q_CAP_C0603-4.7UF,16V,10%,X6S,A
GND                      PC582            2        Q_CAPP_THLF-270UF,16V,20%,OSCOA
GND                      PC583            2        Q_CAPP_THLF-560UF,2.5V,20%,OSCA
GND                      PC585            2        Q_CAPP_THLF-270UF,16V,20%,OSCOA
GND                      PC586            2        Q_CAPP_THLF-560UF,2.5V,20%,OSCA
GND                      PC587            2        Q_CAPP_SMLF-470UF,2.5V,20%,EMPA
GND                      PC588            2        Q_CAPP_THLF-270UF,16V,20%,OSCOA
GND                      PC589            2        Q_CAPP_THLF-560UF,2.5V,20%,OSCA
GND                      PC590            2        Q_CAPP_SMLF-470UF,2.5V,20%,EMPA
GND                      PC591            2        Q_CAP_C0603-2.2UF,16V,10%,X6S,A
GND                      PC592            2        Q_CAP_0402-1000PF,50V,5%,X7R,TA
GND                      PC593            2        Q_CAP_0402-1000PF,50V,5%,EMPTYA
GND                      PC600            2        Q_CAP_C0402-2.2UF,10V,10%,X6S,A
GND                      PC601            2        Q_CAP_C0402-2.2UF,10V,10%,X6S,A
GND                      PC602_P0_1       2        Q_CAP_0402-3300PF,50V,10%,X7R,A
GND                      PC603_P0_2       2        Q_CAP_0402-3300PF,50V,10%,X7R,A
GND                      PC604_P0_1       2        Q_CAP_C0402-1UF,16V,10%,X6S,CHA
GND                      PC605_P0_2       2        Q_CAP_C0402-1UF,16V,10%,X6S,CHA
GND                      PC608_P0_1       2        Q_CAP_C0805-22UF,16V,20%,X6S,CA
GND                      PC609_P0_2       2        Q_CAP_C0805-22UF,16V,20%,X6S,CA
GND                      PC610_P0_1       2        Q_CAP_C0805-22UF,16V,20%,X6S,CA
GND                      PC611_P0_2       2        Q_CAP_C0805-22UF,16V,20%,X6S,CA
GND                      PC612_P0_1       2        Q_CAP_C0402-100NF,50V,10%,X7R,A
GND                      PC613_P0_2       2        Q_CAP_C0402-1UF,16V,10%,X6S,CHA
GND                      PC615_P0_1       2        Q_CAP_0805-22UF,4V,20%,X6S,TMPA
GND                      PC616_P0_2       2        Q_CAP_0805-22UF,4V,20%,X6S,TMPA
GND                      PC617_P0_1       2        Q_CAP_0805-22UF,4V,20%,X6S,TMPA
GND                      PC618_P0_2       2        Q_CAP_0805-22UF,4V,20%,X6S,TMPA
GND                      PC619            2        Q_CAPP_THLF-560UF,2.5V,20%,OSCA
GND                      PC620            2        Q_CAPP_THLF-560UF,2.5V,20%,OSCA
GND                      PC621            2        Q_CAPP_THLF-560UF,2.5V,20%,EMPA
GND                      PC621_P1_1       2        Q_CAP_C0402-100NF,50V,10%,X7R,A
GND                      PC71             2        Q_CAP_C0805-22UF,16V,20%,X6S,CA
GND                      PC83             2        Q_CAPP_THLF-560UF,2.5V,20%,OSCA
GND                      PC622            2        Q_CAPP_THLF-270UF,16V,20%,OSCOA
GND                      PC623            2        Q_CAPP_SMLF-470UF,2.5V,20%,EMPA
GND                      PC624            2        Q_CAP_0402-0.1UF,25V,10%,X7R,CA
GND                      PC626            2        Q_CAP_0402-1000PF,50V,5%,EMPTYA
GND                      PC628            2        Q_CAP_0402-0.1UF,25V,10%,X7R,CA
GND                      PC629            2        Q_CAP_C0402-100NF,50V,10%,EMPTA
GND                      PC630            2        Q_CAP_0402-4.7UF,6.3V,20%,X6S,A
GND                      PC631            2        Q_CAP_0402-470PF,50V,10%,X7R,TA
GND                      PC632            2        Q_CAP_C0402-1UF,16V,10%,X6S,CHA
GND                      PC633            2        Q_CAP_C0402-2.2UF,10V,10%,X6S,A
GND                      PC634            2        Q_CAP_0402-3300PF,50V,10%,X7R,A
GND                      PC635            2        Q_CAP_C0402-1UF,16V,10%,X6S,CHA
GND                      PC637            2        Q_CAP_C0805-22UF,16V,20%,X6S,CA
GND                      PC638            2        Q_CAP_C0805-22UF,16V,20%,X6S,CA
GND                      PC639            2        Q_CAP_C0402-100NF,50V,10%,X7R,A
GND                      PC641            2        Q_CAP_0805-22UF,4V,20%,X6S,TMPA
GND                      PC642            2        Q_CAP_0805-22UF,4V,20%,X6S,TMPA
GND                      PC644            2        Q_CAP_C0402-1UF,25V,10%,X6S,CHA
GND                      PC720_P0_1       2        Q_CAP_C0805-22UF,16V,20%,X6S,CA
GND                      PC721_P0_2       2        Q_CAP_C0805-22UF,16V,20%,X6S,CA
GND                      PC722_P0_3       2        Q_CAP_C0805-22UF,16V,20%,EMPTYA
GND                      PC723_P0_4       2        Q_CAP_C0805-22UF,16V,20%,EMPTYA
GND                      PC724_P1_1       2        Q_CAP_C0805-22UF,16V,20%,X6S,CA
GND                      PC725_P1_2       2        Q_CAP_C0805-22UF,16V,20%,X6S,CA
GND                      PC726_P1_3       2        Q_CAP_C0805-22UF,16V,20%,X6S,CA
GND                      PC727_P1_4       2        Q_CAP_C0805-22UF,16V,20%,X6S,CA
GND                      PC831            2        Q_CAP_C0805-22UF,16V,20%,EMPTYA
GND                      PJ63             2        Q_SHORT_SM-EMPTY,SHORT6
GND                      PJ65             2        Q_SHORT_SM-EMPTY,SHORT6
GND                      PJ67             2        Q_SHORT_SM-EMPTY,SHORT6
GND                      PL7              3        Q_INDUCTOR4P_14-150NH,SMLF,INDA
GND                      PL25             3        Q_INDUCTOR4P_14-150NH,SMLF,INDA
GND                      PL105            2        Q_INDUCTOR_SMLF-120NH/76A,IND,A
GND                      PL106            2        Q_INDUCTOR_SMLF-120NH/76A,IND,A
GND                      PR50             2        Q_RES_0402LF-12.4K,1%,1/16W,CHA
GND                      PR51             2        Q_RES_0402LF-12.4K,1%,1/16W,CHA
GND                      PR89             2        Q_RES_0402LF-15K,1%,1/16W,CHIPA
GND                      PR91             2        Q_RES_0402LF-11.8K,1%,1/16W,CHA
GND                      PR106            2        Q_RES_R0402LF-887,1%,1/16W,CHIA
GND                      PR122            2        Q_RES_0402LF-0,5%,1/16W,CHIP,CA
GND                      PR123            2        Q_RES_0402LF-1K,1%,1/16W,EMPTYA
GND                      PR132            2        Q_RES_0402LF-8.87K,1%,1/16W,EMA
GND                      PR133            2        Q_RES_0402LF-8.87K,1%,1/16W,EMA
GND                      PR138            2        Q_RES_0402LF-8.87K,1%,1/16W,EMA
GND                      PR139            2        Q_RES_0402LF-8.87K,1%,1/16W,EMA
GND                      PR144            2        Q_RES_0402LF-8.87K,1%,1/16W,EMA
GND                      PR145            2        Q_RES_0402LF-8.87K,1%,1/16W,EMA
GND                      PR150            2        Q_RES_0402LF-8.87K,1%,1/16W,EMA
GND                      PR151            2        Q_RES_0402LF-8.87K,1%,1/16W,EMA
GND                      PR158            2        Q_RES_0402LF-0,5%,1/16W,CHIP,CA
GND                      PR166            2        Q_RES_0402LF-1K,1%,1/16W,EMPTYA
GND                      PR171            2        Q_RES_0402LF-0,5%,1/16W,CHIP,CA
GND                      PR203            1        Q_RES_0402LF-30.1K    ,1%  ,1/A
GND                      PR214            2        Q_RES_0402LF-1K,1%,1/16W,EMPTYA
GND                      PR218            2        Q_RES_0402LF-1K,1%,1/16W,EMPTYA
GND                      PR224            2        Q_RES_0402LF-8.87K,1%,1/16W,EMA
GND                      PR225            2        Q_RES_0402LF-8.87K,1%,1/16W,EMA
GND                      PR259            2        Q_RES_0402LF -9.53K,1%,1/16W ,A
GND                      PR275            2        Q_RES_0402LF-0,5%,1/16W,CHIP,CA
GND                      PR276            2        Q_RES_0402LF-1K,1%,1/16W,EMPTYA
GND                      PR285            2        Q_RES_0402LF-8.87K,1%,1/16W,EMA
GND                      PR286            2        Q_RES_0402LF-8.87K,1%,1/16W,EMA
GND                      PR291            2        Q_RES_0402LF-8.87K,1%,1/16W,EMA
GND                      PR292            2        Q_RES_0402LF-8.87K,1%,1/16W,EMA
GND                      PR297            2        Q_RES_0402LF-8.87K,1%,1/16W,EMA
GND                      PR298            2        Q_RES_0402LF-8.87K,1%,1/16W,EMA
GND                      PR305            2        Q_RES_0402LF-0,5%,1/16W,CHIP,CA
GND                      PR313            2        Q_RES_0402LF-1K,1%,1/16W,EMPTYA
GND                      PR318            2        Q_RES_0402LF-5.23K,1%,1/16W,CHA
GND                      PR325            2        Q_RES_0402LF-8.87K,1%,1/16W,EMA
GND                      PR326            2        Q_RES_0402LF-8.87K,1%,1/16W,EMA
GND                      PR353            2        Q_RES_0402LF-8.87K,1%,1/16W,EMA
GND                      PR354            2        Q_RES_0402LF-8.87K,1%,1/16W,EMA
GND                      PR358            1        Q_RES_0402LF-4.64K,0.5%,1/16W,A
GND                      PR369            2        Q_RES_0402LF-1K,1%,1/16W,EMPTYA
GND                      PR373            2        Q_RES_0402LF-1K,1%,1/16W,EMPTYA
GND                      PR400            2        Q_RES_0402LF-10K,1%,1/16W,EMPTB
GND                      PR435            2        Q_RES_0402LF-10K,1%,1/16W,EMPTB
GND                      PR436            2        Q_RES_0402LF-10K,1%,1/16W,EMPTB
GND                      PR451            2        Q_RES_0402LF-0,5%,1/16W,CHIP,CA
GND                      PR453            2        Q_RES_0402LF-0,5%,1/16W,CHIP,CA
GND                      PR519            2        Q_RES_0402LF-100,1%,1/16W,CHIPA
GND                      PR520            2        Q_RES_0402LF-100,1%,1/16W,CHIPA
GND                      PR527            2        Q_RES_0402LF-100,1%,1/16W,CHIPA
GND                      PR558            2        Q_RES_0402LF-100,1%,1/16W,CHIPA
GND                      PR560            2        Q_RES_0402LF-100,1%,1/16W,CHIPA
GND                      PR566            2        Q_RES_0402LF-100,1%,1/16W,CHIPA
GND                      PR567            2        Q_RES_0402LF-100,1%,1/16W,CHIPA
GND                      PR574            2        Q_RES_0402LF-100,1%,1/16W,CHIPA
GND                      PR586            2        Q_RES_0402LF-100,1%,1/16W,CHIPA
GND                      PR591            2        Q_RES_0402LF-100,1%,1/16W,CHIPA
GND                      PR634            2        Q_RES_0402LF-10K,1%,1/16W,EMPTB
GND                      PR637            2        Q_RES_0402LF-10K,1%,1/16W,EMPTB
GND                      PR665            2        Q_RES_0402LF-10K,1%,1/16W,EMPTB
GND                      PR667            2        Q_RES_0402LF-10K,1%,1/16W,EMPTB
GND                      PR705            2        Q_RES_0402LF-10K,1%,1/16W,EMPTB
GND                      PR830            2        Q_RES_0402LF-31.6K,1%,1/16W,CHA
GND                      PR832            2        Q_RES_0402LF-7.5K,1%,1/16W,CHIA
GND                      PR833            2        Q_RES_0402LF-1.5K,1%,1/16W,EMPA
GND                      PR834            2        Q_RES_0402LF-21.5K,1%,1/16W,CHA
GND                      PR1297           2        Q_RES_0402LF-8.87K,1%,1/16W,EMA
GND                      PR1298           2        Q_RES_0402LF-8.87K,1%,1/16W,EMA
GND                      PR1301           2        Q_RES_0402LF-60.4K,1%,1/16W,CHA
GND                      PR1303           2        Q_RES_0402LF-9.09K,1%,1/16W,CHA
GND                      PR1304           2        Q_RES_0402LF-8.87K,1%,1/16W,EMA
GND                      PR1305           2        Q_RES_0402LF-8.87K,1%,1/16W,EMA
GND                      PR1311           2        Q_RES_0402LF-0,5%,1/16W,CHIP,CA
GND                      PR1315           2        Q_RES_0402LF-0,5%,1/16W,CHIP,CA
GND                      PR1327           2        Q_RES_0402LF-6.81K,1%,1/16W,CHA
GND                      PR1330           2        Q_RES_0402LF-150K,1%,1/16W,CHIA
GND                      PR1336           2        Q_RES_0402LF-8.87K,1%,1/16W,EMA
GND                      PR1339           2        Q_RES_0402LF-9.31K,1%,1/16W,CHA
GND                      PR1707           2        Q_RES_0402LF-8.87K,1%,1/16W,EMA
GND                      PR1708           2        Q_RES_0402LF-8.87K,1%,1/16W,EMA
GND                      PR1709           2        Q_RES_0402LF-8.87K,1%,1/16W,EMA
GND                      PR1726           2        Q_RES_0402LF-8.87K,1%,1/16W,EMA
GND                      PR1727           2        Q_RES_0402LF-8.87K,1%,1/16W,EMA
GND                      PR1728           2        Q_RES_0402LF-8.87K,1%,1/16W,EMA
GND                      PR1746           2        Q_RES_0402LF-8.87K,1%,1/16W,EMA
GND                      PR1948           2        Q_RES_0402LF-75K,1%,1/16W,CHIPA
GND                      PR2220           2        Q_RES_0402LF-60.4K,1%,1/16W,CHA
GND                      PR2222           2        Q_RES_0402LF-9.09K,1%,1/16W,CHA
GND                      PR2718           2        Q_RES_0402LF-8.87K,1%,1/16W,EMA
GND                      PU10_P0_4        2        ISL99390FRZTR5935-ISL99390FRZ-A
GND                      PU10_P0_4        5        ISL99390FRZTR5935-ISL99390FRZ-A
GND                      PU10_P0_4        40       ISL99390FRZTR5935-ISL99390FRZ-A
GND                      PU10_P0_4        7_9-20_24 ISL99390FRZTR5935-ISL99390FRZ-A
GND                      PU11_P0_3        2        ISL99390FRZTR5935-ISL99390FRZ-A
GND                      PU11_P0_3        5        ISL99390FRZTR5935-ISL99390FRZ-A
GND                      PU11_P0_3        40       ISL99390FRZTR5935-ISL99390FRZ-A
GND                      PU11_P0_3        7_9-20_24 ISL99390FRZTR5935-ISL99390FRZ-A
GND                      PU12_P0_2        2        ISL99390FRZTR5935-ISL99390FRZ-A
GND                      PU12_P0_2        5        ISL99390FRZTR5935-ISL99390FRZ-A
GND                      PU12_P0_2        40       ISL99390FRZTR5935-ISL99390FRZ-A
GND                      PU12_P0_2        7_9-20_24 ISL99390FRZTR5935-ISL99390FRZ-A
GND                      PU13_P0_1        2        ISL99390FRZTR5935-ISL99390FRZ-A
GND                      PU13_P0_1        5        ISL99390FRZTR5935-ISL99390FRZ-A
GND                      PU13_P0_1        40       ISL99390FRZTR5935-ISL99390FRZ-A
GND                      PU13_P0_1        7_9-20_24 ISL99390FRZTR5935-ISL99390FRZ-A
GND                      PU14             TH       RAA229126GNPHA0-RAA229126GNP#HA
GND                      PU17             2        RAA2213404GNPHB0-RAA2213404GNPA
GND                      PU17             23       RAA2213404GNPHB0-RAA2213404GNPA
GND                      PU17             26       RAA2213404GNPHB0-RAA2213404GNPA
GND                      PU17             6_7-13_15-29 RAA2213404GNPHB0-RAA2213404GNPA
GND                      PU18             20       ISL69260IRAZT-ISL69260IRAZ-T,SA
GND                      PU18             31       ISL69260IRAZT-ISL69260IRAZ-T,SA
GND                      PU18             32       ISL69260IRAZT-ISL69260IRAZ-T,SA
GND                      PU18             TH       ISL69260IRAZT-ISL69260IRAZ-T,SA
GND                      PU22             TH       ISL69260IRAZT-ISL69260IRAZ-T,SA
GND                      PU23_P1_8        2        ISL99390FRZTR5935-ISL99390FRZ-A
GND                      PU23_P1_8        5        ISL99390FRZTR5935-ISL99390FRZ-A
GND                      PU23_P1_8        40       ISL99390FRZTR5935-ISL99390FRZ-A
GND                      PU23_P1_8        7_9-20_24 ISL99390FRZTR5935-ISL99390FRZ-A
GND                      PU24_P1_7        2        ISL99390FRZTR5935-ISL99390FRZ-A
GND                      PU24_P1_7        5        ISL99390FRZTR5935-ISL99390FRZ-A
GND                      PU24_P1_7        40       ISL99390FRZTR5935-ISL99390FRZ-A
GND                      PU24_P1_7        7_9-20_24 ISL99390FRZTR5935-ISL99390FRZ-A
GND                      PU25_P1_6        2        ISL99390FRZTR5935-ISL99390FRZ-A
GND                      PU25_P1_6        5        ISL99390FRZTR5935-ISL99390FRZ-A
GND                      PU25_P1_6        40       ISL99390FRZTR5935-ISL99390FRZ-A
GND                      PU25_P1_6        7_9-20_24 ISL99390FRZTR5935-ISL99390FRZ-A
GND                      PU26_P1_5        2        ISL99390FRZTR5935-ISL99390FRZ-A
GND                      PU26_P1_5        5        ISL99390FRZTR5935-ISL99390FRZ-A
GND                      PU26_P1_5        40       ISL99390FRZTR5935-ISL99390FRZ-A
GND                      PU26_P1_5        7_9-20_24 ISL99390FRZTR5935-ISL99390FRZ-A
GND                      PU27_P1_4        2        ISL99390FRZTR5935-ISL99390FRZ-A
GND                      PU27_P1_4        5        ISL99390FRZTR5935-ISL99390FRZ-A
GND                      PU27_P1_4        40       ISL99390FRZTR5935-ISL99390FRZ-A
GND                      PU27_P1_4        7_9-20_24 ISL99390FRZTR5935-ISL99390FRZ-A
GND                      PU28_P1_3        2        ISL99390FRZTR5935-ISL99390FRZ-A
GND                      PU28_P1_3        5        ISL99390FRZTR5935-ISL99390FRZ-A
GND                      PU28_P1_3        40       ISL99390FRZTR5935-ISL99390FRZ-A
GND                      PU28_P1_3        7_9-20_24 ISL99390FRZTR5935-ISL99390FRZ-A
GND                      PU29             TH       RAA229126GNPHA0-RAA229126GNP#HA
GND                      PU30_P1_2        2        ISL99390FRZTR5935-ISL99390FRZ-A
GND                      PU30_P1_2        5        ISL99390FRZTR5935-ISL99390FRZ-A
GND                      PU30_P1_2        40       ISL99390FRZTR5935-ISL99390FRZ-A
GND                      PU30_P1_2        7_9-20_24 ISL99390FRZTR5935-ISL99390FRZ-A
GND                      PU31_P1_1        2        ISL99390FRZTR5935-ISL99390FRZ-A
GND                      PU31_P1_1        5        ISL99390FRZTR5935-ISL99390FRZ-A
GND                      PU31_P1_1        40       ISL99390FRZTR5935-ISL99390FRZ-A
GND                      PU31_P1_1        7_9-20_24 ISL99390FRZTR5935-ISL99390FRZ-A
GND                      PU5              TH       ISL69260IRAZT-ISL69260IRAZ-T,SA
GND                      PU35             20       ISL69260IRAZT-ISL69260IRAZ-T,SA
GND                      PU35             31       ISL69260IRAZT-ISL69260IRAZ-T,SA
GND                      PU35             32       ISL69260IRAZT-ISL69260IRAZ-T,SA
GND                      PU35             TH       ISL69260IRAZT-ISL69260IRAZ-T,SA
GND                      PU36             2        RAA2213404GNPHB0-RAA2213404GNPA
GND                      PU36             23       RAA2213404GNPHB0-RAA2213404GNPA
GND                      PU36             26       RAA2213404GNPHB0-RAA2213404GNPA
GND                      PU36             6_7-13_15-29 RAA2213404GNPHB0-RAA2213404GNPA
GND                      PU42             2        RAA2213404GNPHB0-RAA2213404GNPA
GND                      PU42             23       RAA2213404GNPHB0-RAA2213404GNPA
GND                      PU42             26       RAA2213404GNPHB0-RAA2213404GNPA
GND                      PU42             6_7-13_15-29 RAA2213404GNPHB0-RAA2213404GNPA
GND                      PU181            11_18    MPQ8633BGLEC838Z-MPQ8633BGLE-CA
GND                      PU181            2        MPQ8633BGLEC838Z-MPQ8633BGLE-CA
GND                      PU181            6        MPQ8633BGLEC838Z-MPQ8633BGLE-CA
GND                      PU43_P0_1        2        RAA2213404GNPHB0-RAA2213404GNPA
GND                      PU43_P0_1        23       RAA2213404GNPHB0-RAA2213404GNPA
GND                      PU43_P0_1        26       RAA2213404GNPHB0-RAA2213404GNPA
GND                      PU43_P0_1        6_7-13_15-29 RAA2213404GNPHB0-RAA2213404GNPA
GND                      PU44_P0_2        2        RAA2213404GNPHB0-RAA2213404GNPA
GND                      PU44_P0_2        23       RAA2213404GNPHB0-RAA2213404GNPA
GND                      PU44_P0_2        26       RAA2213404GNPHB0-RAA2213404GNPA
GND                      PU44_P0_2        6_7-13_15-29 RAA2213404GNPHB0-RAA2213404GNPA
GND                      PU49             2        RAA2213404GNPHB0-RAA2213404GNPA
GND                      PU49             23       RAA2213404GNPHB0-RAA2213404GNPA
GND                      PU49             26       RAA2213404GNPHB0-RAA2213404GNPA
GND                      PU49             6_7-13_15-29 RAA2213404GNPHB0-RAA2213404GNPA
GND                      PU50_P1_1        2        RAA2213404GNPHB0-RAA2213404GNPA
GND                      PU50_P1_1        23       RAA2213404GNPHB0-RAA2213404GNPA
GND                      PU50_P1_1        26       RAA2213404GNPHB0-RAA2213404GNPA
GND                      PU50_P1_1        6_7-13_15-29 RAA2213404GNPHB0-RAA2213404GNPA
GND                      PU51_P1_2        2        RAA2213404GNPHB0-RAA2213404GNPA
GND                      PU51_P1_2        23       RAA2213404GNPHB0-RAA2213404GNPA
GND                      PU51_P1_2        26       RAA2213404GNPHB0-RAA2213404GNPA
GND                      PU51_P1_2        6_7-13_15-29 RAA2213404GNPHB0-RAA2213404GNPA
GND                      PU69_P0_1        2        ISL99390FRZTR5935-ISL99390FRZ-A
GND                      PU69_P0_1        5        ISL99390FRZTR5935-ISL99390FRZ-A
GND                      PU69_P0_1        40       ISL99390FRZTR5935-ISL99390FRZ-A
GND                      PU69_P0_1        7_9-20_24 ISL99390FRZTR5935-ISL99390FRZ-A
GND                      PU6_P0_8         2        ISL99390FRZTR5935-ISL99390FRZ-A
GND                      PU6_P0_8         5        ISL99390FRZTR5935-ISL99390FRZ-A
GND                      PU6_P0_8         40       ISL99390FRZTR5935-ISL99390FRZ-A
GND                      PU6_P0_8         7_9-20_24 ISL99390FRZTR5935-ISL99390FRZ-A
GND                      PU70_P0_2        2        ISL99390FRZTR5935-ISL99390FRZ-A
GND                      PU70_P0_2        5        ISL99390FRZTR5935-ISL99390FRZ-A
GND                      PU70_P0_2        40       ISL99390FRZTR5935-ISL99390FRZ-A
GND                      PU70_P0_2        7_9-20_24 ISL99390FRZTR5935-ISL99390FRZ-A
GND                      PU71_P0_3        2        ISL99390FRZTR5935-ISL99390FRZ-B
GND                      PU71_P0_3        5        ISL99390FRZTR5935-ISL99390FRZ-B
GND                      PU71_P0_3        40       ISL99390FRZTR5935-ISL99390FRZ-B
GND                      PU71_P0_3        7_9-20_24 ISL99390FRZTR5935-ISL99390FRZ-B
GND                      PU72_P0_4        2        ISL99390FRZTR5935-ISL99390FRZ-B
GND                      PU72_P0_4        5        ISL99390FRZTR5935-ISL99390FRZ-B
GND                      PU72_P0_4        40       ISL99390FRZTR5935-ISL99390FRZ-B
GND                      PU72_P0_4        7_9-20_24 ISL99390FRZTR5935-ISL99390FRZ-B
GND                      PU73             11_18    MPQ8633BGLEC838Z-MPQ8633BGLE-CA
GND                      PU73             2        MPQ8633BGLEC838Z-MPQ8633BGLE-CA
GND                      PU74             2        NB695GDZ-NB695GD-Z,SMLF,IC,AL0A
GND                      PU74             4        NB695GDZ-NB695GD-Z,SMLF,IC,AL0A
GND                      PU74             11       NB695GDZ-NB695GD-Z,SMLF,IC,AL0A
GND                      PU75_P1_1        2        ISL99390FRZTR5935-ISL99390FRZ-A
GND                      PU75_P1_1        5        ISL99390FRZTR5935-ISL99390FRZ-A
GND                      PU75_P1_1        40       ISL99390FRZTR5935-ISL99390FRZ-A
GND                      PU75_P1_1        7_9-20_24 ISL99390FRZTR5935-ISL99390FRZ-A
GND                      PU76_P1_2        2        ISL99390FRZTR5935-ISL99390FRZ-A
GND                      PU76_P1_2        5        ISL99390FRZTR5935-ISL99390FRZ-A
GND                      PU76_P1_2        40       ISL99390FRZTR5935-ISL99390FRZ-A
GND                      PU76_P1_2        7_9-20_24 ISL99390FRZTR5935-ISL99390FRZ-A
GND                      PU77_P1_3        2        ISL99390FRZTR5935-ISL99390FRZ-A
GND                      PU77_P1_3        5        ISL99390FRZTR5935-ISL99390FRZ-A
GND                      PU77_P1_3        40       ISL99390FRZTR5935-ISL99390FRZ-A
GND                      PU77_P1_3        7_9-20_24 ISL99390FRZTR5935-ISL99390FRZ-A
GND                      PU78_P1_4        2        ISL99390FRZTR5935-ISL99390FRZ-A
GND                      PU78_P1_4        5        ISL99390FRZTR5935-ISL99390FRZ-A
GND                      PU78_P1_4        40       ISL99390FRZTR5935-ISL99390FRZ-A
GND                      PU78_P1_4        7_9-20_24 ISL99390FRZTR5935-ISL99390FRZ-A
GND                      PU79             11_18    MPQ8633AGLEC807Z-MPQ8633AGLE-CA
GND                      PU79             2        MPQ8633AGLEC807Z-MPQ8633AGLE-CA
GND                      PU7_P0_7         2        ISL99390FRZTR5935-ISL99390FRZ-A
GND                      PU7_P0_7         5        ISL99390FRZTR5935-ISL99390FRZ-A
GND                      PU7_P0_7         40       ISL99390FRZTR5935-ISL99390FRZ-A
GND                      PU7_P0_7         7_9-20_24 ISL99390FRZTR5935-ISL99390FRZ-A
GND                      PU9              31       NCP3284MNTXG-NCP3284MNTXG,SMLFA
GND                      PU9              32       NCP3284MNTXG-NCP3284MNTXG,SMLFA
GND                      PU9              7_10-19  NCP3284MNTXG-NCP3284MNTXG,SMLFA
GND                      PU80             11_18    MPQ8633AGLEC807Z-MPQ8633AGLE-CB
GND                      PU80             2        MPQ8633AGLEC807Z-MPQ8633AGLE-CB
GND                      PU81             1        MPQ8626GDZ-MPQ8626GD-Z,SMLF,ICA
GND                      PU81             7        MPQ8626GDZ-MPQ8626GD-Z,SMLF,ICA
GND                      PU81             14       MPQ8626GDZ-MPQ8626GD-Z,SMLF,ICA
GND                      PU82             1        MPQ8626GDZ-MPQ8626GD-Z,SMLF,ICA
GND                      PU82             7        MPQ8626GDZ-MPQ8626GD-Z,SMLF,ICA
GND                      PU82             14       MPQ8626GDZ-MPQ8626GD-Z,SMLF,ICA
GND                      PU8_P0_6         2        ISL99390FRZTR5935-ISL99390FRZ-A
GND                      PU8_P0_6         5        ISL99390FRZTR5935-ISL99390FRZ-A
GND                      PU8_P0_6         40       ISL99390FRZTR5935-ISL99390FRZ-A
GND                      PU8_P0_6         7_9-20_24 ISL99390FRZTR5935-ISL99390FRZ-A
GND                      PU9_P0_5         2        ISL99390FRZTR5935-ISL99390FRZ-A
GND                      PU9_P0_5         5        ISL99390FRZTR5935-ISL99390FRZ-A
GND                      PU9_P0_5         40       ISL99390FRZTR5935-ISL99390FRZ-A
GND                      PU9_P0_5         7_9-20_24 ISL99390FRZTR5935-ISL99390FRZ-A
GND                      Q15              1        MOSFET_NCH_DUAL-2N7002KDW,SMLFA
GND                      Q15              4        MOSFET_NCH_DUAL-2N7002KDW,SMLFA
GND                      Q16              1        MOSFET_NCH_DUAL-2N7002KDW,SMLFA
GND                      Q16              4        MOSFET_NCH_DUAL-2N7002KDW,SMLFA
GND                      Q34              S        MOSFET_N_GSD-NX7002AK,SMLF,IC,A
GND                      Q35              S        MOSFET_N_GSD-NX7002AK,SMLF,IC,A
GND                      Q37              1        MOSFET_NCH_DUAL-2N7002KDW,SMLFA
GND                      Q37              4        MOSFET_NCH_DUAL-2N7002KDW,SMLFA
GND                      Q39              4        MOSFET_NCH_DUAL-2N7002KDW,SMLFA
GND                      Q45              1        MOSFET_NCH_DUAL-2N7002KDW,SMLFA
GND                      Q45              4        MOSFET_NCH_DUAL-2N7002KDW,SMLFA
GND                      R9               2        Q_RES_0402LF-4.32K,1%,1/16W,CHA
GND                      R26              2        Q_RES_0402LF-10K,1%,1/16W,CHIPA
GND                      R27              2        Q_RES_0402LF-15.4K,1%,1/16W,CHA
GND                      R28              2        Q_RES_0402LF-23.2K,1%,1/16W,CHA
GND                      R29              2        Q_RES_0402LF-35.7K,1%,1/16W,CHA
GND                      R30              2        Q_RES_0402LF-54.9K,1%,1/16W,CHA
GND                      R31              2        Q_RES_0402LF-84.5K,1%,1/16W,CHA
GND                      R32              2        Q_RES_0402LF-127K,1%,1/16W,CHIA
GND                      R33              2        Q_RES_0402LF-196K,1%,1/16W,CHIA
GND                      R34              2        Q_RES_0402LF-10K,1%,1/16W,CHIPA
GND                      R35              2        Q_RES_0402LF-15.4K,1%,1/16W,CHA
GND                      R36              2        Q_RES_0402LF-23.2K,1%,1/16W,CHA
GND                      R37              2        Q_RES_0402LF-35.7K,1%,1/16W,CHA
GND                      R38              2        Q_RES_0402LF-54.9K,1%,1/16W,CHA
GND                      R39              2        Q_RES_0402LF-84.5K,1%,1/16W,CHA
GND                      R40              2        Q_RES_0402LF-127K,1%,1/16W,CHIA
GND                      R41              2        Q_RES_0402LF-196K,1%,1/16W,CHIA
GND                      R42              2        Q_RES_0402LF-10K,1%,1/16W,CHIPA
GND                      R43              2        Q_RES_0402LF-15.4K,1%,1/16W,CHA
GND                      R44              2        Q_RES_0402LF-23.2K,1%,1/16W,CHA
GND                      R45              2        Q_RES_0402LF-35.7K,1%,1/16W,CHA
GND                      R46              2        Q_RES_0402LF-54.9K,1%,1/16W,CHA
GND                      R47              2        Q_RES_0402LF-84.5K,1%,1/16W,CHA
GND                      R48              2        Q_RES_0402LF-127K,1%,1/16W,CHIA
GND                      R69              2        Q_RES_0402LF-10K,1%,1/16W,CHIPA
GND                      R70              2        Q_RES_0402LF-10K,1%,1/16W,CHIPA
GND                      R72              2        Q_RES_0402LF-196K,1%,1/16W,CHIA
GND                      R73              2        Q_RES_0402LF-127K,1%,1/16W,CHIA
GND                      R74              2        Q_RES_0402LF-84.5K,1%,1/16W,CHA
GND                      R75              2        Q_RES_0402LF-54.9K,1%,1/16W,CHA
GND                      R76              2        Q_RES_0402LF-35.7K,1%,1/16W,CHA
GND                      R77              2        Q_RES_0402LF-23.2K,1%,1/16W,CHA
GND                      R78              2        Q_RES_0402LF-15.4K,1%,1/16W,CHA
GND                      R79              2        Q_RES_0402LF-10K,1%,1/16W,CHIPA
GND                      R80              2        Q_RES_0402LF-196K,1%,1/16W,CHIA
GND                      R106             1        Q_RES_0402LF-2K,1%,1/16W,CHIP,A
GND                      R148             2        Q_RES_0402LF-10K,1%,1/16W,CHIPA
GND                      R288             1        Q_RES_0402LF-240,1%,1/16W,CHIPA
GND                      R289             1        Q_RES_0402LF-240,1%,1/16W,CHIPA
GND                      R290             1        Q_RES_0402LF-240,1%,1/16W,CHIPA
GND                      R291             1        Q_RES_0402LF-240,1%,1/16W,EMPTA
GND                      R292             1        Q_RES_0402LF-240,1%,1/16W,CHIPA
GND                      R293             1        Q_RES_0402LF-240,1%,1/16W,CHIPA
GND                      R294             1        Q_RES_0402LF-240,1%,1/16W,EMPTA
GND                      R295             1        Q_RES_0402LF-240,1%,1/16W,EMPTA
GND                      R316             2        Q_RES_0402LF-4.32K,1%,1/16W,CHA
GND                      R318             2        Q_RES_0402LF-10K,1%,1/16W,CHIPA
GND                      R332             2        Q_RES_0402LF-10K,1%,1/16W,CHIPA
GND                      R334             2        Q_RES_0402LF-10K,1%,1/16W,CHIPA
GND                      R372             2        Q_RES_0402LF-10K,1%,1/16W,CHIPA
GND                      R375             2        Q_RES_0402LF-10K,1%,1/16W,CHIPA
GND                      R379             2        Q_RES_0402LF-1K,5%,1/16W,CHIP,A
GND                      R381             2        Q_RES_0402LF-10K,1%,1/16W,CHIPA
GND                      R396             2        Q_RES_0402LF-10K,1%,1/16W,CHIPA
GND                      R400             2        Q_RES_0402LF-10K,1%,1/16W,CHIPA
GND                      R404             2        Q_RES_0402LF-10K,1%,1/16W,CHIPA
GND                      R410             2        Q_RES_0402LF-4.7K,1%,1/16W,CHIA
GND                      R413             1        Q_RES_0402LF-100K,1%,1/16W,CHIA
GND                      R415             2        Q_RES_0402LF-4.7K,1%,1/16W,CHIA
GND                      R422             2        Q_RES_0402LF-1K,1%,1/16W,EMPTYA
GND                      R423             2        Q_RES_0402LF-0,5%,1/16W,EMPTY,A
GND                      R462             2        Q_RES_0402LF-20K,1%,1/16W,CHIPA
GND                      R477             2        Q_RES_0402LF-60.4,1%,1/16W,CHIA
GND                      R491             2        Q_RES_0402LF-4.7K,1%,1/16W,EMPA
GND                      R496             2        Q_RES_0402LF-113,1%,1/16W,CHIPA
GND                      R497             2        Q_RES_0402LF-200,1%,1/16W,CHIPA
GND                      R508             2        Q_RES_0402LF-0,5%,1/16W,EMPTY,A
GND                      R509             2        Q_RES_0402LF-0,5%,1/16W,CHIP,CA
GND                      R515             2        Q_RES_0402LF-10K,1%,1/16W,CHIPA
GND                      R537             2        Q_RES_0402LF-1K,1%,1/16W,CHIP,A
GND                      R539             2        Q_RES_0402LF-1K,1%,1/16W,CHIP,A
GND                      R568             2        Q_RES_0402LF-4.7K,1%,1/16W,CHIA
GND                      R570             2        Q_RES_0402LF-4.7K,1%,1/16W,CHIA
GND                      R574             2        Q_RES_0402LF-4.7K,1%,1/16W,CHIA
GND                      R587             2        Q_RES_0402LF-1K,1%,1/16W,CHIP,A
GND                      R608             2        Q_RES_0402LF-10K,1%,1/16W,CHIPA
GND                      R610             2        Q_RES_0402LF-10K,1%,1/16W,CHIPA
GND                      R612             2        Q_RES_0402LF-10K,1%,1/16W,EMPTA
GND                      R614             2        Q_RES_0402LF-1K,5%,1/16W,EMPTYA
GND                      R618             2        Q_RES_0402LF-10K,1%,1/16W,CHIPA
GND                      R622             2        Q_RES_0402LF-1K,5%,1/16W,CHIP,A
GND                      R624             2        Q_RES_0402LF-10K,1%,1/16W,CHIPA
GND                      R626             2        Q_RES_0402LF-10K,1%,1/16W,CHIPA
GND                      R628             2        Q_RES_0402LF-10K,1%,1/16W,CHIPA
GND                      R630             2        Q_RES_0402LF-10K,1%,1/16W,EMPTA
GND                      R642             2        Q_RES_0402LF-1K,1%,1/16W,CHIP,A
GND                      R644             2        Q_RES_0402LF-1K,1%,1/16W,CHIP,A
GND                      R646             2        Q_RES_0402LF-1K,1%,1/16W,EMPTYA
GND                      R661             2        Q_RES_0402LF-1K,1%,1/16W,CHIP,A
GND                      R678             2        Q_RES_0402LF-1K,1%,1/16W,CHIP,A
GND                      R701             2        Q_RES_0402LF-10K,1%,1/16W,EMPTA
GND                      R702             2        Q_RES_0402LF-10K,1%,1/16W,EMPTA
GND                      R703             2        Q_RES_0402LF-10K,1%,1/16W,EMPTA
GND                      R704             2        Q_RES_0402LF-10K,1%,1/16W,EMPTA
GND                      R705             2        Q_RES_0402LF-10K,1%,1/16W,EMPTA
GND                      R706             2        Q_RES_0402LF-10K,1%,1/16W,EMPTA
GND                      R707             2        Q_RES_0402LF-10K,1%,1/16W,EMPTA
GND                      R708             2        Q_RES_0402LF-10K,1%,1/16W,EMPTA
GND                      R710             2        Q_RES_0402LF-1K,1%,1/16W,CHIP,A
GND                      R712             2        Q_RES_0402LF-1K,1%,1/16W,CHIP,A
GND                      R714             2        Q_RES_0402LF-1K,1%,1/16W,CHIP,A
GND                      R716             2        Q_RES_0402LF-1K,1%,1/16W,CHIP,A
GND                      R718             2        Q_RES_0402LF-1K,1%,1/16W,CHIP,A
GND                      R720             2        Q_RES_0402LF-1K,1%,1/16W,EMPTYA
GND                      R722             2        Q_RES_0402LF-1K,1%,1/16W,EMPTYA
GND                      R729             2        Q_RES_0402LF-1K,1%,1/16W,CHIP,A
GND                      R731             2        Q_RES_0402LF-1K,1%,1/16W,EMPTYA
GND                      R733             2        Q_RES_0402LF-1K,1%,1/16W,CHIP,A
GND                      R734             2        Q_RES_0402LF-4.75K,1%,1/16W,CHA
GND                      R736             2        Q_RES_0402LF-1K,1%,1/16W,EMPTYA
GND                      R746             2        Q_RES_0402LF-0,5%,1/16W,CHIP,CA
GND                      R769             2        Q_RES_0402LF-10K,1%,1/16W,CHIPA
GND                      R774             2        Q_RES_0402LF-75,1%,1/16W,CHIP,A
GND                      R782             2        Q_RES_0402LF-1K,1%,1/16W,CHIP,A
GND                      R784             2        Q_RES_0402LF-1K,1%,1/16W,EMPTYA
GND                      R786             2        Q_RES_0402LF-1K,1%,1/16W,CHIP,A
GND                      R920             2        Q_RES_0402LF-1K,5%,1/16W,EMPTYA
GND                      R930             2        Q_RES_0402LF-4.7K,1%,1/16W,CHIA
GND                      R932             2        Q_RES_0402LF-10K,1%,1/16W,CHIPA
GND                      R933             2        Q_RES_0402LF-10K,1%,1/16W,CHIPA
GND                      R934             2        Q_RES_0402LF-10K,1%,1/16W,CHIPA
GND                      R935             2        Q_RES_0402LF-10K,1%,1/16W,CHIPA
GND                      R936             2        Q_RES_0402LF-10K,1%,1/16W,CHIPA
GND                      R937             2        Q_RES_0402LF-10K,1%,1/16W,CHIPA
GND                      R938             2        Q_RES_0402LF-10K,1%,1/16W,CHIPA
GND                      R939             2        Q_RES_0402LF-10K,1%,1/16W,CHIPA
GND                      R953             2        Q_RES_0402LF-4.75K,1%,1/16W,CHA
GND                      R990             2        Q_RES_0402LF-2K,1%,1/16W,CHIP,A
GND                      R991             2        Q_RES_0402LF-2K,1%,1/16W,CHIP,A
GND                      R992             2        Q_RES_0402LF-2K,1%,1/16W,CHIP,A
GND                      R997             2        Q_RES_0402LF-10K,1%,1/16W,EMPTA
GND                      R1005            2        Q_RES_0402LF-10K,1%,1/16W,EMPTA
GND                      R1024            2        Q_RES_0402LF-100,1%,1/16W,CHIPA
GND                      R1025            2        Q_RES_0402LF-75,1%,1/16W,EMPTYA
GND                      R1103            2        Q_RES_0402LF-1.33K,1%,1/16W,CHA
GND                      R1124            2        Q_RES_0402LF-1K,5%,1/16W,CHIP,A
GND                      R1126            2        Q_RES_0402LF-1K,5%,1/16W,CHIP,A
GND                      R1128            2        Q_RES_0402LF-1K,5%,1/16W,CHIP,A
GND                      R1134            2        Q_RES_0402LF-0,5%,1/16W,CHIP,CA
GND                      R1135            2        Q_RES_0402LF-0,5%,1/16W,EMPTY,A
GND                      R1136            2        Q_RES_0402LF-0,5%,1/16W,CHIP,CA
GND                      R1137            2        Q_RES_0402LF-150,1%,1/16W,CHIPA
GND                      R1142            2        Q_RES_0402LF-1K,5%,1/16W,CHIP,A
GND                      R1144            2        Q_RES_0402LF-562,1%,1/16W,CHIPA
GND                      R1196            2        Q_RES_0402LF-4.75K,1%,1/16W,CHA
GND                      R1197            1        Q_RES_0402LF-1K,5%,1/16W,EMPTYA
GND                      R1221            2        Q_RES_0402LF-1K,1%,1/16W,CHIP,A
GND                      R1226            2        Q_RES_0402LF-1K,1%,1/16W,CHIP,A
GND                      R1227            2        Q_RES_0402LF-10K,1%,1/16W,CHIPA
GND                      R1234            1        Q_RES_0402LF-240,1%,1/16W,EMPTA
GND                      R1235            1        Q_RES_0402LF-240,1%,1/16W,EMPTA
GND                      R1236            1        Q_RES_0402LF-240,1%,1/16W,EMPTA
GND                      R1237            1        Q_RES_0402LF-240,1%,1/16W,EMPTA
GND                      R1238            1        Q_RES_0402LF-240,1%,1/16W,EMPTA
GND                      R1239            1        Q_RES_0402LF-240,1%,1/16W,EMPTA
GND                      R1241            2        Q_RES_0402LF-249,1%,1/16W,CHIPA
GND                      R1243            2        Q_RES_0402LF-249,1%,1/16W,CHIPA
GND                      R1267            2        Q_RES_0402LF-1K,1%,1/16W,CHIP,A
GND                      R1269            2        Q_RES_0402LF-4.75K,1%,1/16W,CHA
GND                      R1270            2        Q_RES_0402LF-240,1%,1/16W,EMPTA
GND                      R1289            2        Q_RES_0402LF-100K,1%,1/16W,CHIA
GND                      R1299            2        Q_RES_0402LF-10K,1%,1/16W,CHIPA
GND                      R1302            2        Q_RES_0402LF-2K,1%,1/16W,CHIP,A
GND                      R1308            2        Q_RES_0402LF-10K,1%,1/16W,EMPTA
GND                      R1311            2        Q_RES_0402LF-10K,1%,1/16W,CHIPA
GND                      R1312            2        Q_RES_0402LF-10K,1%,1/16W,EMPTA
GND                      R1324            1        Q_RES_0402LF-1K,1%,1/16W,CHIP,A
GND                      R1326            2        Q_RES_0402LF-2K,1%,1/16W,CHIP,A
GND                      R1327            2        Q_RES_0402LF-2K,1%,1/16W,CHIP,A
GND                      R1328            2        Q_RES_0402LF-2K,1%,1/16W,CHIP,A
GND                      R1329            2        Q_RES_0402LF-2K,1%,1/16W,CHIP,A
GND                      R1330            2        Q_RES_0402LF-2K,1%,1/16W,CHIP,A
GND                      R1333            1        Q_RES_0402LF-1K,1%,1/16W,CHIP,A
GND                      R1334            1        Q_RES_0402LF-1K,1%,1/16W,CHIP,A
GND                      R1335            1        Q_RES_0402LF-1K,1%,1/16W,CHIP,A
GND                      R1337            2        Q_RES_0402LF-10K,1%,1/16W,CHIPA
GND                      R1338            2        Q_RES_0402LF-10K,1%,1/16W,CHIPA
GND                      R1341            2        Q_RES_0402LF-10K,1%,1/16W,CHIPA
GND                      R1346            2        Q_RES_0402LF-1K,1%,1/16W,CHIP,A
GND                      R1347            2        Q_RES_0402LF-1K,1%,1/16W,CHIP,A
GND                      R1350            2        Q_RES_0402LF-100K,1%,1/16W,CHIA
GND                      R1351            2        Q_RES_0402LF-100K,1%,1/16W,CHIA
GND                      R1352            2        Q_RES_0402LF-100K,1%,1/16W,CHIA
GND                      R1353            2        Q_RES_0402LF-100K,1%,1/16W,CHIA
GND                      R1354            2        Q_RES_0402LF-100K,1%,1/16W,CHIA
GND                      R1355            2        Q_RES_0402LF-100K,1%,1/16W,CHIA
GND                      R1356            2        Q_RES_0402LF-1K,1%,1/16W,CHIP,A
GND                      R1365            2        Q_RES_0402LF-1K,1%,1/16W,CHIP,A
GND                      R1368            2        Q_RES_0402LF-1K,1%,1/16W,CHIP,A
GND                      R1369            2        Q_RES_0402LF-1K,1%,1/16W,CHIP,A
GND                      R1371            2        Q_RES_0402LF-1K,1%,1/16W,CHIP,A
GND                      R1372            2        Q_RES_0402LF-1K,1%,1/16W,CHIP,A
GND                      R1373            2        Q_RES_0402LF-1K,1%,1/16W,CHIP,A
GND                      R1374            2        Q_RES_0402LF-1K,1%,1/16W,CHIP,A
GND                      R1375            2        Q_RES_0402LF-10K,1%,1/16W,CHIPA
GND                      R1388            2        Q_RES_0402LF-2K,1%,1/16W,CHIP,A
GND                      R1389            2        Q_RES_0402LF-2K,1%,1/16W,CHIP,A
GND                      R1390            2        Q_RES_0402LF-1K,1%,1/16W,EMPTYA
GND                      R1391            1        Q_RES_0402LF-240,1%,1/16W,EMPTA
GND                      R1392            1        Q_RES_0402LF-240,1%,1/16W,EMPTA
GND                      R1393            1        Q_RES_0402LF-240,1%,1/16W,EMPTA
GND                      R1394            1        Q_RES_0402LF-240,1%,1/16W,EMPTA
GND                      R1398            2        Q_RES_0402LF-2K,1%,1/16W,CHIP,A
GND                      R1402            2        Q_RES_0402LF-2K,1%,1/16W,CHIP,A
GND                      R1403            2        Q_RES_0402LF-2K,1%,1/16W,CHIP,A
GND                      R1404            2        Q_RES_0402LF-2K,1%,1/16W,CHIP,A
GND                      R1405            2        Q_RES_0402LF-2K,1%,1/16W,CHIP,A
GND                      R1406            2        Q_RES_0402LF-2K,1%,1/16W,CHIP,A
GND                      R1407            2        Q_RES_0402LF-2K,1%,1/16W,CHIP,A
GND                      R1408            2        Q_RES_0402LF-2K,1%,1/16W,CHIP,A
GND                      R1409            2        Q_RES_0402LF-2K,1%,1/16W,CHIP,A
GND                      R1410            2        Q_RES_0402LF-2K,1%,1/16W,CHIP,A
GND                      R1411            2        Q_RES_0402LF-2K,1%,1/16W,CHIP,A
GND                      R1412            2        Q_RES_0402LF-2K,1%,1/16W,CHIP,A
GND                      R1413            2        Q_RES_0402LF-2K,1%,1/16W,CHIP,A
GND                      R1414            2        Q_RES_0402LF-2K,1%,1/16W,CHIP,A
GND                      R1415            2        Q_RES_0402LF-2K,1%,1/16W,CHIP,A
GND                      R1416            2        Q_RES_0402LF-2K,1%,1/16W,CHIP,A
GND                      R1417            2        Q_RES_0402LF-2K,1%,1/16W,CHIP,A
GND                      R1418            2        Q_RES_0402LF-2K,1%,1/16W,CHIP,A
GND                      R1419            2        Q_RES_0402LF-2K,1%,1/16W,CHIP,A
GND                      R1420            2        Q_RES_0402LF-2K,1%,1/16W,CHIP,A
GND                      R1421            2        Q_RES_0402LF-2K,1%,1/16W,CHIP,A
GND                      R1441            2        Q_RES_0402LF-1K,1%,1/16W,CHIP,A
GND                      R1445            2        Q_RES_0402LF-2K,1%,1/16W,CHIP,A
GND                      R1457            2        Q_RES_0402LF-10K,1%,1/16W,CHIPA
GND                      R1462            2        Q_RES_0402LF-1K,1%,1/16W,CHIP,A
GND                      R1476            2        Q_RES_0402LF-1K,1%,1/16W,CHIP,A
GND                      R1478            2        Q_RES_0402LF-10K,1%,1/16W,CHIPA
GND                      R1484            2        Q_RES_0402LF-1K,1%,1/16W,EMPTYA
GND                      R1487            2        Q_RES_0402LF-100,1%,1/16W,CHIPA
GND                      R1491            2        Q_RES_0402LF-1K,1%,1/16W,CHIP,A
GND                      R1494            2        Q_RES_0402LF-1K,1%,1/16W,CHIP,A
GND                      R1495            2        Q_RES_0402LF-10K,1%,1/16W,CHIPA
GND                      R1497            2        Q_RES_0402LF-12K,1%,1/16W,EMPTA
GND                      R1499            2        Q_RES_0402LF-1K,1%,1/16W,CHIP,A
GND                      R1500            2        Q_RES_0402LF-4.75K,1%,1/16W,CHA
GND                      R1502            2        Q_RES_0402LF-4.75K,1%,1/16W,CHA
GND                      R1527            2        Q_RES_0402LF-1K,1%,1/16W,CHIP,A
GND                      R1530            2        Q_RES_0402LF-4.7K,5%,1/16W,EMPA
GND                      R1531            2        Q_RES_0402LF-4.7K,5%,1/16W,EMPA
GND                      R1535            2        Q_RES_0402LF-4.7K,5%,1/16W,EMPA
GND                      R1536            2        Q_RES_0402LF-4.7K,5%,1/16W,EMPA
GND                      R1539            2        Q_RES_0402LF-10K,1%,1/16W,CHIPA
GND                      R1541            1        Q_RES_0402LF-100K,1%,1/16W,CHIA
GND                      R1574            2        Q_RES_0402LF-100,1%,1/16W,CHIPA
GND                      R1578            2        Q_RES_0402LF-100,1%,1/16W,CHIPA
GND                      R1605            2        Q_RES_0402LF-1K,1%,1/16W,CHIP,A
GND                      R1614            2        Q_RES_0402LF-100,1%,1/16W,CHIPA
GND                      R1616            2        Q_RES_0402LF-100,1%,1/16W,CHIPA
GND                      R1618            2        Q_RES_0402LF-100,1%,1/16W,CHIPA
GND                      R1641            2        Q_RES_0402LF-100,1%,1/16W,CHIPA
GND                      R1646            2        Q_RES_0402LF-4.7K,5%,1/16W,CHIA
GND                      R1649            2        Q_RES_0402LF-2K,1%,1/16W,CHIP,A
GND                      R1676            2        Q_RES_0402LF-1K,1%,1/16W,EMPTYA
GND                      R1689            2        Q_RES_0402LF-6.19K,1%,1/16W,CHA
GND                      R1692            2        Q_RES_0402LF-100K,1%,1/16W,CHIA
GND                      R1698            2        Q_RES_0402LF-20K,5%,1/16W,CHIPA
GND                      R1701            2        Q_RES_0402LF-100K,1%,1/16W,EMPB
GND                      R1738            2        Q_RES_0402LF-100,1%,1/16W,CHIPA
GND                      R1739            2        Q_RES_0402LF-100,1%,1/16W,CHIPA
GND                      R1742            2        Q_RES_0402LF-10K,1%,1/16W,EMPTA
GND                      R1749            2        Q_RES_0402LF-10K,1%,1/16W,EMPTA
GND                      R1764            2        Q_RES_0402LF-1K,1%,1/16W,EMPTYA
GND                      R1785            2        Q_RES_0402LF-4.7K,1%,1/16W,CHIA
GND                      R1787            2        Q_RES_0402LF-1K,0.1%,1/16W,CHIA
GND                      R1789            2        Q_RES_0402LF-1K,0.1%,1/16W,CHIA
GND                      R1791            2        Q_RES_0402LF-200K,1%,1/16W,CHIA
GND                      R1800            2        Q_RES_0402LF-120K,1%,1/16W,CHIA
GND                      R1801            2        Q_RES_0402LF-0,5%,1/16W,CHIP,CA
GND                      R1810            2        Q_RES_0402LF-1K,5%,1/16W,EMPTYA
GND                      R1814            2        Q_RES_0402LF-1K,1%,1/16W,CHIP,A
GND                      R1850            1        Q_RES_0402LF-1K,5%,1/16W,EMPTYA
GND                      R1895            2        Q_RES_0402LF-100,1%,1/16W,CHIPA
GND                      R1896            2        Q_RES_0402LF-100,1%,1/16W,CHIPA
GND                      R1897            2        Q_RES_0402LF-100,1%,1/16W,CHIPA
GND                      R1898            2        Q_RES_0402LF-100,1%,1/16W,CHIPA
GND                      R1929            1        Q_RES_0402LF-10K,5%,1/16W,CHIPA
GND                      R1930            1        Q_RES_0402LF-10K,5%,1/16W,CHIPA
GND                      R1962            2        Q_RES_0402LF-20K,5%,1/16W,CHIPA
GND                      R1969            2        Q_RES_0402LF-10K,1%,1/16W,EMPTA
GND                      R1970            2        Q_RES_0402LF-10K,1%,1/16W,CHIPA
GND                      R1972            2        Q_RES_0402LF-100,1%,1/16W,CHIPA
GND                      R1980            2        Q_RES_0402LF-10K,1%,1/16W,CHIPA
GND                      R1982            2        Q_RES_0402LF-100,1%,1/16W,CHIPA
GND                      R1990            2        Q_RES_0402LF-10K,1%,1/16W,CHIPA
GND                      R1992            2        Q_RES_0402LF-100,1%,1/16W,CHIPA
GND                      R2002            2        Q_RES_0402LF-10K,1%,1/16W,CHIPA
GND                      R2004            2        Q_RES_0402LF-100,1%,1/16W,CHIPA
GND                      R2016            2        Q_RES_0402LF-1.33K,1%,1/16W,CHA
GND                      R2020            2        Q_RES_0402LF-1.33K,1%,1/16W,CHA
GND                      R2021            2        Q_RES_0402LF-1.33K,1%,1/16W,CHA
GND                      R2038            2        Q_RES_0402LF-576,1%,1/16W,CHIPA
GND                      R2039            2        Q_RES_0402LF-576,1%,1/16W,CHIPA
GND                      R2044            2        Q_RES_0402LF-576,1%,1/16W,CHIPA
GND                      R2045            2        Q_RES_0402LF-576,1%,1/16W,CHIPA
GND                      R2074            2        Q_RES_0402LF-0,5%,1/16W,CHIP,CA
GND                      R2075            2        Q_RES_0402LF-120K,1%,1/16W,CHIA
GND                      R2076            2        Q_RES_0402LF-2.4K,1%,1/16W,CHIA
GND                      R2082            2        Q_RES_0402LF-4.7K,5%,1/16W,EMPA
GND                      R2083            2        Q_RES_0402LF-4.7K,5%,1/16W,EMPA
GND                      R2086            2        Q_RES_0402LF-0,5%,1/16W,CHIP,CA
GND                      R2087            2        Q_RES_0402LF-120K,1%,1/16W,CHIA
GND                      R2088            2        Q_RES_0402LF-2.4K,1%,1/16W,CHIA
GND                      R2090            2        Q_RES_0402LF-1K,5%,1/16W,CHIP,A
GND                      R2092            2        Q_RES_0402LF-1K,5%,1/16W,CHIP,A
GND                      R2094            2        Q_RES_0402LF-1K,5%,1/16W,CHIP,A
GND                      R2096            2        Q_RES_0402LF-1K,5%,1/16W,CHIP,A
GND                      R2098            2        Q_RES_0402LF-1K,5%,1/16W,CHIP,A
GND                      R2100            2        Q_RES_0402LF-1K,5%,1/16W,CHIP,A
GND                      R2134            2        Q_RES_0402LF-10K,1%,1/16W,CHIPA
GND                      R2137            2        Q_RES_0402LF-576,1%,1/16W,CHIPA
GND                      R2141            2        Q_RES_0402LF-2.4K,1%,1/16W,CHIA
GND                      R2142            2        Q_RES_0402LF-2.4K,1%,1/16W,CHIA
GND                      R2156            2        Q_RES_0402LF-0,5%,1/16W,CHIP,CA
GND                      R2172            2        Q_RES_0402LF-100,1%,1/16W,CHIPA
GND                      R2178            2        Q_RES_0402LF-4.7K,5%,1/16W,EMPA
GND                      R2179            2        Q_RES_0402LF-4.7K,5%,1/16W,EMPA
GND                      R2192            2        Q_RES_0402LF-1K,1%,1/16W,CHIP,A
GND                      R2194            2        Q_RES_0402LF-1K,1%,1/16W,EMPTYA
GND                      R2196            2        Q_RES_0402LF-1K,1%,1/16W,CHIP,A
GND                      R2332            2        Q_RES_0402LF-2K,1%,1/16W,EMPTYA
GND                      R2374            2        Q_RES_0402LF-2K,1%,1/16W,CHIP,A
GND                      R2385            2        Q_RES_0402LF-2K,1%,1/16W,CHIP,A
GND                      U1               A11      SOCKET4677_AZIFS054P001C01-SOCA
GND                      U1               A13      SOCKET4677_AZIFS054P001C01-SOCA
GND                      U1               A17      SOCKET4677_AZIFS054P001C01-SOCA
GND                      U1               A19      SOCKET4677_AZIFS054P001C01-SOCA
GND                      U1               A23      SOCKET4677_AZIFS054P001C01-SOCA
GND                      U1               A25      SOCKET4677_AZIFS054P001C01-SOCA
GND                      U1               A29      SOCKET4677_AZIFS054P001C01-SOCA
GND                      U1               A31      SOCKET4677_AZIFS054P001C01-SOCA
GND                      U1               A35      SOCKET4677_AZIFS054P001C01-SOCA
GND                      U1               A37      SOCKET4677_AZIFS054P001C01-SOCA
GND                      U1               A41      SOCKET4677_AZIFS054P001C01-SOCA
GND                      U1               A50      SOCKET4677_AZIFS054P001C01-SOCA
GND                      U1               A54      SOCKET4677_AZIFS054P001C01-SOCA
GND                      U1               A56      SOCKET4677_AZIFS054P001C01-SOCA
GND                      U1               A60      SOCKET4677_AZIFS054P001C01-SOCA
GND                      U1               A62      SOCKET4677_AZIFS054P001C01-SOCA
GND                      U1               AA19     SOCKET4677_AZIFS054P001C01-SOCA
GND                      U1               AA23     SOCKET4677_AZIFS054P001C01-SOCA
GND                      U1               AA25     SOCKET4677_AZIFS054P001C01-SOCA
GND                      U1               AA29     SOCKET4677_AZIFS054P001C01-SOCA
GND                      U1               AA31     SOCKET4677_AZIFS054P001C01-SOCA
GND                      U1               AA35     SOCKET4677_AZIFS054P001C01-SOCA
GND                      U1               AA37     SOCKET4677_AZIFS054P001C01-SOCA
GND                      U1               AA41     SOCKET4677_AZIFS054P001C01-SOCA
GND                      U1               AA43     SOCKET4677_AZIFS054P001C01-SOCA
GND                      U1               AA48     SOCKET4677_AZIFS054P001C01-SOCA
GND                      U1               AA50     SOCKET4677_AZIFS054P001C01-SOCA
GND                      U1               AA54     SOCKET4677_AZIFS054P001C01-SOCA
GND                      U1               AA56     SOCKET4677_AZIFS054P001C01-SOCA
GND                      U1               AA60     SOCKET4677_AZIFS054P001C01-SOCA
GND                      U1               AA62     SOCKET4677_AZIFS054P001C01-SOCA
GND                      U1               AA66     SOCKET4677_AZIFS054P001C01-SOCA
GND                      U1               AA68     SOCKET4677_AZIFS054P001C01-SOCA
GND                      U1               AA72     SOCKET4677_AZIFS054P001C01-SOCA
GND                      U1               AA74     SOCKET4677_AZIFS054P001C01-SOCA
GND                      U1               AA78     SOCKET4677_AZIFS054P001C01-SOCA
GND                      U1               AA80     SOCKET4677_AZIFS054P001C01-SOCA
GND                      U1               AA82     SOCKET4677_AZIFS054P001C01-SOCA
GND                      U1               AA84     SOCKET4677_AZIFS054P001C01-SOCA
GND                      U1               AA88     SOCKET4677_AZIFS054P001C01-SOCA
GND                      U1               AB4      SOCKET4677_AZIFS054P001C01-SOCA
GND                      U1               AB8      SOCKET4677_AZIFS054P001C01-SOCA
GND                      U1               AB12     SOCKET4677_AZIFS054P001C01-SOCA
GND                      U1               AB16     SOCKET4677_AZIFS054P001C01-SOCA
GND                      U1               AB20     SOCKET4677_AZIFS054P001C01-SOCA
GND                      U1               AB22     SOCKET4677_AZIFS054P001C01-SOCA
GND                      U1               AB26     SOCKET4677_AZIFS054P001C01-SOCA
GND                      U1               AB28     SOCKET4677_AZIFS054P001C01-SOCA
GND                      U1               AB32     SOCKET4677_AZIFS054P001C01-SOCA
GND                      U1               AB34     SOCKET4677_AZIFS054P001C01-SOCA
GND                      U1               AB38     SOCKET4677_AZIFS054P001C01-SOCA
GND                      U1               AB40     SOCKET4677_AZIFS054P001C01-SOCA
GND                      U1               AB44     SOCKET4677_AZIFS054P001C01-SOCA
GND                      U1               AB47     SOCKET4677_AZIFS054P001C01-SOCA
GND                      U1               AB51     SOCKET4677_AZIFS054P001C01-SOCA
GND                      U1               AB53     SOCKET4677_AZIFS054P001C01-SOCA
GND                      U1               AB57     SOCKET4677_AZIFS054P001C01-SOCA
GND                      U1               AB59     SOCKET4677_AZIFS054P001C01-SOCA
GND                      U1               AB63     SOCKET4677_AZIFS054P001C01-SOCA
GND                      U1               AB65     SOCKET4677_AZIFS054P001C01-SOCA
GND                      U1               AB69     SOCKET4677_AZIFS054P001C01-SOCA
GND                      U1               AB71     SOCKET4677_AZIFS054P001C01-SOCA
GND                      U1               AB75     SOCKET4677_AZIFS054P001C01-SOCA
GND                      U1               AB77     SOCKET4677_AZIFS054P001C01-SOCA
GND                      U1               AB79     SOCKET4677_AZIFS054P001C01-SOCA
GND                      U1               AB81     SOCKET4677_AZIFS054P001C01-SOCA
GND                      U1               AB83     SOCKET4677_AZIFS054P001C01-SOCA
GND                      U1               AB87     SOCKET4677_AZIFS054P001C01-SOCA
GND                      U1               AB91     SOCKET4677_AZIFS054P001C01-SOCA
GND                      U1               AC1      SOCKET4677_AZIFS054P001C01-SOCA
GND                      U1               AC5      SOCKET4677_AZIFS054P001C01-SOCA
GND                      U1               AC9      SOCKET4677_AZIFS054P001C01-SOCA
GND                      U1               AC13     SOCKET4677_AZIFS054P001C01-SOCA
GND                      U1               AC21     SOCKET4677_AZIFS054P001C01-SOCA
GND                      U1               AC27     SOCKET4677_AZIFS054P001C01-SOCA
GND                      U1               AC33     SOCKET4677_AZIFS054P001C01-SOCA
GND                      U1               AC39     SOCKET4677_AZIFS054P001C01-SOCA
GND                      U1               AC45     SOCKET4677_AZIFS054P001C01-SOCA
GND                      U1               AC52     SOCKET4677_AZIFS054P001C01-SOCA
GND                      U1               AC58     SOCKET4677_AZIFS054P001C01-SOCA
GND                      U1               AC64     SOCKET4677_AZIFS054P001C01-SOCA
GND                      U1               AC70     SOCKET4677_AZIFS054P001C01-SOCA
GND                      U1               AC76     SOCKET4677_AZIFS054P001C01-SOCA
GND                      U1               AC84     SOCKET4677_AZIFS054P001C01-SOCA
GND                      U1               AC88     SOCKET4677_AZIFS054P001C01-SOCA
GND                      U1               AD4      SOCKET4677_AZIFS054P001C01-SOCA
GND                      U1               AD8      SOCKET4677_AZIFS054P001C01-SOCA
GND                      U1               AD12     SOCKET4677_AZIFS054P001C01-SOCA
GND                      U1               AD16     SOCKET4677_AZIFS054P001C01-SOCA
GND                      U1               AD42     SOCKET4677_AZIFS054P001C01-SOCA
GND                      U1               AD79     SOCKET4677_AZIFS054P001C01-SOCA
GND                      U1               AD83     SOCKET4677_AZIFS054P001C01-SOCA
GND                      U1               AE17     SOCKET4677_AZIFS054P001C01-SOCA
GND                      U1               AE19     SOCKET4677_AZIFS054P001C01-SOCA
GND                      U1               AE21     SOCKET4677_AZIFS054P001C01-SOCA
GND                      U1               AE23     SOCKET4677_AZIFS054P001C01-SOCA
GND                      U1               AE25     SOCKET4677_AZIFS054P001C01-SOCA
GND                      U1               AE27     SOCKET4677_AZIFS054P001C01-SOCA
GND                      U1               AE29     SOCKET4677_AZIFS054P001C01-SOCA
GND                      U1               AE31     SOCKET4677_AZIFS054P001C01-SOCA
GND                      U1               AE33     SOCKET4677_AZIFS054P001C01-SOCA
GND                      U1               AE35     SOCKET4677_AZIFS054P001C01-SOCA
GND                      U1               AE37     SOCKET4677_AZIFS054P001C01-SOCA
GND                      U1               AE39     SOCKET4677_AZIFS054P001C01-SOCA
GND                      U1               AE41     SOCKET4677_AZIFS054P001C01-SOCA
GND                      U1               AE43     SOCKET4677_AZIFS054P001C01-SOCA
GND                      U1               AE45     SOCKET4677_AZIFS054P001C01-SOCA
GND                      U1               AE48     SOCKET4677_AZIFS054P001C01-SOCA
GND                      U1               AE50     SOCKET4677_AZIFS054P001C01-SOCA
GND                      U1               AE52     SOCKET4677_AZIFS054P001C01-SOCA
GND                      U1               AE54     SOCKET4677_AZIFS054P001C01-SOCA
GND                      U1               AE56     SOCKET4677_AZIFS054P001C01-SOCA
GND                      U1               AE58     SOCKET4677_AZIFS054P001C01-SOCA
GND                      U1               AE60     SOCKET4677_AZIFS054P001C01-SOCA
GND                      U1               AE62     SOCKET4677_AZIFS054P001C01-SOCA
GND                      U1               AE64     SOCKET4677_AZIFS054P001C01-SOCA
GND                      U1               AE66     SOCKET4677_AZIFS054P001C01-SOCA
GND                      U1               AE68     SOCKET4677_AZIFS054P001C01-SOCA
GND                      U1               AE70     SOCKET4677_AZIFS054P001C01-SOCA
GND                      U1               AE72     SOCKET4677_AZIFS054P001C01-SOCA
GND                      U1               AE74     SOCKET4677_AZIFS054P001C01-SOCA
GND                      U1               AE76     SOCKET4677_AZIFS054P001C01-SOCA
GND                      U1               AE78     SOCKET4677_AZIFS054P001C01-SOCA
GND                      U1               AE84     SOCKET4677_AZIFS054P001C01-SOCA
GND                      U1               AE88     SOCKET4677_AZIFS054P001C01-SOCA
GND                      U1               AF4      SOCKET4677_AZIFS054P001C01-SOCA
GND                      U1               AF8      SOCKET4677_AZIFS054P001C01-SOCA
GND                      U1               AF12     SOCKET4677_AZIFS054P001C01-SOCA
GND                      U1               AF16     SOCKET4677_AZIFS054P001C01-SOCA
GND                      U1               AF42     SOCKET4677_AZIFS054P001C01-SOCA
GND                      U1               AF81     SOCKET4677_AZIFS054P001C01-SOCA
GND                      U1               AF87     SOCKET4677_AZIFS054P001C01-SOCA
GND                      U1               AF91     SOCKET4677_AZIFS054P001C01-SOCA
GND                      U1               AG1      SOCKET4677_AZIFS054P001C01-SOCA
GND                      U1               AG5      SOCKET4677_AZIFS054P001C01-SOCA
GND                      U1               AG9      SOCKET4677_AZIFS054P001C01-SOCA
GND                      U1               AG13     SOCKET4677_AZIFS054P001C01-SOCA
GND                      U1               AG21     SOCKET4677_AZIFS054P001C01-SOCA
GND                      U1               AG27     SOCKET4677_AZIFS054P001C01-SOCA
GND                      U1               AG33     SOCKET4677_AZIFS054P001C01-SOCA
GND                      U1               AG39     SOCKET4677_AZIFS054P001C01-SOCA
GND                      U1               AG45     SOCKET4677_AZIFS054P001C01-SOCA
GND                      U1               AG52     SOCKET4677_AZIFS054P001C01-SOCA
GND                      U1               AG58     SOCKET4677_AZIFS054P001C01-SOCA
GND                      U1               AG64     SOCKET4677_AZIFS054P001C01-SOCA
GND                      U1               AG70     SOCKET4677_AZIFS054P001C01-SOCA
GND                      U1               AG76     SOCKET4677_AZIFS054P001C01-SOCA
GND                      U1               AG84     SOCKET4677_AZIFS054P001C01-SOCA
GND                      U1               AG88     SOCKET4677_AZIFS054P001C01-SOCA
GND                      U1               AH4      SOCKET4677_AZIFS054P001C01-SOCA
GND                      U1               AH8      SOCKET4677_AZIFS054P001C01-SOCA
GND                      U1               AH12     SOCKET4677_AZIFS054P001C01-SOCA
GND                      U1               AH16     SOCKET4677_AZIFS054P001C01-SOCA
GND                      U1               AH20     SOCKET4677_AZIFS054P001C01-SOCA
GND                      U1               AH22     SOCKET4677_AZIFS054P001C01-SOCA
GND                      U1               AH26     SOCKET4677_AZIFS054P001C01-SOCA
GND                      U1               AH28     SOCKET4677_AZIFS054P001C01-SOCA
GND                      U1               AH32     SOCKET4677_AZIFS054P001C01-SOCA
GND                      U1               AH34     SOCKET4677_AZIFS054P001C01-SOCA
GND                      U1               AH38     SOCKET4677_AZIFS054P001C01-SOCA
GND                      U1               AH40     SOCKET4677_AZIFS054P001C01-SOCA
GND                      U1               AH44     SOCKET4677_AZIFS054P001C01-SOCA
GND                      U1               AH47     SOCKET4677_AZIFS054P001C01-SOCA
GND                      U1               AH51     SOCKET4677_AZIFS054P001C01-SOCA
GND                      U1               AH53     SOCKET4677_AZIFS054P001C01-SOCA
GND                      U1               AH57     SOCKET4677_AZIFS054P001C01-SOCA
GND                      U1               AH59     SOCKET4677_AZIFS054P001C01-SOCA
GND                      U1               AH63     SOCKET4677_AZIFS054P001C01-SOCA
GND                      U1               AH65     SOCKET4677_AZIFS054P001C01-SOCA
GND                      U1               AH69     SOCKET4677_AZIFS054P001C01-SOCA
GND                      U1               AH71     SOCKET4677_AZIFS054P001C01-SOCA
GND                      U1               AH75     SOCKET4677_AZIFS054P001C01-SOCA
GND                      U1               AH77     SOCKET4677_AZIFS054P001C01-SOCA
GND                      U1               AH79     SOCKET4677_AZIFS054P001C01-SOCA
GND                      U1               AH83     SOCKET4677_AZIFS054P001C01-SOCA
GND                      U1               AJ19     SOCKET4677_AZIFS054P001C01-SOCA
GND                      U1               AJ23     SOCKET4677_AZIFS054P001C01-SOCA
GND                      U1               AJ25     SOCKET4677_AZIFS054P001C01-SOCA
GND                      U1               AJ29     SOCKET4677_AZIFS054P001C01-SOCA
GND                      U1               AJ31     SOCKET4677_AZIFS054P001C01-SOCA
GND                      U1               AJ35     SOCKET4677_AZIFS054P001C01-SOCA
GND                      U1               AJ37     SOCKET4677_AZIFS054P001C01-SOCA
GND                      U1               AJ41     SOCKET4677_AZIFS054P001C01-SOCA
GND                      U1               AJ43     SOCKET4677_AZIFS054P001C01-SOCA
GND                      U1               AJ48     SOCKET4677_AZIFS054P001C01-SOCA
GND                      U1               AJ50     SOCKET4677_AZIFS054P001C01-SOCA
GND                      U1               AJ54     SOCKET4677_AZIFS054P001C01-SOCA
GND                      U1               AJ56     SOCKET4677_AZIFS054P001C01-SOCA
GND                      U1               AJ60     SOCKET4677_AZIFS054P001C01-SOCA
GND                      U1               AJ62     SOCKET4677_AZIFS054P001C01-SOCA
GND                      U1               AJ66     SOCKET4677_AZIFS054P001C01-SOCA
GND                      U1               AJ68     SOCKET4677_AZIFS054P001C01-SOCA
GND                      U1               AJ72     SOCKET4677_AZIFS054P001C01-SOCA
GND                      U1               AJ74     SOCKET4677_AZIFS054P001C01-SOCA
GND                      U1               AJ78     SOCKET4677_AZIFS054P001C01-SOCA
GND                      U1               AJ84     SOCKET4677_AZIFS054P001C01-SOCA
GND                      U1               AJ88     SOCKET4677_AZIFS054P001C01-SOCA
GND                      U1               AK4      SOCKET4677_AZIFS054P001C01-SOCA
GND                      U1               AK8      SOCKET4677_AZIFS054P001C01-SOCA
GND                      U1               AK12     SOCKET4677_AZIFS054P001C01-SOCA
GND                      U1               AK16     SOCKET4677_AZIFS054P001C01-SOCA
GND                      U1               AK18     SOCKET4677_AZIFS054P001C01-SOCA
GND                      U1               AK24     SOCKET4677_AZIFS054P001C01-SOCA
GND                      U1               AK30     SOCKET4677_AZIFS054P001C01-SOCA
GND                      U1               AK36     SOCKET4677_AZIFS054P001C01-SOCA
GND                      U1               AK42     SOCKET4677_AZIFS054P001C01-SOCA
GND                      U1               AK49     SOCKET4677_AZIFS054P001C01-SOCA
GND                      U1               AK55     SOCKET4677_AZIFS054P001C01-SOCA
GND                      U1               AK61     SOCKET4677_AZIFS054P001C01-SOCA
GND                      U1               AK67     SOCKET4677_AZIFS054P001C01-SOCA
GND                      U1               AK73     SOCKET4677_AZIFS054P001C01-SOCA
GND                      U1               AK79     SOCKET4677_AZIFS054P001C01-SOCA
GND                      U1               AK81     SOCKET4677_AZIFS054P001C01-SOCA
GND                      U1               AK83     SOCKET4677_AZIFS054P001C01-SOCA
GND                      U1               AK87     SOCKET4677_AZIFS054P001C01-SOCA
GND                      U1               AK91     SOCKET4677_AZIFS054P001C01-SOCA
GND                      U1               AL1      SOCKET4677_AZIFS054P001C01-SOCA
GND                      U1               AL5      SOCKET4677_AZIFS054P001C01-SOCA
GND                      U1               AL9      SOCKET4677_AZIFS054P001C01-SOCA
GND                      U1               AL13     SOCKET4677_AZIFS054P001C01-SOCA
GND                      U1               AL17     SOCKET4677_AZIFS054P001C01-SOCA
GND                      U1               AL52     SOCKET4677_AZIFS054P001C01-SOCA
GND                      U1               AL80     SOCKET4677_AZIFS054P001C01-SOCA
GND                      U1               AL82     SOCKET4677_AZIFS054P001C01-SOCA
GND                      U1               AL84     SOCKET4677_AZIFS054P001C01-SOCA
GND                      U1               AL88     SOCKET4677_AZIFS054P001C01-SOCA
GND                      U1               AM4      SOCKET4677_AZIFS054P001C01-SOCA
GND                      U1               AM8      SOCKET4677_AZIFS054P001C01-SOCA
GND                      U1               AM12     SOCKET4677_AZIFS054P001C01-SOCA
GND                      U1               AM16     SOCKET4677_AZIFS054P001C01-SOCA
GND                      U1               AM18     SOCKET4677_AZIFS054P001C01-SOCA
GND                      U1               AM20     SOCKET4677_AZIFS054P001C01-SOCA
GND                      U1               AM22     SOCKET4677_AZIFS054P001C01-SOCA
GND                      U1               AM24     SOCKET4677_AZIFS054P001C01-SOCA
GND                      U1               AM26     SOCKET4677_AZIFS054P001C01-SOCA
GND                      U1               AM28     SOCKET4677_AZIFS054P001C01-SOCA
GND                      U1               AM30     SOCKET4677_AZIFS054P001C01-SOCA
GND                      U1               AM32     SOCKET4677_AZIFS054P001C01-SOCA
GND                      U1               AM34     SOCKET4677_AZIFS054P001C01-SOCA
GND                      U1               AM36     SOCKET4677_AZIFS054P001C01-SOCA
GND                      U1               AM38     SOCKET4677_AZIFS054P001C01-SOCA
GND                      U1               AM40     SOCKET4677_AZIFS054P001C01-SOCA
GND                      U1               AM42     SOCKET4677_AZIFS054P001C01-SOCA
GND                      U1               AM44     SOCKET4677_AZIFS054P001C01-SOCA
GND                      U1               AM47     SOCKET4677_AZIFS054P001C01-SOCA
GND                      U1               AM49     SOCKET4677_AZIFS054P001C01-SOCA
GND                      U1               AM51     SOCKET4677_AZIFS054P001C01-SOCA
GND                      U1               AM53     SOCKET4677_AZIFS054P001C01-SOCA
GND                      U1               AM55     SOCKET4677_AZIFS054P001C01-SOCA
GND                      U1               AM57     SOCKET4677_AZIFS054P001C01-SOCA
GND                      U1               AM59     SOCKET4677_AZIFS054P001C01-SOCA
GND                      U1               AM61     SOCKET4677_AZIFS054P001C01-SOCA
GND                      U1               AM63     SOCKET4677_AZIFS054P001C01-SOCA
GND                      U1               AM65     SOCKET4677_AZIFS054P001C01-SOCA
GND                      U1               AM67     SOCKET4677_AZIFS054P001C01-SOCA
GND                      U1               AM69     SOCKET4677_AZIFS054P001C01-SOCA
GND                      U1               AM71     SOCKET4677_AZIFS054P001C01-SOCA
GND                      U1               AM73     SOCKET4677_AZIFS054P001C01-SOCA
GND                      U1               AM75     SOCKET4677_AZIFS054P001C01-SOCA
GND                      U1               AM77     SOCKET4677_AZIFS054P001C01-SOCA
GND                      U1               AN52     SOCKET4677_AZIFS054P001C01-SOCA
GND                      U1               AN84     SOCKET4677_AZIFS054P001C01-SOCA
GND                      U1               AN88     SOCKET4677_AZIFS054P001C01-SOCA
GND                      U1               AP4      SOCKET4677_AZIFS054P001C01-SOCA
GND                      U1               AP8      SOCKET4677_AZIFS054P001C01-SOCA
GND                      U1               AP12     SOCKET4677_AZIFS054P001C01-SOCA
GND                      U1               AP16     SOCKET4677_AZIFS054P001C01-SOCA
GND                      U1               AP18     SOCKET4677_AZIFS054P001C01-SOCA
GND                      U1               AP24     SOCKET4677_AZIFS054P001C01-SOCA
GND                      U1               AP30     SOCKET4677_AZIFS054P001C01-SOCA
GND                      U1               AP36     SOCKET4677_AZIFS054P001C01-SOCA
GND                      U1               AP42     SOCKET4677_AZIFS054P001C01-SOCA
GND                      U1               AP49     SOCKET4677_AZIFS054P001C01-SOCA
GND                      U1               AP55     SOCKET4677_AZIFS054P001C01-SOCA
GND                      U1               AP61     SOCKET4677_AZIFS054P001C01-SOCA
GND                      U1               AP67     SOCKET4677_AZIFS054P001C01-SOCA
GND                      U1               AP73     SOCKET4677_AZIFS054P001C01-SOCA
GND                      U1               AP79     SOCKET4677_AZIFS054P001C01-SOCA
GND                      U1               AP83     SOCKET4677_AZIFS054P001C01-SOCA
GND                      U1               AP87     SOCKET4677_AZIFS054P001C01-SOCA
GND                      U1               AP91     SOCKET4677_AZIFS054P001C01-SOCA
GND                      U1               AR1      SOCKET4677_AZIFS054P001C01-SOCA
GND                      U1               AR5      SOCKET4677_AZIFS054P001C01-SOCA
GND                      U1               AR9      SOCKET4677_AZIFS054P001C01-SOCA
GND                      U1               AR13     SOCKET4677_AZIFS054P001C01-SOCA
GND                      U1               AR19     SOCKET4677_AZIFS054P001C01-SOCA
GND                      U1               AR23     SOCKET4677_AZIFS054P001C01-SOCA
GND                      U1               AR25     SOCKET4677_AZIFS054P001C01-SOCA
GND                      U1               AR29     SOCKET4677_AZIFS054P001C01-SOCA
GND                      U1               AR31     SOCKET4677_AZIFS054P001C01-SOCA
GND                      U1               AR35     SOCKET4677_AZIFS054P001C01-SOCA
GND                      U1               AR37     SOCKET4677_AZIFS054P001C01-SOCA
GND                      U1               AR41     SOCKET4677_AZIFS054P001C01-SOCA
GND                      U1               AR43     SOCKET4677_AZIFS054P001C01-SOCA
GND                      U1               AR48     SOCKET4677_AZIFS054P001C01-SOCA
GND                      U1               AR50     SOCKET4677_AZIFS054P001C01-SOCA
GND                      U1               AR54     SOCKET4677_AZIFS054P001C01-SOCA
GND                      U1               AR56     SOCKET4677_AZIFS054P001C01-SOCA
GND                      U1               AR60     SOCKET4677_AZIFS054P001C01-SOCA
GND                      U1               AR62     SOCKET4677_AZIFS054P001C01-SOCA
GND                      U1               AR66     SOCKET4677_AZIFS054P001C01-SOCA
GND                      U1               AR68     SOCKET4677_AZIFS054P001C01-SOCA
GND                      U1               AR72     SOCKET4677_AZIFS054P001C01-SOCA
GND                      U1               AR74     SOCKET4677_AZIFS054P001C01-SOCA
GND                      U1               AR78     SOCKET4677_AZIFS054P001C01-SOCA
GND                      U1               AR82     SOCKET4677_AZIFS054P001C01-SOCA
GND                      U1               AR84     SOCKET4677_AZIFS054P001C01-SOCA
GND                      U1               AR88     SOCKET4677_AZIFS054P001C01-SOCA
GND                      U1               AT4      SOCKET4677_AZIFS054P001C01-SOCA
GND                      U1               AT8      SOCKET4677_AZIFS054P001C01-SOCA
GND                      U1               AT12     SOCKET4677_AZIFS054P001C01-SOCA
GND                      U1               AT16     SOCKET4677_AZIFS054P001C01-SOCA
GND                      U1               AT20     SOCKET4677_AZIFS054P001C01-SOCA
GND                      U1               AT22     SOCKET4677_AZIFS054P001C01-SOCA
GND                      U1               AT26     SOCKET4677_AZIFS054P001C01-SOCA
GND                      U1               AT28     SOCKET4677_AZIFS054P001C01-SOCA
GND                      U1               AT32     SOCKET4677_AZIFS054P001C01-SOCA
GND                      U1               AT34     SOCKET4677_AZIFS054P001C01-SOCA
GND                      U1               AT38     SOCKET4677_AZIFS054P001C01-SOCA
GND                      U1               AT40     SOCKET4677_AZIFS054P001C01-SOCA
GND                      U1               AT44     SOCKET4677_AZIFS054P001C01-SOCA
GND                      U1               AT51     SOCKET4677_AZIFS054P001C01-SOCA
GND                      U1               AT53     SOCKET4677_AZIFS054P001C01-SOCA
GND                      U1               AT57     SOCKET4677_AZIFS054P001C01-SOCA
GND                      U1               AT59     SOCKET4677_AZIFS054P001C01-SOCA
GND                      U1               AT63     SOCKET4677_AZIFS054P001C01-SOCA
GND                      U1               AT65     SOCKET4677_AZIFS054P001C01-SOCA
GND                      U1               AT69     SOCKET4677_AZIFS054P001C01-SOCA
GND                      U1               AT71     SOCKET4677_AZIFS054P001C01-SOCA
GND                      U1               AT75     SOCKET4677_AZIFS054P001C01-SOCA
GND                      U1               AT77     SOCKET4677_AZIFS054P001C01-SOCA
GND                      U1               AT79     SOCKET4677_AZIFS054P001C01-SOCA
GND                      U1               AU27     SOCKET4677_AZIFS054P001C01-SOCA
GND                      U1               AU31     SOCKET4677_AZIFS054P001C01-SOCA
GND                      U1               AU37     SOCKET4677_AZIFS054P001C01-SOCA
GND                      U1               AU39     SOCKET4677_AZIFS054P001C01-SOCA
GND                      U1               AU41     SOCKET4677_AZIFS054P001C01-SOCA
GND                      U1               AU45     SOCKET4677_AZIFS054P001C01-SOCA
GND                      U1               AU48     SOCKET4677_AZIFS054P001C01-SOCA
GND                      U1               AU70     SOCKET4677_AZIFS054P001C01-SOCA
GND                      U1               AU72     SOCKET4677_AZIFS054P001C01-SOCA
GND                      U1               AU74     SOCKET4677_AZIFS054P001C01-SOCA
GND                      U1               AU76     SOCKET4677_AZIFS054P001C01-SOCA
GND                      U1               AU80     SOCKET4677_AZIFS054P001C01-SOCA
GND                      U1               AU84     SOCKET4677_AZIFS054P001C01-SOCA
GND                      U1               AU88     SOCKET4677_AZIFS054P001C01-SOCA
GND                      U1               AV4      SOCKET4677_AZIFS054P001C01-SOCA
GND                      U1               AV8      SOCKET4677_AZIFS054P001C01-SOCA
GND                      U1               AV12     SOCKET4677_AZIFS054P001C01-SOCA
GND                      U1               AV16     SOCKET4677_AZIFS054P001C01-SOCA
GND                      U1               AV77     SOCKET4677_AZIFS054P001C01-SOCA
GND                      U1               AV87     SOCKET4677_AZIFS054P001C01-SOCA
GND                      U1               AV91     SOCKET4677_AZIFS054P001C01-SOCA
GND                      U1               AW1      SOCKET4677_AZIFS054P001C01-SOCA
GND                      U1               AW5      SOCKET4677_AZIFS054P001C01-SOCA
GND                      U1               AW9      SOCKET4677_AZIFS054P001C01-SOCA
GND                      U1               AW13     SOCKET4677_AZIFS054P001C01-SOCA
GND                      U1               AW21     SOCKET4677_AZIFS054P001C01-SOCA
GND                      U1               AW23     SOCKET4677_AZIFS054P001C01-SOCA
GND                      U1               AW25     SOCKET4677_AZIFS054P001C01-SOCA
GND                      U1               AW62     SOCKET4677_AZIFS054P001C01-SOCA
GND                      U1               AW66     SOCKET4677_AZIFS054P001C01-SOCA
GND                      U1               AW68     SOCKET4677_AZIFS054P001C01-SOCA
GND                      U1               AW72     SOCKET4677_AZIFS054P001C01-SOCA
GND                      U1               AW80     SOCKET4677_AZIFS054P001C01-SOCA
GND                      U1               AW82     SOCKET4677_AZIFS054P001C01-SOCA
GND                      U1               AW84     SOCKET4677_AZIFS054P001C01-SOCA
GND                      U1               AW88     SOCKET4677_AZIFS054P001C01-SOCA
GND                      U1               AY4      SOCKET4677_AZIFS054P001C01-SOCA
GND                      U1               AY8      SOCKET4677_AZIFS054P001C01-SOCA
GND                      U1               AY12     SOCKET4677_AZIFS054P001C01-SOCA
GND                      U1               AY16     SOCKET4677_AZIFS054P001C01-SOCA
GND                      U1               AY71     SOCKET4677_AZIFS054P001C01-SOCA
GND                      U1               AY77     SOCKET4677_AZIFS054P001C01-SOCA
GND                      U1               AY79     SOCKET4677_AZIFS054P001C01-SOCA
GND                      U1               AY81     SOCKET4677_AZIFS054P001C01-SOCA
GND                      U1               AY83     SOCKET4677_AZIFS054P001C01-SOCA
GND                      U1               B6       SOCKET4677_AZIFS054P001C01-SOCA
GND                      U1               B12      SOCKET4677_AZIFS054P001C01-SOCA
GND                      U1               B18      SOCKET4677_AZIFS054P001C01-SOCA
GND                      U1               B24      SOCKET4677_AZIFS054P001C01-SOCA
GND                      U1               B30      SOCKET4677_AZIFS054P001C01-SOCA
GND                      U1               B36      SOCKET4677_AZIFS054P001C01-SOCA
GND                      U1               B42      SOCKET4677_AZIFS054P001C01-SOCA
GND                      U1               B49      SOCKET4677_AZIFS054P001C01-SOCA
GND                      U1               B55      SOCKET4677_AZIFS054P001C01-SOCA
GND                      U1               B61      SOCKET4677_AZIFS054P001C01-SOCA
GND                      U1               B67      SOCKET4677_AZIFS054P001C01-SOCA
GND                      U1               B75      SOCKET4677_AZIFS054P001C01-SOCA
GND                      U1               B83      SOCKET4677_AZIFS054P001C01-SOCA
GND                      U1               B87      SOCKET4677_AZIFS054P001C01-SOCA
GND                      U1               BA17     SOCKET4677_AZIFS054P001C01-SOCA
GND                      U1               BA60     SOCKET4677_AZIFS054P001C01-SOCA
GND                      U1               BA64     SOCKET4677_AZIFS054P001C01-SOCA
GND                      U1               BA74     SOCKET4677_AZIFS054P001C01-SOCA
GND                      U1               BA84     SOCKET4677_AZIFS054P001C01-SOCA
GND                      U1               BA88     SOCKET4677_AZIFS054P001C01-SOCA
GND                      U1               BB4      SOCKET4677_AZIFS054P001C01-SOCA
GND                      U1               BB8      SOCKET4677_AZIFS054P001C01-SOCA
GND                      U1               BB10     SOCKET4677_AZIFS054P001C01-SOCA
GND                      U1               BB12     SOCKET4677_AZIFS054P001C01-SOCA
GND                      U1               BB16     SOCKET4677_AZIFS054P001C01-SOCA
GND                      U1               BB20     SOCKET4677_AZIFS054P001C01-SOCA
GND                      U1               BB22     SOCKET4677_AZIFS054P001C01-SOCA
GND                      U1               BB24     SOCKET4677_AZIFS054P001C01-SOCA
GND                      U1               BB26     SOCKET4677_AZIFS054P001C01-SOCA
GND                      U1               BB63     SOCKET4677_AZIFS054P001C01-SOCA
GND                      U1               BB69     SOCKET4677_AZIFS054P001C01-SOCA
GND                      U1               BB71     SOCKET4677_AZIFS054P001C01-SOCA
GND                      U1               BB77     SOCKET4677_AZIFS054P001C01-SOCA
GND                      U1               BB79     SOCKET4677_AZIFS054P001C01-SOCA
GND                      U1               BB83     SOCKET4677_AZIFS054P001C01-SOCA
GND                      U1               BB87     SOCKET4677_AZIFS054P001C01-SOCA
GND                      U1               BB91     SOCKET4677_AZIFS054P001C01-SOCA
GND                      U1               BC1      SOCKET4677_AZIFS054P001C01-SOCA
GND                      U1               BC5      SOCKET4677_AZIFS054P001C01-SOCA
GND                      U1               BC9      SOCKET4677_AZIFS054P001C01-SOCA
GND                      U1               BC13     SOCKET4677_AZIFS054P001C01-SOCA
GND                      U1               BC17     SOCKET4677_AZIFS054P001C01-SOCA
GND                      U1               BC62     SOCKET4677_AZIFS054P001C01-SOCA
GND                      U1               BC66     SOCKET4677_AZIFS054P001C01-SOCA
GND                      U1               BC72     SOCKET4677_AZIFS054P001C01-SOCA
GND                      U1               BC76     SOCKET4677_AZIFS054P001C01-SOCA
GND                      U1               BC78     SOCKET4677_AZIFS054P001C01-SOCA
GND                      U1               BC84     SOCKET4677_AZIFS054P001C01-SOCA
GND                      U1               BC86     SOCKET4677_AZIFS054P001C01-SOCA
GND                      U1               BC88     SOCKET4677_AZIFS054P001C01-SOCA
GND                      U1               BD4      SOCKET4677_AZIFS054P001C01-SOCA
GND                      U1               BD8      SOCKET4677_AZIFS054P001C01-SOCA
GND                      U1               BD12     SOCKET4677_AZIFS054P001C01-SOCA
GND                      U1               BD16     SOCKET4677_AZIFS054P001C01-SOCA
GND                      U1               BD20     SOCKET4677_AZIFS054P001C01-SOCA
GND                      U1               BD81     SOCKET4677_AZIFS054P001C01-SOCA
GND                      U1               BD85     SOCKET4677_AZIFS054P001C01-SOCA
GND                      U1               BD89     SOCKET4677_AZIFS054P001C01-SOCA
GND                      U1               BE64     SOCKET4677_AZIFS054P001C01-SOCA
GND                      U1               BE66     SOCKET4677_AZIFS054P001C01-SOCA
GND                      U1               BE68     SOCKET4677_AZIFS054P001C01-SOCA
GND                      U1               BE74     SOCKET4677_AZIFS054P001C01-SOCA
GND                      U1               BE76     SOCKET4677_AZIFS054P001C01-SOCA
GND                      U1               BE78     SOCKET4677_AZIFS054P001C01-SOCA
GND                      U1               BE84     SOCKET4677_AZIFS054P001C01-SOCA
GND                      U1               BF4      SOCKET4677_AZIFS054P001C01-SOCA
GND                      U1               BF8      SOCKET4677_AZIFS054P001C01-SOCA
GND                      U1               BF12     SOCKET4677_AZIFS054P001C01-SOCA
GND                      U1               BF16     SOCKET4677_AZIFS054P001C01-SOCA
GND                      U1               BF20     SOCKET4677_AZIFS054P001C01-SOCA
GND                      U1               BF61     SOCKET4677_AZIFS054P001C01-SOCA
GND                      U1               BF63     SOCKET4677_AZIFS054P001C01-SOCA
GND                      U1               BF73     SOCKET4677_AZIFS054P001C01-SOCA
GND                      U1               BF75     SOCKET4677_AZIFS054P001C01-SOCA
GND                      U1               BF79     SOCKET4677_AZIFS054P001C01-SOCA
GND                      U1               BF83     SOCKET4677_AZIFS054P001C01-SOCA
GND                      U1               BG1      SOCKET4677_AZIFS054P001C01-SOCA
GND                      U1               BG5      SOCKET4677_AZIFS054P001C01-SOCA
GND                      U1               BG9      SOCKET4677_AZIFS054P001C01-SOCA
GND                      U1               BG13     SOCKET4677_AZIFS054P001C01-SOCA
GND                      U1               BG17     SOCKET4677_AZIFS054P001C01-SOCA
GND                      U1               BG21     SOCKET4677_AZIFS054P001C01-SOCA
GND                      U1               BG23     SOCKET4677_AZIFS054P001C01-SOCA
GND                      U1               BG25     SOCKET4677_AZIFS054P001C01-SOCA
GND                      U1               BG70     SOCKET4677_AZIFS054P001C01-SOCA
GND                      U1               BH4      SOCKET4677_AZIFS054P001C01-SOCA
GND                      U1               BH8      SOCKET4677_AZIFS054P001C01-SOCA
GND                      U1               BH12     SOCKET4677_AZIFS054P001C01-SOCA
GND                      U1               BH16     SOCKET4677_AZIFS054P001C01-SOCA
GND                      U1               BH20     SOCKET4677_AZIFS054P001C01-SOCA
GND                      U1               BH67     SOCKET4677_AZIFS054P001C01-SOCA
GND                      U1               BH73     SOCKET4677_AZIFS054P001C01-SOCA
GND                      U1               BH77     SOCKET4677_AZIFS054P001C01-SOCA
GND                      U1               BH81     SOCKET4677_AZIFS054P001C01-SOCA
GND                      U1               BH83     SOCKET4677_AZIFS054P001C01-SOCA
GND                      U1               BJ62     SOCKET4677_AZIFS054P001C01-SOCA
GND                      U1               BJ68     SOCKET4677_AZIFS054P001C01-SOCA
GND                      U1               BJ80     SOCKET4677_AZIFS054P001C01-SOCA
GND                      U1               BJ82     SOCKET4677_AZIFS054P001C01-SOCA
GND                      U1               BJ84     SOCKET4677_AZIFS054P001C01-SOCA
GND                      U1               BJ86     SOCKET4677_AZIFS054P001C01-SOCA
GND                      U1               BJ88     SOCKET4677_AZIFS054P001C01-SOCA
GND                      U1               BJ90     SOCKET4677_AZIFS054P001C01-SOCA
GND                      U1               BK4      SOCKET4677_AZIFS054P001C01-SOCA
GND                      U1               BK8      SOCKET4677_AZIFS054P001C01-SOCA
GND                      U1               BK12     SOCKET4677_AZIFS054P001C01-SOCA
GND                      U1               BK16     SOCKET4677_AZIFS054P001C01-SOCA
GND                      U1               BK20     SOCKET4677_AZIFS054P001C01-SOCA
GND                      U1               BK65     SOCKET4677_AZIFS054P001C01-SOCA
GND                      U1               BK71     SOCKET4677_AZIFS054P001C01-SOCA
GND                      U1               BK75     SOCKET4677_AZIFS054P001C01-SOCA
GND                      U1               BK79     SOCKET4677_AZIFS054P001C01-SOCA
GND                      U1               BL1      SOCKET4677_AZIFS054P001C01-SOCA
GND                      U1               BL5      SOCKET4677_AZIFS054P001C01-SOCA
GND                      U1               BL9      SOCKET4677_AZIFS054P001C01-SOCA
GND                      U1               BL13     SOCKET4677_AZIFS054P001C01-SOCA
GND                      U1               BL17     SOCKET4677_AZIFS054P001C01-SOCA
GND                      U1               BL68     SOCKET4677_AZIFS054P001C01-SOCA
GND                      U1               BL70     SOCKET4677_AZIFS054P001C01-SOCA
GND                      U1               BL72     SOCKET4677_AZIFS054P001C01-SOCA
GND                      U1               BL78     SOCKET4677_AZIFS054P001C01-SOCA
GND                      U1               BM4      SOCKET4677_AZIFS054P001C01-SOCA
GND                      U1               BM8      SOCKET4677_AZIFS054P001C01-SOCA
GND                      U1               BM12     SOCKET4677_AZIFS054P001C01-SOCA
GND                      U1               BM16     SOCKET4677_AZIFS054P001C01-SOCA
GND                      U1               BM20     SOCKET4677_AZIFS054P001C01-SOCA
GND                      U1               BM22     SOCKET4677_AZIFS054P001C01-SOCA
GND                      U1               BM24     SOCKET4677_AZIFS054P001C01-SOCA
GND                      U1               BM26     SOCKET4677_AZIFS054P001C01-SOCA
GND                      U1               BM61     SOCKET4677_AZIFS054P001C01-SOCA
GND                      U1               BM73     SOCKET4677_AZIFS054P001C01-SOCA
GND                      U1               BM77     SOCKET4677_AZIFS054P001C01-SOCA
GND                      U1               BN31     SOCKET4677_AZIFS054P001C01-SOCA
GND                      U1               BN62     SOCKET4677_AZIFS054P001C01-SOCA
GND                      U1               BN70     SOCKET4677_AZIFS054P001C01-SOCA
GND                      U1               BP2      SOCKET4677_AZIFS054P001C01-SOCA
GND                      U1               BP4      SOCKET4677_AZIFS054P001C01-SOCA
GND                      U1               BP8      SOCKET4677_AZIFS054P001C01-SOCA
GND                      U1               BP12     SOCKET4677_AZIFS054P001C01-SOCA
GND                      U1               BP16     SOCKET4677_AZIFS054P001C01-SOCA
GND                      U1               BP20     SOCKET4677_AZIFS054P001C01-SOCA
GND                      U1               BP63     SOCKET4677_AZIFS054P001C01-SOCA
GND                      U1               BP71     SOCKET4677_AZIFS054P001C01-SOCA
GND                      U1               BP73     SOCKET4677_AZIFS054P001C01-SOCA
GND                      U1               BP75     SOCKET4677_AZIFS054P001C01-SOCA
GND                      U1               BP77     SOCKET4677_AZIFS054P001C01-SOCA
GND                      U1               BR5      SOCKET4677_AZIFS054P001C01-SOCA
GND                      U1               BR9      SOCKET4677_AZIFS054P001C01-SOCA
GND                      U1               BR13     SOCKET4677_AZIFS054P001C01-SOCA
GND                      U1               BR17     SOCKET4677_AZIFS054P001C01-SOCA
GND                      U1               BR27     SOCKET4677_AZIFS054P001C01-SOCA
GND                      U1               BR29     SOCKET4677_AZIFS054P001C01-SOCA
GND                      U1               BR31     SOCKET4677_AZIFS054P001C01-SOCA
GND                      U1               BR33     SOCKET4677_AZIFS054P001C01-SOCA
GND                      U1               BR35     SOCKET4677_AZIFS054P001C01-SOCA
GND                      U1               BR37     SOCKET4677_AZIFS054P001C01-SOCA
GND                      U1               BR39     SOCKET4677_AZIFS054P001C01-SOCA
GND                      U1               BR41     SOCKET4677_AZIFS054P001C01-SOCA
GND                      U1               BR43     SOCKET4677_AZIFS054P001C01-SOCA
GND                      U1               BR45     SOCKET4677_AZIFS054P001C01-SOCA
GND                      U1               BR48     SOCKET4677_AZIFS054P001C01-SOCA
GND                      U1               BR50     SOCKET4677_AZIFS054P001C01-SOCA
GND                      U1               BR52     SOCKET4677_AZIFS054P001C01-SOCA
GND                      U1               BR54     SOCKET4677_AZIFS054P001C01-SOCA
GND                      U1               BR56     SOCKET4677_AZIFS054P001C01-SOCA
GND                      U1               BR58     SOCKET4677_AZIFS054P001C01-SOCA
GND                      U1               BR64     SOCKET4677_AZIFS054P001C01-SOCA
GND                      U1               BR66     SOCKET4677_AZIFS054P001C01-SOCA
GND                      U1               BR68     SOCKET4677_AZIFS054P001C01-SOCA
GND                      U1               BR70     SOCKET4677_AZIFS054P001C01-SOCA
GND                      U1               BR72     SOCKET4677_AZIFS054P001C01-SOCA
GND                      U1               BR74     SOCKET4677_AZIFS054P001C01-SOCA
GND                      U1               BR76     SOCKET4677_AZIFS054P001C01-SOCA
GND                      U1               BR80     SOCKET4677_AZIFS054P001C01-SOCA
GND                      U1               BR82     SOCKET4677_AZIFS054P001C01-SOCA
GND                      U1               BR84     SOCKET4677_AZIFS054P001C01-SOCA
GND                      U1               BR86     SOCKET4677_AZIFS054P001C01-SOCA
GND                      U1               BR88     SOCKET4677_AZIFS054P001C01-SOCA
GND                      U1               BR90     SOCKET4677_AZIFS054P001C01-SOCA
GND                      U1               BT4      SOCKET4677_AZIFS054P001C01-SOCA
GND                      U1               BT8      SOCKET4677_AZIFS054P001C01-SOCA
GND                      U1               BT12     SOCKET4677_AZIFS054P001C01-SOCA
GND                      U1               BT16     SOCKET4677_AZIFS054P001C01-SOCA
GND                      U1               BT20     SOCKET4677_AZIFS054P001C01-SOCA
GND                      U1               BU7      SOCKET4677_AZIFS054P001C01-SOCA
GND                      U1               BU15     SOCKET4677_AZIFS054P001C01-SOCA
GND                      U1               BU19     SOCKET4677_AZIFS054P001C01-SOCA
GND                      U1               BU21     SOCKET4677_AZIFS054P001C01-SOCA
GND                      U1               BU23     SOCKET4677_AZIFS054P001C01-SOCA
GND                      U1               BU25     SOCKET4677_AZIFS054P001C01-SOCA
GND                      U1               BU31     SOCKET4677_AZIFS054P001C01-SOCA
GND                      U1               BV2      SOCKET4677_AZIFS054P001C01-SOCA
GND                      U1               BV4      SOCKET4677_AZIFS054P001C01-SOCA
GND                      U1               BV6      SOCKET4677_AZIFS054P001C01-SOCA
GND                      U1               BV8      SOCKET4677_AZIFS054P001C01-SOCA
GND                      U1               BV12     SOCKET4677_AZIFS054P001C01-SOCA
GND                      U1               BV16     SOCKET4677_AZIFS054P001C01-SOCA
GND                      U1               BV18     SOCKET4677_AZIFS054P001C01-SOCA
GND                      U1               BV20     SOCKET4677_AZIFS054P001C01-SOCA
GND                      U1               BW3      SOCKET4677_AZIFS054P001C01-SOCA
GND                      U1               BW5      SOCKET4677_AZIFS054P001C01-SOCA
GND                      U1               BW9      SOCKET4677_AZIFS054P001C01-SOCA
GND                      U1               BW13     SOCKET4677_AZIFS054P001C01-SOCA
GND                      U1               BW17     SOCKET4677_AZIFS054P001C01-SOCA
GND                      U1               BW27     SOCKET4677_AZIFS054P001C01-SOCA
GND                      U1               BW29     SOCKET4677_AZIFS054P001C01-SOCA
GND                      U1               BW31     SOCKET4677_AZIFS054P001C01-SOCA
GND                      U1               BY4      SOCKET4677_AZIFS054P001C01-SOCA
GND                      U1               BY8      SOCKET4677_AZIFS054P001C01-SOCA
GND                      U1               BY12     SOCKET4677_AZIFS054P001C01-SOCA
GND                      U1               BY16     SOCKET4677_AZIFS054P001C01-SOCA
GND                      U1               BY20     SOCKET4677_AZIFS054P001C01-SOCA
GND                      U1               C5       SOCKET4677_AZIFS054P001C01-SOCA
GND                      U1               C39      SOCKET4677_AZIFS054P001C01-SOCA
GND                      U1               C45      SOCKET4677_AZIFS054P001C01-SOCA
GND                      U1               C52      SOCKET4677_AZIFS054P001C01-SOCA
GND                      U1               C72      SOCKET4677_AZIFS054P001C01-SOCA
GND                      U1               C74      SOCKET4677_AZIFS054P001C01-SOCA
GND                      U1               C78      SOCKET4677_AZIFS054P001C01-SOCA
GND                      U1               C80      SOCKET4677_AZIFS054P001C01-SOCA
GND                      U1               C82      SOCKET4677_AZIFS054P001C01-SOCA
GND                      U1               C86      SOCKET4677_AZIFS054P001C01-SOCA
GND                      U1               CA3      SOCKET4677_AZIFS054P001C01-SOCA
GND                      U1               CA31     SOCKET4677_AZIFS054P001C01-SOCA
GND                      U1               CB4      SOCKET4677_AZIFS054P001C01-SOCA
GND                      U1               CB8      SOCKET4677_AZIFS054P001C01-SOCA
GND                      U1               CB12     SOCKET4677_AZIFS054P001C01-SOCA
GND                      U1               CB16     SOCKET4677_AZIFS054P001C01-SOCA
GND                      U1               CB20     SOCKET4677_AZIFS054P001C01-SOCA
GND                      U1               CB22     SOCKET4677_AZIFS054P001C01-SOCA
GND                      U1               CB24     SOCKET4677_AZIFS054P001C01-SOCA
GND                      U1               CB26     SOCKET4677_AZIFS054P001C01-SOCA
GND                      U1               CB28     SOCKET4677_AZIFS054P001C01-SOCA
GND                      U1               CB32     SOCKET4677_AZIFS054P001C01-SOCA
GND                      U1               CB34     SOCKET4677_AZIFS054P001C01-SOCA
GND                      U1               CB36     SOCKET4677_AZIFS054P001C01-SOCA
GND                      U1               CB38     SOCKET4677_AZIFS054P001C01-SOCA
GND                      U1               CB40     SOCKET4677_AZIFS054P001C01-SOCA
GND                      U1               CB42     SOCKET4677_AZIFS054P001C01-SOCA
GND                      U1               CB44     SOCKET4677_AZIFS054P001C01-SOCA
GND                      U1               CB47     SOCKET4677_AZIFS054P001C01-SOCA
GND                      U1               CB49     SOCKET4677_AZIFS054P001C01-SOCA
GND                      U1               CB51     SOCKET4677_AZIFS054P001C01-SOCA
GND                      U1               CB53     SOCKET4677_AZIFS054P001C01-SOCA
GND                      U1               CB55     SOCKET4677_AZIFS054P001C01-SOCA
GND                      U1               CB57     SOCKET4677_AZIFS054P001C01-SOCA
GND                      U1               CB59     SOCKET4677_AZIFS054P001C01-SOCA
GND                      U1               CB63     SOCKET4677_AZIFS054P001C01-SOCA
GND                      U1               CB65     SOCKET4677_AZIFS054P001C01-SOCA
GND                      U1               CB67     SOCKET4677_AZIFS054P001C01-SOCA
GND                      U1               CB69     SOCKET4677_AZIFS054P001C01-SOCA
GND                      U1               CB71     SOCKET4677_AZIFS054P001C01-SOCA
GND                      U1               CB73     SOCKET4677_AZIFS054P001C01-SOCA
GND                      U1               CB79     SOCKET4677_AZIFS054P001C01-SOCA
GND                      U1               CB81     SOCKET4677_AZIFS054P001C01-SOCA
GND                      U1               CB83     SOCKET4677_AZIFS054P001C01-SOCA
GND                      U1               CB85     SOCKET4677_AZIFS054P001C01-SOCA
GND                      U1               CB87     SOCKET4677_AZIFS054P001C01-SOCA
GND                      U1               CB89     SOCKET4677_AZIFS054P001C01-SOCA
GND                      U1               CC5      SOCKET4677_AZIFS054P001C01-SOCA
GND                      U1               CC9      SOCKET4677_AZIFS054P001C01-SOCA
GND                      U1               CC13     SOCKET4677_AZIFS054P001C01-SOCA
GND                      U1               CC17     SOCKET4677_AZIFS054P001C01-SOCA
GND                      U1               CC31     SOCKET4677_AZIFS054P001C01-SOCA
GND                      U1               CC62     SOCKET4677_AZIFS054P001C01-SOCA
GND                      U1               CC70     SOCKET4677_AZIFS054P001C01-SOCA
GND                      U1               CC72     SOCKET4677_AZIFS054P001C01-SOCA
GND                      U1               CC74     SOCKET4677_AZIFS054P001C01-SOCA
GND                      U1               CD4      SOCKET4677_AZIFS054P001C01-SOCA
GND                      U1               CD8      SOCKET4677_AZIFS054P001C01-SOCA
GND                      U1               CD12     SOCKET4677_AZIFS054P001C01-SOCA
GND                      U1               CD16     SOCKET4677_AZIFS054P001C01-SOCA
GND                      U1               CD20     SOCKET4677_AZIFS054P001C01-SOCA
GND                      U1               CD61     SOCKET4677_AZIFS054P001C01-SOCA
GND                      U1               CD75     SOCKET4677_AZIFS054P001C01-SOCA
GND                      U1               CD77     SOCKET4677_AZIFS054P001C01-SOCA
GND                      U1               CE3      SOCKET4677_AZIFS054P001C01-SOCA
GND                      U1               CE60     SOCKET4677_AZIFS054P001C01-SOCA
GND                      U1               CE66     SOCKET4677_AZIFS054P001C01-SOCA
GND                      U1               CE72     SOCKET4677_AZIFS054P001C01-SOCA
GND                      U1               CE76     SOCKET4677_AZIFS054P001C01-SOCA
GND                      U1               CE78     SOCKET4677_AZIFS054P001C01-SOCA
GND                      U1               CF4      SOCKET4677_AZIFS054P001C01-SOCA
GND                      U1               CF8      SOCKET4677_AZIFS054P001C01-SOCA
GND                      U1               CF12     SOCKET4677_AZIFS054P001C01-SOCA
GND                      U1               CF16     SOCKET4677_AZIFS054P001C01-SOCA
GND                      U1               CF20     SOCKET4677_AZIFS054P001C01-SOCA
GND                      U1               CF69     SOCKET4677_AZIFS054P001C01-SOCA
GND                      U1               CF71     SOCKET4677_AZIFS054P001C01-SOCA
GND                      U1               CG1      SOCKET4677_AZIFS054P001C01-SOCA
GND                      U1               CG5      SOCKET4677_AZIFS054P001C01-SOCA
GND                      U1               CG9      SOCKET4677_AZIFS054P001C01-SOCA
GND                      U1               CG13     SOCKET4677_AZIFS054P001C01-SOCA
GND                      U1               CG17     SOCKET4677_AZIFS054P001C01-SOCA
GND                      U1               CG21     SOCKET4677_AZIFS054P001C01-SOCA
GND                      U1               CG23     SOCKET4677_AZIFS054P001C01-SOCA
GND                      U1               CG25     SOCKET4677_AZIFS054P001C01-SOCA
GND                      U1               CG62     SOCKET4677_AZIFS054P001C01-SOCA
GND                      U1               CG64     SOCKET4677_AZIFS054P001C01-SOCA
GND                      U1               CG70     SOCKET4677_AZIFS054P001C01-SOCA
GND                      U1               CG72     SOCKET4677_AZIFS054P001C01-SOCA
GND                      U1               CG74     SOCKET4677_AZIFS054P001C01-SOCA
GND                      U1               CG78     SOCKET4677_AZIFS054P001C01-SOCA
GND                      U1               CH4      SOCKET4677_AZIFS054P001C01-SOCA
GND                      U1               CH8      SOCKET4677_AZIFS054P001C01-SOCA
GND                      U1               CH12     SOCKET4677_AZIFS054P001C01-SOCA
GND                      U1               CH16     SOCKET4677_AZIFS054P001C01-SOCA
GND                      U1               CH20     SOCKET4677_AZIFS054P001C01-SOCA
GND                      U1               CH67     SOCKET4677_AZIFS054P001C01-SOCA
GND                      U1               CH73     SOCKET4677_AZIFS054P001C01-SOCA
GND                      U1               CH79     SOCKET4677_AZIFS054P001C01-SOCA
GND                      U1               CH83     SOCKET4677_AZIFS054P001C01-SOCA
GND                      U1               CH85     SOCKET4677_AZIFS054P001C01-SOCA
GND                      U1               CH87     SOCKET4677_AZIFS054P001C01-SOCA
GND                      U1               CH89     SOCKET4677_AZIFS054P001C01-SOCA
GND                      U1               CJ60     SOCKET4677_AZIFS054P001C01-SOCA
GND                      U1               CJ76     SOCKET4677_AZIFS054P001C01-SOCA
GND                      U1               CJ80     SOCKET4677_AZIFS054P001C01-SOCA
GND                      U1               CK4      SOCKET4677_AZIFS054P001C01-SOCA
GND                      U1               CK8      SOCKET4677_AZIFS054P001C01-SOCA
GND                      U1               CK12     SOCKET4677_AZIFS054P001C01-SOCA
GND                      U1               CK16     SOCKET4677_AZIFS054P001C01-SOCA
GND                      U1               CK20     SOCKET4677_AZIFS054P001C01-SOCA
GND                      U1               CK26     SOCKET4677_AZIFS054P001C01-SOCA
GND                      U1               CK63     SOCKET4677_AZIFS054P001C01-SOCA
GND                      U1               CK69     SOCKET4677_AZIFS054P001C01-SOCA
GND                      U1               CK81     SOCKET4677_AZIFS054P001C01-SOCA
GND                      U1               CL1      SOCKET4677_AZIFS054P001C01-SOCA
GND                      U1               CL5      SOCKET4677_AZIFS054P001C01-SOCA
GND                      U1               CL9      SOCKET4677_AZIFS054P001C01-SOCA
GND                      U1               CL13     SOCKET4677_AZIFS054P001C01-SOCA
GND                      U1               CL17     SOCKET4677_AZIFS054P001C01-SOCA
GND                      U1               CL62     SOCKET4677_AZIFS054P001C01-SOCA
GND                      U1               CL74     SOCKET4677_AZIFS054P001C01-SOCA
GND                      U1               CL78     SOCKET4677_AZIFS054P001C01-SOCA
GND                      U1               CL80     SOCKET4677_AZIFS054P001C01-SOCA
GND                      U1               CL82     SOCKET4677_AZIFS054P001C01-SOCA
GND                      U1               CM4      SOCKET4677_AZIFS054P001C01-SOCA
GND                      U1               CM8      SOCKET4677_AZIFS054P001C01-SOCA
GND                      U1               CM12     SOCKET4677_AZIFS054P001C01-SOCA
GND                      U1               CM16     SOCKET4677_AZIFS054P001C01-SOCA
GND                      U1               CM20     SOCKET4677_AZIFS054P001C01-SOCA
GND                      U1               CM22     SOCKET4677_AZIFS054P001C01-SOCA
GND                      U1               CM24     SOCKET4677_AZIFS054P001C01-SOCA
GND                      U1               CM61     SOCKET4677_AZIFS054P001C01-SOCA
GND                      U1               CM65     SOCKET4677_AZIFS054P001C01-SOCA
GND                      U1               CM67     SOCKET4677_AZIFS054P001C01-SOCA
GND                      U1               CM79     SOCKET4677_AZIFS054P001C01-SOCA
GND                      U1               CM81     SOCKET4677_AZIFS054P001C01-SOCA
GND                      U1               CM83     SOCKET4677_AZIFS054P001C01-SOCA
GND                      U1               CM85     SOCKET4677_AZIFS054P001C01-SOCA
GND                      U1               CN68     SOCKET4677_AZIFS054P001C01-SOCA
GND                      U1               CN70     SOCKET4677_AZIFS054P001C01-SOCA
GND                      U1               CN72     SOCKET4677_AZIFS054P001C01-SOCA
GND                      U1               CN74     SOCKET4677_AZIFS054P001C01-SOCA
GND                      U1               CN76     SOCKET4677_AZIFS054P001C01-SOCA
GND                      U1               CN84     SOCKET4677_AZIFS054P001C01-SOCA
GND                      U1               CN86     SOCKET4677_AZIFS054P001C01-SOCA
GND                      U1               CP4      SOCKET4677_AZIFS054P001C01-SOCA
GND                      U1               CP8      SOCKET4677_AZIFS054P001C01-SOCA
GND                      U1               CP12     SOCKET4677_AZIFS054P001C01-SOCA
GND                      U1               CP16     SOCKET4677_AZIFS054P001C01-SOCA
GND                      U1               CP18     SOCKET4677_AZIFS054P001C01-SOCA
GND                      U1               CP75     SOCKET4677_AZIFS054P001C01-SOCA
GND                      U1               CP77     SOCKET4677_AZIFS054P001C01-SOCA
GND                      U1               CP79     SOCKET4677_AZIFS054P001C01-SOCA
GND                      U1               CP83     SOCKET4677_AZIFS054P001C01-SOCA
GND                      U1               CP87     SOCKET4677_AZIFS054P001C01-SOCA
GND                      U1               CP91     SOCKET4677_AZIFS054P001C01-SOCA
GND                      U1               CR1      SOCKET4677_AZIFS054P001C01-SOCA
GND                      U1               CR5      SOCKET4677_AZIFS054P001C01-SOCA
GND                      U1               CR9      SOCKET4677_AZIFS054P001C01-SOCA
GND                      U1               CR11     SOCKET4677_AZIFS054P001C01-SOCA
GND                      U1               CR13     SOCKET4677_AZIFS054P001C01-SOCA
GND                      U1               CR17     SOCKET4677_AZIFS054P001C01-SOCA
GND                      U1               CR62     SOCKET4677_AZIFS054P001C01-SOCA
GND                      U1               CR64     SOCKET4677_AZIFS054P001C01-SOCA
GND                      U1               CR78     SOCKET4677_AZIFS054P001C01-SOCA
GND                      U1               CR84     SOCKET4677_AZIFS054P001C01-SOCA
GND                      U1               CR88     SOCKET4677_AZIFS054P001C01-SOCA
GND                      U1               CR90     SOCKET4677_AZIFS054P001C01-SOCA
GND                      U1               CT4      SOCKET4677_AZIFS054P001C01-SOCA
GND                      U1               CT8      SOCKET4677_AZIFS054P001C01-SOCA
GND                      U1               CT10     SOCKET4677_AZIFS054P001C01-SOCA
GND                      U1               CT12     SOCKET4677_AZIFS054P001C01-SOCA
GND                      U1               CT16     SOCKET4677_AZIFS054P001C01-SOCA
GND                      U1               CT69     SOCKET4677_AZIFS054P001C01-SOCA
GND                      U1               CT73     SOCKET4677_AZIFS054P001C01-SOCA
GND                      U1               CT81     SOCKET4677_AZIFS054P001C01-SOCA
GND                      U1               CT89     SOCKET4677_AZIFS054P001C01-SOCA
GND                      U1               CU19     SOCKET4677_AZIFS054P001C01-SOCA
GND                      U1               CU21     SOCKET4677_AZIFS054P001C01-SOCA
GND                      U1               CU23     SOCKET4677_AZIFS054P001C01-SOCA
GND                      U1               CU25     SOCKET4677_AZIFS054P001C01-SOCA
GND                      U1               CU60     SOCKET4677_AZIFS054P001C01-SOCA
GND                      U1               CU66     SOCKET4677_AZIFS054P001C01-SOCA
GND                      U1               CU68     SOCKET4677_AZIFS054P001C01-SOCA
GND                      U1               CU72     SOCKET4677_AZIFS054P001C01-SOCA
GND                      U1               CU78     SOCKET4677_AZIFS054P001C01-SOCA
GND                      U1               CU84     SOCKET4677_AZIFS054P001C01-SOCA
GND                      U1               CU88     SOCKET4677_AZIFS054P001C01-SOCA
GND                      U1               CV4      SOCKET4677_AZIFS054P001C01-SOCA
GND                      U1               CV8      SOCKET4677_AZIFS054P001C01-SOCA
GND                      U1               CV12     SOCKET4677_AZIFS054P001C01-SOCA
GND                      U1               CV16     SOCKET4677_AZIFS054P001C01-SOCA
GND                      U1               CV26     SOCKET4677_AZIFS054P001C01-SOCA
GND                      U1               CV75     SOCKET4677_AZIFS054P001C01-SOCA
GND                      U1               CV79     SOCKET4677_AZIFS054P001C01-SOCA
GND                      U1               CV83     SOCKET4677_AZIFS054P001C01-SOCA
GND                      U1               CV87     SOCKET4677_AZIFS054P001C01-SOCA
GND                      U1               CV91     SOCKET4677_AZIFS054P001C01-SOCA
GND                      U1               CW1      SOCKET4677_AZIFS054P001C01-SOCA
GND                      U1               CW5      SOCKET4677_AZIFS054P001C01-SOCA
GND                      U1               CW9      SOCKET4677_AZIFS054P001C01-SOCA
GND                      U1               CW13     SOCKET4677_AZIFS054P001C01-SOCA
GND                      U1               CW17     SOCKET4677_AZIFS054P001C01-SOCA
GND                      U1               CW33     SOCKET4677_AZIFS054P001C01-SOCA
GND                      U1               CW70     SOCKET4677_AZIFS054P001C01-SOCA
GND                      U1               CW72     SOCKET4677_AZIFS054P001C01-SOCA
GND                      U1               CW78     SOCKET4677_AZIFS054P001C01-SOCA
GND                      U1               CW84     SOCKET4677_AZIFS054P001C01-SOCA
GND                      U1               CW88     SOCKET4677_AZIFS054P001C01-SOCA
GND                      U1               CY4      SOCKET4677_AZIFS054P001C01-SOCA
GND                      U1               CY8      SOCKET4677_AZIFS054P001C01-SOCA
GND                      U1               CY12     SOCKET4677_AZIFS054P001C01-SOCA
GND                      U1               CY16     SOCKET4677_AZIFS054P001C01-SOCA
GND                      U1               CY18     SOCKET4677_AZIFS054P001C01-SOCA
GND                      U1               CY26     SOCKET4677_AZIFS054P001C01-SOCA
GND                      U1               CY30     SOCKET4677_AZIFS054P001C01-SOCA
GND                      U1               CY63     SOCKET4677_AZIFS054P001C01-SOCA
GND                      U1               CY73     SOCKET4677_AZIFS054P001C01-SOCA
GND                      U1               CY77     SOCKET4677_AZIFS054P001C01-SOCA
GND                      U1               CY81     SOCKET4677_AZIFS054P001C01-SOCA
GND                      U1               CY83     SOCKET4677_AZIFS054P001C01-SOCA
GND                      U1               D6       SOCKET4677_AZIFS054P001C01-SOCA
GND                      U1               D8       SOCKET4677_AZIFS054P001C01-SOCA
GND                      U1               D10      SOCKET4677_AZIFS054P001C01-SOCA
GND                      U1               D12      SOCKET4677_AZIFS054P001C01-SOCA
GND                      U1               D14      SOCKET4677_AZIFS054P001C01-SOCA
GND                      U1               D16      SOCKET4677_AZIFS054P001C01-SOCA
GND                      U1               D18      SOCKET4677_AZIFS054P001C01-SOCA
GND                      U1               D20      SOCKET4677_AZIFS054P001C01-SOCA
GND                      U1               D22      SOCKET4677_AZIFS054P001C01-SOCA
GND                      U1               D24      SOCKET4677_AZIFS054P001C01-SOCA
GND                      U1               D26      SOCKET4677_AZIFS054P001C01-SOCA
GND                      U1               D28      SOCKET4677_AZIFS054P001C01-SOCA
GND                      U1               D30      SOCKET4677_AZIFS054P001C01-SOCA
GND                      U1               D32      SOCKET4677_AZIFS054P001C01-SOCA
GND                      U1               D34      SOCKET4677_AZIFS054P001C01-SOCA
GND                      U1               D36      SOCKET4677_AZIFS054P001C01-SOCA
GND                      U1               D38      SOCKET4677_AZIFS054P001C01-SOCA
GND                      U1               D40      SOCKET4677_AZIFS054P001C01-SOCA
GND                      U1               D42      SOCKET4677_AZIFS054P001C01-SOCA
GND                      U1               D44      SOCKET4677_AZIFS054P001C01-SOCA
GND                      U1               D47      SOCKET4677_AZIFS054P001C01-SOCA
GND                      U1               D49      SOCKET4677_AZIFS054P001C01-SOCA
GND                      U1               D51      SOCKET4677_AZIFS054P001C01-SOCA
GND                      U1               D53      SOCKET4677_AZIFS054P001C01-SOCA
GND                      U1               D55      SOCKET4677_AZIFS054P001C01-SOCA
GND                      U1               D57      SOCKET4677_AZIFS054P001C01-SOCA
GND                      U1               D59      SOCKET4677_AZIFS054P001C01-SOCA
GND                      U1               D61      SOCKET4677_AZIFS054P001C01-SOCA
GND                      U1               D63      SOCKET4677_AZIFS054P001C01-SOCA
GND                      U1               D65      SOCKET4677_AZIFS054P001C01-SOCA
GND                      U1               D67      SOCKET4677_AZIFS054P001C01-SOCA
GND                      U1               D69      SOCKET4677_AZIFS054P001C01-SOCA
GND                      U1               D71      SOCKET4677_AZIFS054P001C01-SOCA
GND                      U1               D79      SOCKET4677_AZIFS054P001C01-SOCA
GND                      U1               D81      SOCKET4677_AZIFS054P001C01-SOCA
GND                      U1               D83      SOCKET4677_AZIFS054P001C01-SOCA
GND                      U1               DA19     SOCKET4677_AZIFS054P001C01-SOCA
GND                      U1               DA23     SOCKET4677_AZIFS054P001C01-SOCA
GND                      U1               DA25     SOCKET4677_AZIFS054P001C01-SOCA
GND                      U1               DA29     SOCKET4677_AZIFS054P001C01-SOCA
GND                      U1               DA31     SOCKET4677_AZIFS054P001C01-SOCA
GND                      U1               DA33     SOCKET4677_AZIFS054P001C01-SOCA
GND                      U1               DA35     SOCKET4677_AZIFS054P001C01-SOCA
GND                      U1               DA37     SOCKET4677_AZIFS054P001C01-SOCA
GND                      U1               DA41     SOCKET4677_AZIFS054P001C01-SOCA
GND                      U1               DA43     SOCKET4677_AZIFS054P001C01-SOCA
GND                      U1               DA48     SOCKET4677_AZIFS054P001C01-SOCA
GND                      U1               DA50     SOCKET4677_AZIFS054P001C01-SOCA
GND                      U1               DA54     SOCKET4677_AZIFS054P001C01-SOCA
GND                      U1               DA56     SOCKET4677_AZIFS054P001C01-SOCA
GND                      U1               DA58     SOCKET4677_AZIFS054P001C01-SOCA
GND                      U1               DA60     SOCKET4677_AZIFS054P001C01-SOCA
GND                      U1               DA62     SOCKET4677_AZIFS054P001C01-SOCA
GND                      U1               DA66     SOCKET4677_AZIFS054P001C01-SOCA
GND                      U1               DA68     SOCKET4677_AZIFS054P001C01-SOCA
GND                      U1               DA72     SOCKET4677_AZIFS054P001C01-SOCA
GND                      U1               DA74     SOCKET4677_AZIFS054P001C01-SOCA
GND                      U1               DA80     SOCKET4677_AZIFS054P001C01-SOCA
GND                      U1               DA82     SOCKET4677_AZIFS054P001C01-SOCA
GND                      U1               DA84     SOCKET4677_AZIFS054P001C01-SOCA
GND                      U1               DA88     SOCKET4677_AZIFS054P001C01-SOCA
GND                      U1               DB4      SOCKET4677_AZIFS054P001C01-SOCA
GND                      U1               DB8      SOCKET4677_AZIFS054P001C01-SOCA
GND                      U1               DB12     SOCKET4677_AZIFS054P001C01-SOCA
GND                      U1               DB16     SOCKET4677_AZIFS054P001C01-SOCA
GND                      U1               DB20     SOCKET4677_AZIFS054P001C01-SOCA
GND                      U1               DB22     SOCKET4677_AZIFS054P001C01-SOCA
GND                      U1               DB26     SOCKET4677_AZIFS054P001C01-SOCA
GND                      U1               DB28     SOCKET4677_AZIFS054P001C01-SOCA
GND                      U1               DB32     SOCKET4677_AZIFS054P001C01-SOCA
GND                      U1               DB34     SOCKET4677_AZIFS054P001C01-SOCA
GND                      U1               DB38     SOCKET4677_AZIFS054P001C01-SOCA
GND                      U1               DB40     SOCKET4677_AZIFS054P001C01-SOCA
GND                      U1               DB44     SOCKET4677_AZIFS054P001C01-SOCA
GND                      U1               DB47     SOCKET4677_AZIFS054P001C01-SOCA
GND                      U1               DB51     SOCKET4677_AZIFS054P001C01-SOCA
GND                      U1               DB53     SOCKET4677_AZIFS054P001C01-SOCA
GND                      U1               DB57     SOCKET4677_AZIFS054P001C01-SOCA
GND                      U1               DB59     SOCKET4677_AZIFS054P001C01-SOCA
GND                      U1               DB63     SOCKET4677_AZIFS054P001C01-SOCA
GND                      U1               DB65     SOCKET4677_AZIFS054P001C01-SOCA
GND                      U1               DB69     SOCKET4677_AZIFS054P001C01-SOCA
GND                      U1               DB71     SOCKET4677_AZIFS054P001C01-SOCA
GND                      U1               DB75     SOCKET4677_AZIFS054P001C01-SOCA
GND                      U1               DB77     SOCKET4677_AZIFS054P001C01-SOCA
GND                      U1               DB87     SOCKET4677_AZIFS054P001C01-SOCA
GND                      U1               DB91     SOCKET4677_AZIFS054P001C01-SOCA
GND                      U1               DC1      SOCKET4677_AZIFS054P001C01-SOCA
GND                      U1               DC5      SOCKET4677_AZIFS054P001C01-SOCA
GND                      U1               DC9      SOCKET4677_AZIFS054P001C01-SOCA
GND                      U1               DC13     SOCKET4677_AZIFS054P001C01-SOCA
GND                      U1               DC21     SOCKET4677_AZIFS054P001C01-SOCA
GND                      U1               DC27     SOCKET4677_AZIFS054P001C01-SOCA
GND                      U1               DC33     SOCKET4677_AZIFS054P001C01-SOCA
GND                      U1               DC39     SOCKET4677_AZIFS054P001C01-SOCA
GND                      U1               DC45     SOCKET4677_AZIFS054P001C01-SOCA
GND                      U1               DC52     SOCKET4677_AZIFS054P001C01-SOCA
GND                      U1               DC58     SOCKET4677_AZIFS054P001C01-SOCA
GND                      U1               DC64     SOCKET4677_AZIFS054P001C01-SOCA
GND                      U1               DC70     SOCKET4677_AZIFS054P001C01-SOCA
GND                      U1               DC76     SOCKET4677_AZIFS054P001C01-SOCA
GND                      U1               DC78     SOCKET4677_AZIFS054P001C01-SOCA
GND                      U1               DC80     SOCKET4677_AZIFS054P001C01-SOCA
GND                      U1               DC84     SOCKET4677_AZIFS054P001C01-SOCA
GND                      U1               DC88     SOCKET4677_AZIFS054P001C01-SOCA
GND                      U1               DD4      SOCKET4677_AZIFS054P001C01-SOCA
GND                      U1               DD8      SOCKET4677_AZIFS054P001C01-SOCA
GND                      U1               DD12     SOCKET4677_AZIFS054P001C01-SOCA
GND                      U1               DD16     SOCKET4677_AZIFS054P001C01-SOCA
GND                      U1               DD49     SOCKET4677_AZIFS054P001C01-SOCA
GND                      U1               DD79     SOCKET4677_AZIFS054P001C01-SOCA
GND                      U1               DE17     SOCKET4677_AZIFS054P001C01-SOCA
GND                      U1               DE19     SOCKET4677_AZIFS054P001C01-SOCA
GND                      U1               DE21     SOCKET4677_AZIFS054P001C01-SOCA
GND                      U1               DE23     SOCKET4677_AZIFS054P001C01-SOCA
GND                      U1               DE25     SOCKET4677_AZIFS054P001C01-SOCA
GND                      U1               DE27     SOCKET4677_AZIFS054P001C01-SOCA
GND                      U1               DE29     SOCKET4677_AZIFS054P001C01-SOCA
GND                      U1               DE31     SOCKET4677_AZIFS054P001C01-SOCA
GND                      U1               DE33     SOCKET4677_AZIFS054P001C01-SOCA
GND                      U1               DE35     SOCKET4677_AZIFS054P001C01-SOCA
GND                      U1               DE37     SOCKET4677_AZIFS054P001C01-SOCA
GND                      U1               DE39     SOCKET4677_AZIFS054P001C01-SOCA
GND                      U1               DE41     SOCKET4677_AZIFS054P001C01-SOCA
GND                      U1               DE43     SOCKET4677_AZIFS054P001C01-SOCA
GND                      U1               DE45     SOCKET4677_AZIFS054P001C01-SOCA
GND                      U1               DE48     SOCKET4677_AZIFS054P001C01-SOCA
GND                      U1               DE50     SOCKET4677_AZIFS054P001C01-SOCA
GND                      U1               DE52     SOCKET4677_AZIFS054P001C01-SOCA
GND                      U1               DE54     SOCKET4677_AZIFS054P001C01-SOCA
GND                      U1               DE56     SOCKET4677_AZIFS054P001C01-SOCA
GND                      U1               DE58     SOCKET4677_AZIFS054P001C01-SOCA
GND                      U1               DE60     SOCKET4677_AZIFS054P001C01-SOCA
GND                      U1               DE62     SOCKET4677_AZIFS054P001C01-SOCA
GND                      U1               DE64     SOCKET4677_AZIFS054P001C01-SOCA
GND                      U1               DE66     SOCKET4677_AZIFS054P001C01-SOCA
GND                      U1               DE68     SOCKET4677_AZIFS054P001C01-SOCA
GND                      U1               DE70     SOCKET4677_AZIFS054P001C01-SOCA
GND                      U1               DE72     SOCKET4677_AZIFS054P001C01-SOCA
GND                      U1               DE74     SOCKET4677_AZIFS054P001C01-SOCA
GND                      U1               DE76     SOCKET4677_AZIFS054P001C01-SOCA
GND                      U1               DE82     SOCKET4677_AZIFS054P001C01-SOCA
GND                      U1               DE84     SOCKET4677_AZIFS054P001C01-SOCA
GND                      U1               DE88     SOCKET4677_AZIFS054P001C01-SOCA
GND                      U1               DF4      SOCKET4677_AZIFS054P001C01-SOCA
GND                      U1               DF8      SOCKET4677_AZIFS054P001C01-SOCA
GND                      U1               DF12     SOCKET4677_AZIFS054P001C01-SOCA
GND                      U1               DF16     SOCKET4677_AZIFS054P001C01-SOCA
GND                      U1               DF49     SOCKET4677_AZIFS054P001C01-SOCA
GND                      U1               DF79     SOCKET4677_AZIFS054P001C01-SOCA
GND                      U1               DF87     SOCKET4677_AZIFS054P001C01-SOCA
GND                      U1               DF91     SOCKET4677_AZIFS054P001C01-SOCA
GND                      U1               DG1      SOCKET4677_AZIFS054P001C01-SOCA
GND                      U1               DG5      SOCKET4677_AZIFS054P001C01-SOCA
GND                      U1               DG9      SOCKET4677_AZIFS054P001C01-SOCA
GND                      U1               DG13     SOCKET4677_AZIFS054P001C01-SOCA
GND                      U1               DG21     SOCKET4677_AZIFS054P001C01-SOCA
GND                      U1               DG27     SOCKET4677_AZIFS054P001C01-SOCA
GND                      U1               DG33     SOCKET4677_AZIFS054P001C01-SOCA
GND                      U1               DG39     SOCKET4677_AZIFS054P001C01-SOCA
GND                      U1               DG45     SOCKET4677_AZIFS054P001C01-SOCA
GND                      U1               DG52     SOCKET4677_AZIFS054P001C01-SOCA
GND                      U1               DG58     SOCKET4677_AZIFS054P001C01-SOCA
GND                      U1               DG64     SOCKET4677_AZIFS054P001C01-SOCA
GND                      U1               DG70     SOCKET4677_AZIFS054P001C01-SOCA
GND                      U1               DG76     SOCKET4677_AZIFS054P001C01-SOCA
GND                      U1               DG80     SOCKET4677_AZIFS054P001C01-SOCA
GND                      U1               DG84     SOCKET4677_AZIFS054P001C01-SOCA
GND                      U1               DG88     SOCKET4677_AZIFS054P001C01-SOCA
GND                      U1               DH4      SOCKET4677_AZIFS054P001C01-SOCA
GND                      U1               DH8      SOCKET4677_AZIFS054P001C01-SOCA
GND                      U1               DH12     SOCKET4677_AZIFS054P001C01-SOCA
GND                      U1               DH16     SOCKET4677_AZIFS054P001C01-SOCA
GND                      U1               DH20     SOCKET4677_AZIFS054P001C01-SOCA
GND                      U1               DH22     SOCKET4677_AZIFS054P001C01-SOCA
GND                      U1               DH26     SOCKET4677_AZIFS054P001C01-SOCA
GND                      U1               DH28     SOCKET4677_AZIFS054P001C01-SOCA
GND                      U1               DH32     SOCKET4677_AZIFS054P001C01-SOCA
GND                      U1               DH34     SOCKET4677_AZIFS054P001C01-SOCA
GND                      U1               DH38     SOCKET4677_AZIFS054P001C01-SOCA
GND                      U1               DH40     SOCKET4677_AZIFS054P001C01-SOCA
GND                      U1               DH44     SOCKET4677_AZIFS054P001C01-SOCA
GND                      U1               DH47     SOCKET4677_AZIFS054P001C01-SOCA
GND                      U1               DH51     SOCKET4677_AZIFS054P001C01-SOCA
GND                      U1               DH53     SOCKET4677_AZIFS054P001C01-SOCA
GND                      U1               DH57     SOCKET4677_AZIFS054P001C01-SOCA
GND                      U1               DH59     SOCKET4677_AZIFS054P001C01-SOCA
GND                      U1               DH63     SOCKET4677_AZIFS054P001C01-SOCA
GND                      U1               DH65     SOCKET4677_AZIFS054P001C01-SOCA
GND                      U1               DH69     SOCKET4677_AZIFS054P001C01-SOCA
GND                      U1               DH71     SOCKET4677_AZIFS054P001C01-SOCA
GND                      U1               DH75     SOCKET4677_AZIFS054P001C01-SOCA
GND                      U1               DH77     SOCKET4677_AZIFS054P001C01-SOCA
GND                      U1               DH85     SOCKET4677_AZIFS054P001C01-SOCA
GND                      U1               DJ19     SOCKET4677_AZIFS054P001C01-SOCA
GND                      U1               DJ23     SOCKET4677_AZIFS054P001C01-SOCA
GND                      U1               DJ25     SOCKET4677_AZIFS054P001C01-SOCA
GND                      U1               DJ29     SOCKET4677_AZIFS054P001C01-SOCA
GND                      U1               DJ31     SOCKET4677_AZIFS054P001C01-SOCA
GND                      U1               DJ35     SOCKET4677_AZIFS054P001C01-SOCA
GND                      U1               DJ37     SOCKET4677_AZIFS054P001C01-SOCA
GND                      U1               DJ41     SOCKET4677_AZIFS054P001C01-SOCA
GND                      U1               DJ43     SOCKET4677_AZIFS054P001C01-SOCA
GND                      U1               DJ48     SOCKET4677_AZIFS054P001C01-SOCA
GND                      U1               DJ50     SOCKET4677_AZIFS054P001C01-SOCA
GND                      U1               DJ54     SOCKET4677_AZIFS054P001C01-SOCA
GND                      U1               DJ56     SOCKET4677_AZIFS054P001C01-SOCA
GND                      U1               DJ60     SOCKET4677_AZIFS054P001C01-SOCA
GND                      U1               DJ62     SOCKET4677_AZIFS054P001C01-SOCA
GND                      U1               DJ66     SOCKET4677_AZIFS054P001C01-SOCA
GND                      U1               DJ68     SOCKET4677_AZIFS054P001C01-SOCA
GND                      U1               DJ72     SOCKET4677_AZIFS054P001C01-SOCA
GND                      U1               DJ74     SOCKET4677_AZIFS054P001C01-SOCA
GND                      U1               DJ80     SOCKET4677_AZIFS054P001C01-SOCA
GND                      U1               DJ82     SOCKET4677_AZIFS054P001C01-SOCA
GND                      U1               DJ84     SOCKET4677_AZIFS054P001C01-SOCA
GND                      U1               DJ88     SOCKET4677_AZIFS054P001C01-SOCA
GND                      U1               DK4      SOCKET4677_AZIFS054P001C01-SOCA
GND                      U1               DK8      SOCKET4677_AZIFS054P001C01-SOCA
GND                      U1               DK12     SOCKET4677_AZIFS054P001C01-SOCA
GND                      U1               DK16     SOCKET4677_AZIFS054P001C01-SOCA
GND                      U1               DK18     SOCKET4677_AZIFS054P001C01-SOCA
GND                      U1               DK24     SOCKET4677_AZIFS054P001C01-SOCA
GND                      U1               DK30     SOCKET4677_AZIFS054P001C01-SOCA
GND                      U1               DK36     SOCKET4677_AZIFS054P001C01-SOCA
GND                      U1               DK42     SOCKET4677_AZIFS054P001C01-SOCA
GND                      U1               DK49     SOCKET4677_AZIFS054P001C01-SOCA
GND                      U1               DK55     SOCKET4677_AZIFS054P001C01-SOCA
GND                      U1               DK61     SOCKET4677_AZIFS054P001C01-SOCA
GND                      U1               DK67     SOCKET4677_AZIFS054P001C01-SOCA
GND                      U1               DK73     SOCKET4677_AZIFS054P001C01-SOCA
GND                      U1               DK77     SOCKET4677_AZIFS054P001C01-SOCA
GND                      U1               DK79     SOCKET4677_AZIFS054P001C01-SOCA
GND                      U1               DK81     SOCKET4677_AZIFS054P001C01-SOCA
GND                      U1               DK83     SOCKET4677_AZIFS054P001C01-SOCA
GND                      U1               DK87     SOCKET4677_AZIFS054P001C01-SOCA
GND                      U1               DK91     SOCKET4677_AZIFS054P001C01-SOCA
GND                      U1               DL1      SOCKET4677_AZIFS054P001C01-SOCA
GND                      U1               DL5      SOCKET4677_AZIFS054P001C01-SOCA
GND                      U1               DL9      SOCKET4677_AZIFS054P001C01-SOCA
GND                      U1               DL13     SOCKET4677_AZIFS054P001C01-SOCA
GND                      U1               DL17     SOCKET4677_AZIFS054P001C01-SOCA
GND                      U1               DL39     SOCKET4677_AZIFS054P001C01-SOCA
GND                      U1               DL52     SOCKET4677_AZIFS054P001C01-SOCA
GND                      U1               DL84     SOCKET4677_AZIFS054P001C01-SOCA
GND                      U1               DL88     SOCKET4677_AZIFS054P001C01-SOCA
GND                      U1               DM4      SOCKET4677_AZIFS054P001C01-SOCA
GND                      U1               DM8      SOCKET4677_AZIFS054P001C01-SOCA
GND                      U1               DM12     SOCKET4677_AZIFS054P001C01-SOCA
GND                      U1               DM16     SOCKET4677_AZIFS054P001C01-SOCA
GND                      U1               DM18     SOCKET4677_AZIFS054P001C01-SOCA
GND                      U1               DM20     SOCKET4677_AZIFS054P001C01-SOCA
GND                      U1               DM22     SOCKET4677_AZIFS054P001C01-SOCA
GND                      U1               DM24     SOCKET4677_AZIFS054P001C01-SOCA
GND                      U1               DM26     SOCKET4677_AZIFS054P001C01-SOCA
GND                      U1               DM28     SOCKET4677_AZIFS054P001C01-SOCA
GND                      U1               DM30     SOCKET4677_AZIFS054P001C01-SOCA
GND                      U1               DM32     SOCKET4677_AZIFS054P001C01-SOCA
GND                      U1               DM34     SOCKET4677_AZIFS054P001C01-SOCA
GND                      U1               DM36     SOCKET4677_AZIFS054P001C01-SOCA
GND                      U1               DM38     SOCKET4677_AZIFS054P001C01-SOCA
GND                      U1               DM40     SOCKET4677_AZIFS054P001C01-SOCA
GND                      U1               DM42     SOCKET4677_AZIFS054P001C01-SOCA
GND                      U1               DM44     SOCKET4677_AZIFS054P001C01-SOCA
GND                      U1               DM47     SOCKET4677_AZIFS054P001C01-SOCA
GND                      U1               DM49     SOCKET4677_AZIFS054P001C01-SOCA
GND                      U1               DM51     SOCKET4677_AZIFS054P001C01-SOCA
GND                      U1               DM53     SOCKET4677_AZIFS054P001C01-SOCA
GND                      U1               DM55     SOCKET4677_AZIFS054P001C01-SOCA
GND                      U1               DM57     SOCKET4677_AZIFS054P001C01-SOCA
GND                      U1               DM59     SOCKET4677_AZIFS054P001C01-SOCA
GND                      U1               DM61     SOCKET4677_AZIFS054P001C01-SOCA
GND                      U1               DM63     SOCKET4677_AZIFS054P001C01-SOCA
GND                      U1               DM65     SOCKET4677_AZIFS054P001C01-SOCA
GND                      U1               DM67     SOCKET4677_AZIFS054P001C01-SOCA
GND                      U1               DM69     SOCKET4677_AZIFS054P001C01-SOCA
GND                      U1               DM71     SOCKET4677_AZIFS054P001C01-SOCA
GND                      U1               DM73     SOCKET4677_AZIFS054P001C01-SOCA
GND                      U1               DM75     SOCKET4677_AZIFS054P001C01-SOCA
GND                      U1               DM77     SOCKET4677_AZIFS054P001C01-SOCA
GND                      U1               DM79     SOCKET4677_AZIFS054P001C01-SOCA
GND                      U1               DN17     SOCKET4677_AZIFS054P001C01-SOCA
GND                      U1               DN39     SOCKET4677_AZIFS054P001C01-SOCA
GND                      U1               DN52     SOCKET4677_AZIFS054P001C01-SOCA
GND                      U1               DN78     SOCKET4677_AZIFS054P001C01-SOCA
GND                      U1               DN84     SOCKET4677_AZIFS054P001C01-SOCA
GND                      U1               DN88     SOCKET4677_AZIFS054P001C01-SOCA
GND                      U1               DP4      SOCKET4677_AZIFS054P001C01-SOCA
GND                      U1               DP8      SOCKET4677_AZIFS054P001C01-SOCA
GND                      U1               DP12     SOCKET4677_AZIFS054P001C01-SOCA
GND                      U1               DP16     SOCKET4677_AZIFS054P001C01-SOCA
GND                      U1               DP18     SOCKET4677_AZIFS054P001C01-SOCA
GND                      U1               DP24     SOCKET4677_AZIFS054P001C01-SOCA
GND                      U1               DP30     SOCKET4677_AZIFS054P001C01-SOCA
GND                      U1               DP36     SOCKET4677_AZIFS054P001C01-SOCA
GND                      U1               DP42     SOCKET4677_AZIFS054P001C01-SOCA
GND                      U1               DP49     SOCKET4677_AZIFS054P001C01-SOCA
GND                      U1               DP55     SOCKET4677_AZIFS054P001C01-SOCA
GND                      U1               DP61     SOCKET4677_AZIFS054P001C01-SOCA
GND                      U1               DP67     SOCKET4677_AZIFS054P001C01-SOCA
GND                      U1               DP73     SOCKET4677_AZIFS054P001C01-SOCA
GND                      U1               DP81     SOCKET4677_AZIFS054P001C01-SOCA
GND                      U1               DP87     SOCKET4677_AZIFS054P001C01-SOCA
GND                      U1               DP91     SOCKET4677_AZIFS054P001C01-SOCA
GND                      U1               DR1      SOCKET4677_AZIFS054P001C01-SOCA
GND                      U1               DR5      SOCKET4677_AZIFS054P001C01-SOCA
GND                      U1               DR9      SOCKET4677_AZIFS054P001C01-SOCA
GND                      U1               DR13     SOCKET4677_AZIFS054P001C01-SOCA
GND                      U1               DR19     SOCKET4677_AZIFS054P001C01-SOCA
GND                      U1               DR23     SOCKET4677_AZIFS054P001C01-SOCA
GND                      U1               DR25     SOCKET4677_AZIFS054P001C01-SOCA
GND                      U1               DR29     SOCKET4677_AZIFS054P001C01-SOCA
GND                      U1               DR31     SOCKET4677_AZIFS054P001C01-SOCA
GND                      U1               DR35     SOCKET4677_AZIFS054P001C01-SOCA
GND                      U1               DR37     SOCKET4677_AZIFS054P001C01-SOCA
GND                      U1               DR41     SOCKET4677_AZIFS054P001C01-SOCA
GND                      U1               DR43     SOCKET4677_AZIFS054P001C01-SOCA
GND                      U1               DR48     SOCKET4677_AZIFS054P001C01-SOCA
GND                      U1               DR50     SOCKET4677_AZIFS054P001C01-SOCA
GND                      U1               DR54     SOCKET4677_AZIFS054P001C01-SOCA
GND                      U1               DR56     SOCKET4677_AZIFS054P001C01-SOCA
GND                      U1               DR60     SOCKET4677_AZIFS054P001C01-SOCA
GND                      U1               DR62     SOCKET4677_AZIFS054P001C01-SOCA
GND                      U1               DR66     SOCKET4677_AZIFS054P001C01-SOCA
GND                      U1               DR68     SOCKET4677_AZIFS054P001C01-SOCA
GND                      U1               DR72     SOCKET4677_AZIFS054P001C01-SOCA
GND                      U1               DR74     SOCKET4677_AZIFS054P001C01-SOCA
GND                      U1               DR78     SOCKET4677_AZIFS054P001C01-SOCA
GND                      U1               DR84     SOCKET4677_AZIFS054P001C01-SOCA
GND                      U1               DR88     SOCKET4677_AZIFS054P001C01-SOCA
GND                      U1               DT4      SOCKET4677_AZIFS054P001C01-SOCA
GND                      U1               DT8      SOCKET4677_AZIFS054P001C01-SOCA
GND                      U1               DT12     SOCKET4677_AZIFS054P001C01-SOCA
GND                      U1               DT16     SOCKET4677_AZIFS054P001C01-SOCA
GND                      U1               DT20     SOCKET4677_AZIFS054P001C01-SOCA
GND                      U1               DT22     SOCKET4677_AZIFS054P001C01-SOCA
GND                      U1               DT26     SOCKET4677_AZIFS054P001C01-SOCA
GND                      U1               DT28     SOCKET4677_AZIFS054P001C01-SOCA
GND                      U1               DT32     SOCKET4677_AZIFS054P001C01-SOCA
GND                      U1               DT34     SOCKET4677_AZIFS054P001C01-SOCA
GND                      U1               DT38     SOCKET4677_AZIFS054P001C01-SOCA
GND                      U1               DT40     SOCKET4677_AZIFS054P001C01-SOCA
GND                      U1               DT44     SOCKET4677_AZIFS054P001C01-SOCA
GND                      U1               DT47     SOCKET4677_AZIFS054P001C01-SOCA
GND                      U1               DT51     SOCKET4677_AZIFS054P001C01-SOCA
GND                      U1               DT53     SOCKET4677_AZIFS054P001C01-SOCA
GND                      U1               DT57     SOCKET4677_AZIFS054P001C01-SOCA
GND                      U1               DT59     SOCKET4677_AZIFS054P001C01-SOCA
GND                      U1               DT63     SOCKET4677_AZIFS054P001C01-SOCA
GND                      U1               DT65     SOCKET4677_AZIFS054P001C01-SOCA
GND                      U1               DT69     SOCKET4677_AZIFS054P001C01-SOCA
GND                      U1               DT71     SOCKET4677_AZIFS054P001C01-SOCA
GND                      U1               DT75     SOCKET4677_AZIFS054P001C01-SOCA
GND                      U1               DT83     SOCKET4677_AZIFS054P001C01-SOCA
GND                      U1               DU21     SOCKET4677_AZIFS054P001C01-SOCA
GND                      U1               DU27     SOCKET4677_AZIFS054P001C01-SOCA
GND                      U1               DU33     SOCKET4677_AZIFS054P001C01-SOCA
GND                      U1               DU39     SOCKET4677_AZIFS054P001C01-SOCA
GND                      U1               DU45     SOCKET4677_AZIFS054P001C01-SOCA
GND                      U1               DU52     SOCKET4677_AZIFS054P001C01-SOCA
GND                      U1               DU58     SOCKET4677_AZIFS054P001C01-SOCA
GND                      U1               DU64     SOCKET4677_AZIFS054P001C01-SOCA
GND                      U1               DU70     SOCKET4677_AZIFS054P001C01-SOCA
GND                      U1               DU76     SOCKET4677_AZIFS054P001C01-SOCA
GND                      U1               DU78     SOCKET4677_AZIFS054P001C01-SOCA
GND                      U1               DU84     SOCKET4677_AZIFS054P001C01-SOCA
GND                      U1               DU88     SOCKET4677_AZIFS054P001C01-SOCA
GND                      U1               DV4      SOCKET4677_AZIFS054P001C01-SOCA
GND                      U1               DV8      SOCKET4677_AZIFS054P001C01-SOCA
GND                      U1               DV12     SOCKET4677_AZIFS054P001C01-SOCA
GND                      U1               DV16     SOCKET4677_AZIFS054P001C01-SOCA
GND                      U1               DV42     SOCKET4677_AZIFS054P001C01-SOCA
GND                      U1               DV77     SOCKET4677_AZIFS054P001C01-SOCA
GND                      U1               DV79     SOCKET4677_AZIFS054P001C01-SOCA
GND                      U1               DV81     SOCKET4677_AZIFS054P001C01-SOCA
GND                      U1               DV83     SOCKET4677_AZIFS054P001C01-SOCA
GND                      U1               DV87     SOCKET4677_AZIFS054P001C01-SOCA
GND                      U1               DV91     SOCKET4677_AZIFS054P001C01-SOCA
GND                      U1               DW1      SOCKET4677_AZIFS054P001C01-SOCA
GND                      U1               DW5      SOCKET4677_AZIFS054P001C01-SOCA
GND                      U1               DW9      SOCKET4677_AZIFS054P001C01-SOCA
GND                      U1               DW13     SOCKET4677_AZIFS054P001C01-SOCA
GND                      U1               DW17     SOCKET4677_AZIFS054P001C01-SOCA
GND                      U1               DW19     SOCKET4677_AZIFS054P001C01-SOCA
GND                      U1               DW21     SOCKET4677_AZIFS054P001C01-SOCA
GND                      U1               DW23     SOCKET4677_AZIFS054P001C01-SOCA
GND                      U1               DW25     SOCKET4677_AZIFS054P001C01-SOCA
GND                      U1               DW27     SOCKET4677_AZIFS054P001C01-SOCA
GND                      U1               DW29     SOCKET4677_AZIFS054P001C01-SOCA
GND                      U1               DW31     SOCKET4677_AZIFS054P001C01-SOCA
GND                      U1               DW33     SOCKET4677_AZIFS054P001C01-SOCA
GND                      U1               DW35     SOCKET4677_AZIFS054P001C01-SOCA
GND                      U1               DW37     SOCKET4677_AZIFS054P001C01-SOCA
GND                      U1               DW39     SOCKET4677_AZIFS054P001C01-SOCA
GND                      U1               DW41     SOCKET4677_AZIFS054P001C01-SOCA
GND                      U1               DW43     SOCKET4677_AZIFS054P001C01-SOCA
GND                      U1               DW45     SOCKET4677_AZIFS054P001C01-SOCA
GND                      U1               DW48     SOCKET4677_AZIFS054P001C01-SOCA
GND                      U1               DW50     SOCKET4677_AZIFS054P001C01-SOCA
GND                      U1               DW52     SOCKET4677_AZIFS054P001C01-SOCA
GND                      U1               DW54     SOCKET4677_AZIFS054P001C01-SOCA
GND                      U1               DW56     SOCKET4677_AZIFS054P001C01-SOCA
GND                      U1               DW58     SOCKET4677_AZIFS054P001C01-SOCA
GND                      U1               DW60     SOCKET4677_AZIFS054P001C01-SOCA
GND                      U1               DW62     SOCKET4677_AZIFS054P001C01-SOCA
GND                      U1               DW64     SOCKET4677_AZIFS054P001C01-SOCA
GND                      U1               DW66     SOCKET4677_AZIFS054P001C01-SOCA
GND                      U1               DW68     SOCKET4677_AZIFS054P001C01-SOCA
GND                      U1               DW70     SOCKET4677_AZIFS054P001C01-SOCA
GND                      U1               DW72     SOCKET4677_AZIFS054P001C01-SOCA
GND                      U1               DW74     SOCKET4677_AZIFS054P001C01-SOCA
GND                      U1               DW76     SOCKET4677_AZIFS054P001C01-SOCA
GND                      U1               DW80     SOCKET4677_AZIFS054P001C01-SOCA
GND                      U1               DW82     SOCKET4677_AZIFS054P001C01-SOCA
GND                      U1               DW84     SOCKET4677_AZIFS054P001C01-SOCA
GND                      U1               DW88     SOCKET4677_AZIFS054P001C01-SOCA
GND                      U1               DY4      SOCKET4677_AZIFS054P001C01-SOCA
GND                      U1               DY8      SOCKET4677_AZIFS054P001C01-SOCA
GND                      U1               DY12     SOCKET4677_AZIFS054P001C01-SOCA
GND                      U1               DY16     SOCKET4677_AZIFS054P001C01-SOCA
GND                      U1               DY42     SOCKET4677_AZIFS054P001C01-SOCA
GND                      U1               DY77     SOCKET4677_AZIFS054P001C01-SOCA
GND                      U1               E5       SOCKET4677_AZIFS054P001C01-SOCA
GND                      U1               E39      SOCKET4677_AZIFS054P001C01-SOCA
GND                      U1               E52      SOCKET4677_AZIFS054P001C01-SOCA
GND                      U1               E74      SOCKET4677_AZIFS054P001C01-SOCA
GND                      U1               E76      SOCKET4677_AZIFS054P001C01-SOCA
GND                      U1               E78      SOCKET4677_AZIFS054P001C01-SOCA
GND                      U1               E86      SOCKET4677_AZIFS054P001C01-SOCA
GND                      U1               EA21     SOCKET4677_AZIFS054P001C01-SOCA
GND                      U1               EA27     SOCKET4677_AZIFS054P001C01-SOCA
GND                      U1               EA33     SOCKET4677_AZIFS054P001C01-SOCA
GND                      U1               EA39     SOCKET4677_AZIFS054P001C01-SOCA
GND                      U1               EA45     SOCKET4677_AZIFS054P001C01-SOCA
GND                      U1               EA52     SOCKET4677_AZIFS054P001C01-SOCA
GND                      U1               EA58     SOCKET4677_AZIFS054P001C01-SOCA
GND                      U1               EA64     SOCKET4677_AZIFS054P001C01-SOCA
GND                      U1               EA70     SOCKET4677_AZIFS054P001C01-SOCA
GND                      U1               EA76     SOCKET4677_AZIFS054P001C01-SOCA
GND                      U1               EA78     SOCKET4677_AZIFS054P001C01-SOCA
GND                      U1               EA80     SOCKET4677_AZIFS054P001C01-SOCA
GND                      U1               EA84     SOCKET4677_AZIFS054P001C01-SOCA
GND                      U1               EA88     SOCKET4677_AZIFS054P001C01-SOCA
GND                      U1               EB4      SOCKET4677_AZIFS054P001C01-SOCA
GND                      U1               EB8      SOCKET4677_AZIFS054P001C01-SOCA
GND                      U1               EB12     SOCKET4677_AZIFS054P001C01-SOCA
GND                      U1               EB16     SOCKET4677_AZIFS054P001C01-SOCA
GND                      U1               EB20     SOCKET4677_AZIFS054P001C01-SOCA
GND                      U1               EB22     SOCKET4677_AZIFS054P001C01-SOCA
GND                      U1               EB26     SOCKET4677_AZIFS054P001C01-SOCA
GND                      U1               EB28     SOCKET4677_AZIFS054P001C01-SOCA
GND                      U1               EB32     SOCKET4677_AZIFS054P001C01-SOCA
GND                      U1               EB34     SOCKET4677_AZIFS054P001C01-SOCA
GND                      U1               EB38     SOCKET4677_AZIFS054P001C01-SOCA
GND                      U1               EB40     SOCKET4677_AZIFS054P001C01-SOCA
GND                      U1               EB44     SOCKET4677_AZIFS054P001C01-SOCA
GND                      U1               EB47     SOCKET4677_AZIFS054P001C01-SOCA
GND                      U1               EB51     SOCKET4677_AZIFS054P001C01-SOCA
GND                      U1               EB53     SOCKET4677_AZIFS054P001C01-SOCA
GND                      U1               EB57     SOCKET4677_AZIFS054P001C01-SOCA
GND                      U1               EB59     SOCKET4677_AZIFS054P001C01-SOCA
GND                      U1               EB63     SOCKET4677_AZIFS054P001C01-SOCA
GND                      U1               EB65     SOCKET4677_AZIFS054P001C01-SOCA
GND                      U1               EB69     SOCKET4677_AZIFS054P001C01-SOCA
GND                      U1               EB71     SOCKET4677_AZIFS054P001C01-SOCA
GND                      U1               EB75     SOCKET4677_AZIFS054P001C01-SOCA
GND                      U1               EB79     SOCKET4677_AZIFS054P001C01-SOCA
GND                      U1               EB83     SOCKET4677_AZIFS054P001C01-SOCA
GND                      U1               EB87     SOCKET4677_AZIFS054P001C01-SOCA
GND                      U1               EB91     SOCKET4677_AZIFS054P001C01-SOCA
GND                      U1               EC1      SOCKET4677_AZIFS054P001C01-SOCA
GND                      U1               EC5      SOCKET4677_AZIFS054P001C01-SOCA
GND                      U1               EC9      SOCKET4677_AZIFS054P001C01-SOCA
GND                      U1               EC13     SOCKET4677_AZIFS054P001C01-SOCA
GND                      U1               EC19     SOCKET4677_AZIFS054P001C01-SOCA
GND                      U1               EC23     SOCKET4677_AZIFS054P001C01-SOCA
GND                      U1               EC25     SOCKET4677_AZIFS054P001C01-SOCA
GND                      U1               EC29     SOCKET4677_AZIFS054P001C01-SOCA
GND                      U1               EC31     SOCKET4677_AZIFS054P001C01-SOCA
GND                      U1               EC35     SOCKET4677_AZIFS054P001C01-SOCA
GND                      U1               EC37     SOCKET4677_AZIFS054P001C01-SOCA
GND                      U1               EC41     SOCKET4677_AZIFS054P001C01-SOCA
GND                      U1               EC43     SOCKET4677_AZIFS054P001C01-SOCA
GND                      U1               EC48     SOCKET4677_AZIFS054P001C01-SOCA
GND                      U1               EC50     SOCKET4677_AZIFS054P001C01-SOCA
GND                      U1               EC54     SOCKET4677_AZIFS054P001C01-SOCA
GND                      U1               EC56     SOCKET4677_AZIFS054P001C01-SOCA
GND                      U1               EC60     SOCKET4677_AZIFS054P001C01-SOCA
GND                      U1               EC62     SOCKET4677_AZIFS054P001C01-SOCA
GND                      U1               EC66     SOCKET4677_AZIFS054P001C01-SOCA
GND                      U1               EC68     SOCKET4677_AZIFS054P001C01-SOCA
GND                      U1               EC72     SOCKET4677_AZIFS054P001C01-SOCA
GND                      U1               EC74     SOCKET4677_AZIFS054P001C01-SOCA
GND                      U1               EC82     SOCKET4677_AZIFS054P001C01-SOCA
GND                      U1               EC84     SOCKET4677_AZIFS054P001C01-SOCA
GND                      U1               EC88     SOCKET4677_AZIFS054P001C01-SOCA
GND                      U1               ED4      SOCKET4677_AZIFS054P001C01-SOCA
GND                      U1               ED8      SOCKET4677_AZIFS054P001C01-SOCA
GND                      U1               ED12     SOCKET4677_AZIFS054P001C01-SOCA
GND                      U1               ED16     SOCKET4677_AZIFS054P001C01-SOCA
GND                      U1               ED18     SOCKET4677_AZIFS054P001C01-SOCA
GND                      U1               ED24     SOCKET4677_AZIFS054P001C01-SOCA
GND                      U1               ED30     SOCKET4677_AZIFS054P001C01-SOCA
GND                      U1               ED36     SOCKET4677_AZIFS054P001C01-SOCA
GND                      U1               ED42     SOCKET4677_AZIFS054P001C01-SOCA
GND                      U1               ED49     SOCKET4677_AZIFS054P001C01-SOCA
GND                      U1               ED55     SOCKET4677_AZIFS054P001C01-SOCA
GND                      U1               ED61     SOCKET4677_AZIFS054P001C01-SOCA
GND                      U1               ED67     SOCKET4677_AZIFS054P001C01-SOCA
GND                      U1               ED73     SOCKET4677_AZIFS054P001C01-SOCA
GND                      U1               EE17     SOCKET4677_AZIFS054P001C01-SOCA
GND                      U1               EE39     SOCKET4677_AZIFS054P001C01-SOCA
GND                      U1               EE52     SOCKET4677_AZIFS054P001C01-SOCA
GND                      U1               EE78     SOCKET4677_AZIFS054P001C01-SOCA
GND                      U1               EE80     SOCKET4677_AZIFS054P001C01-SOCA
GND                      U1               EE88     SOCKET4677_AZIFS054P001C01-SOCA
GND                      U1               EF2      SOCKET4677_AZIFS054P001C01-SOCA
GND                      U1               EF4      SOCKET4677_AZIFS054P001C01-SOCA
GND                      U1               EF8      SOCKET4677_AZIFS054P001C01-SOCA
GND                      U1               EF12     SOCKET4677_AZIFS054P001C01-SOCA
GND                      U1               EF16     SOCKET4677_AZIFS054P001C01-SOCA
GND                      U1               EF18     SOCKET4677_AZIFS054P001C01-SOCA
GND                      U1               EF20     SOCKET4677_AZIFS054P001C01-SOCA
GND                      U1               EF22     SOCKET4677_AZIFS054P001C01-SOCA
GND                      U1               EF24     SOCKET4677_AZIFS054P001C01-SOCA
GND                      U1               EF26     SOCKET4677_AZIFS054P001C01-SOCA
GND                      U1               EF28     SOCKET4677_AZIFS054P001C01-SOCA
GND                      U1               EF30     SOCKET4677_AZIFS054P001C01-SOCA
GND                      U1               EF32     SOCKET4677_AZIFS054P001C01-SOCA
GND                      U1               EF34     SOCKET4677_AZIFS054P001C01-SOCA
GND                      U1               EF36     SOCKET4677_AZIFS054P001C01-SOCA
GND                      U1               EF38     SOCKET4677_AZIFS054P001C01-SOCA
GND                      U1               EF40     SOCKET4677_AZIFS054P001C01-SOCA
GND                      U1               EF42     SOCKET4677_AZIFS054P001C01-SOCA
GND                      U1               EF44     SOCKET4677_AZIFS054P001C01-SOCA
GND                      U1               EF47     SOCKET4677_AZIFS054P001C01-SOCA
GND                      U1               EF49     SOCKET4677_AZIFS054P001C01-SOCA
GND                      U1               EF51     SOCKET4677_AZIFS054P001C01-SOCA
GND                      U1               EF53     SOCKET4677_AZIFS054P001C01-SOCA
GND                      U1               EF55     SOCKET4677_AZIFS054P001C01-SOCA
GND                      U1               EF57     SOCKET4677_AZIFS054P001C01-SOCA
GND                      U1               EF59     SOCKET4677_AZIFS054P001C01-SOCA
GND                      U1               EF61     SOCKET4677_AZIFS054P001C01-SOCA
GND                      U1               EF63     SOCKET4677_AZIFS054P001C01-SOCA
GND                      U1               EF65     SOCKET4677_AZIFS054P001C01-SOCA
GND                      U1               EF67     SOCKET4677_AZIFS054P001C01-SOCA
GND                      U1               EF69     SOCKET4677_AZIFS054P001C01-SOCA
GND                      U1               EF71     SOCKET4677_AZIFS054P001C01-SOCA
GND                      U1               EF73     SOCKET4677_AZIFS054P001C01-SOCA
GND                      U1               EF75     SOCKET4677_AZIFS054P001C01-SOCA
GND                      U1               EF77     SOCKET4677_AZIFS054P001C01-SOCA
GND                      U1               EF85     SOCKET4677_AZIFS054P001C01-SOCA
GND                      U1               EF87     SOCKET4677_AZIFS054P001C01-SOCA
GND                      U1               EF89     SOCKET4677_AZIFS054P001C01-SOCA
GND                      U1               EG5      SOCKET4677_AZIFS054P001C01-SOCA
GND                      U1               EG7      SOCKET4677_AZIFS054P001C01-SOCA
GND                      U1               EG9      SOCKET4677_AZIFS054P001C01-SOCA
GND                      U1               EG13     SOCKET4677_AZIFS054P001C01-SOCA
GND                      U1               EG39     SOCKET4677_AZIFS054P001C01-SOCA
GND                      U1               EG52     SOCKET4677_AZIFS054P001C01-SOCA
GND                      U1               EG82     SOCKET4677_AZIFS054P001C01-SOCA
GND                      U1               EG84     SOCKET4677_AZIFS054P001C01-SOCA
GND                      U1               EG86     SOCKET4677_AZIFS054P001C01-SOCA
GND                      U1               EG88     SOCKET4677_AZIFS054P001C01-SOCA
GND                      U1               EG90     SOCKET4677_AZIFS054P001C01-SOCA
GND                      U1               EH4      SOCKET4677_AZIFS054P001C01-SOCA
GND                      U1               EH6      SOCKET4677_AZIFS054P001C01-SOCA
GND                      U1               EH12     SOCKET4677_AZIFS054P001C01-SOCA
GND                      U1               EH14     SOCKET4677_AZIFS054P001C01-SOCA
GND                      U1               EH16     SOCKET4677_AZIFS054P001C01-SOCA
GND                      U1               EH18     SOCKET4677_AZIFS054P001C01-SOCA
GND                      U1               EH24     SOCKET4677_AZIFS054P001C01-SOCA
GND                      U1               EH30     SOCKET4677_AZIFS054P001C01-SOCA
GND                      U1               EH36     SOCKET4677_AZIFS054P001C01-SOCA
GND                      U1               EH42     SOCKET4677_AZIFS054P001C01-SOCA
GND                      U1               EH49     SOCKET4677_AZIFS054P001C01-SOCA
GND                      U1               EH55     SOCKET4677_AZIFS054P001C01-SOCA
GND                      U1               EH61     SOCKET4677_AZIFS054P001C01-SOCA
GND                      U1               EH67     SOCKET4677_AZIFS054P001C01-SOCA
GND                      U1               EH73     SOCKET4677_AZIFS054P001C01-SOCA
GND                      U1               EH79     SOCKET4677_AZIFS054P001C01-SOCA
GND                      U1               EH81     SOCKET4677_AZIFS054P001C01-SOCA
GND                      U1               EH83     SOCKET4677_AZIFS054P001C01-SOCA
GND                      U1               EJ7      SOCKET4677_AZIFS054P001C01-SOCA
GND                      U1               EJ9      SOCKET4677_AZIFS054P001C01-SOCA
GND                      U1               EJ11     SOCKET4677_AZIFS054P001C01-SOCA
GND                      U1               EJ13     SOCKET4677_AZIFS054P001C01-SOCA
GND                      U1               EJ17     SOCKET4677_AZIFS054P001C01-SOCA
GND                      U1               EJ19     SOCKET4677_AZIFS054P001C01-SOCA
GND                      U1               EJ23     SOCKET4677_AZIFS054P001C01-SOCA
GND                      U1               EJ25     SOCKET4677_AZIFS054P001C01-SOCA
GND                      U1               EJ29     SOCKET4677_AZIFS054P001C01-SOCA
GND                      U1               EJ31     SOCKET4677_AZIFS054P001C01-SOCA
GND                      U1               EJ35     SOCKET4677_AZIFS054P001C01-SOCA
GND                      U1               EJ37     SOCKET4677_AZIFS054P001C01-SOCA
GND                      U1               EJ41     SOCKET4677_AZIFS054P001C01-SOCA
GND                      U1               EJ43     SOCKET4677_AZIFS054P001C01-SOCA
GND                      U1               EJ48     SOCKET4677_AZIFS054P001C01-SOCA
GND                      U1               EJ50     SOCKET4677_AZIFS054P001C01-SOCA
GND                      U1               EJ54     SOCKET4677_AZIFS054P001C01-SOCA
GND                      U1               EJ56     SOCKET4677_AZIFS054P001C01-SOCA
GND                      U1               EJ60     SOCKET4677_AZIFS054P001C01-SOCA
GND                      U1               EJ62     SOCKET4677_AZIFS054P001C01-SOCA
GND                      U1               EJ66     SOCKET4677_AZIFS054P001C01-SOCA
GND                      U1               EJ68     SOCKET4677_AZIFS054P001C01-SOCA
GND                      U1               EJ72     SOCKET4677_AZIFS054P001C01-SOCA
GND                      U1               EJ74     SOCKET4677_AZIFS054P001C01-SOCA
GND                      U1               EJ78     SOCKET4677_AZIFS054P001C01-SOCA
GND                      U1               EJ88     SOCKET4677_AZIFS054P001C01-SOCA
GND                      U1               EK2      SOCKET4677_AZIFS054P001C01-SOCA
GND                      U1               EK4      SOCKET4677_AZIFS054P001C01-SOCA
GND                      U1               EK10     SOCKET4677_AZIFS054P001C01-SOCA
GND                      U1               EK14     SOCKET4677_AZIFS054P001C01-SOCA
GND                      U1               EK16     SOCKET4677_AZIFS054P001C01-SOCA
GND                      U1               EK20     SOCKET4677_AZIFS054P001C01-SOCA
GND                      U1               EK22     SOCKET4677_AZIFS054P001C01-SOCA
GND                      U1               EK26     SOCKET4677_AZIFS054P001C01-SOCA
GND                      U1               EK28     SOCKET4677_AZIFS054P001C01-SOCA
GND                      U1               EK32     SOCKET4677_AZIFS054P001C01-SOCA
GND                      U1               EK34     SOCKET4677_AZIFS054P001C01-SOCA
GND                      U1               EK38     SOCKET4677_AZIFS054P001C01-SOCA
GND                      U1               EK40     SOCKET4677_AZIFS054P001C01-SOCA
GND                      U1               EK44     SOCKET4677_AZIFS054P001C01-SOCA
GND                      U1               EK47     SOCKET4677_AZIFS054P001C01-SOCA
GND                      U1               EK51     SOCKET4677_AZIFS054P001C01-SOCA
GND                      U1               EK53     SOCKET4677_AZIFS054P001C01-SOCA
GND                      U1               EK57     SOCKET4677_AZIFS054P001C01-SOCA
GND                      U1               EK59     SOCKET4677_AZIFS054P001C01-SOCA
GND                      U1               EK63     SOCKET4677_AZIFS054P001C01-SOCA
GND                      U1               EK65     SOCKET4677_AZIFS054P001C01-SOCA
GND                      U1               EK69     SOCKET4677_AZIFS054P001C01-SOCA
GND                      U1               EK71     SOCKET4677_AZIFS054P001C01-SOCA
GND                      U1               EK75     SOCKET4677_AZIFS054P001C01-SOCA
GND                      U1               EK77     SOCKET4677_AZIFS054P001C01-SOCA
GND                      U1               EK79     SOCKET4677_AZIFS054P001C01-SOCA
GND                      U1               EK83     SOCKET4677_AZIFS054P001C01-SOCA
GND                      U1               EK89     SOCKET4677_AZIFS054P001C01-SOCA
GND                      U1               EL3      SOCKET4677_AZIFS054P001C01-SOCA
GND                      U1               EL5      SOCKET4677_AZIFS054P001C01-SOCA
GND                      U1               EL7      SOCKET4677_AZIFS054P001C01-SOCA
GND                      U1               EL9      SOCKET4677_AZIFS054P001C01-SOCA
GND                      U1               EL15     SOCKET4677_AZIFS054P001C01-SOCA
GND                      U1               EL21     SOCKET4677_AZIFS054P001C01-SOCA
GND                      U1               EL27     SOCKET4677_AZIFS054P001C01-SOCA
GND                      U1               EL33     SOCKET4677_AZIFS054P001C01-SOCA
GND                      U1               EL39     SOCKET4677_AZIFS054P001C01-SOCA
GND                      U1               EL45     SOCKET4677_AZIFS054P001C01-SOCA
GND                      U1               EL52     SOCKET4677_AZIFS054P001C01-SOCA
GND                      U1               EL58     SOCKET4677_AZIFS054P001C01-SOCA
GND                      U1               EL64     SOCKET4677_AZIFS054P001C01-SOCA
GND                      U1               EL70     SOCKET4677_AZIFS054P001C01-SOCA
GND                      U1               EL72     SOCKET4677_AZIFS054P001C01-SOCA
GND                      U1               EL76     SOCKET4677_AZIFS054P001C01-SOCA
GND                      U1               EL86     SOCKET4677_AZIFS054P001C01-SOCA
GND                      U1               EM8      SOCKET4677_AZIFS054P001C01-SOCA
GND                      U1               EM42     SOCKET4677_AZIFS054P001C01-SOCA
GND                      U1               EM49     SOCKET4677_AZIFS054P001C01-SOCA
GND                      U1               EM73     SOCKET4677_AZIFS054P001C01-SOCA
GND                      U1               EM79     SOCKET4677_AZIFS054P001C01-SOCA
GND                      U1               EM81     SOCKET4677_AZIFS054P001C01-SOCA
GND                      U1               EM83     SOCKET4677_AZIFS054P001C01-SOCA
GND                      U1               EN9      SOCKET4677_AZIFS054P001C01-SOCA
GND                      U1               EN11     SOCKET4677_AZIFS054P001C01-SOCA
GND                      U1               EN13     SOCKET4677_AZIFS054P001C01-SOCA
GND                      U1               EN15     SOCKET4677_AZIFS054P001C01-SOCA
GND                      U1               EN17     SOCKET4677_AZIFS054P001C01-SOCA
GND                      U1               EN19     SOCKET4677_AZIFS054P001C01-SOCA
GND                      U1               EN21     SOCKET4677_AZIFS054P001C01-SOCA
GND                      U1               EN23     SOCKET4677_AZIFS054P001C01-SOCA
GND                      U1               EN25     SOCKET4677_AZIFS054P001C01-SOCA
GND                      U1               EN27     SOCKET4677_AZIFS054P001C01-SOCA
GND                      U1               EN29     SOCKET4677_AZIFS054P001C01-SOCA
GND                      U1               EN31     SOCKET4677_AZIFS054P001C01-SOCA
GND                      U1               EN33     SOCKET4677_AZIFS054P001C01-SOCA
GND                      U1               EN35     SOCKET4677_AZIFS054P001C01-SOCA
GND                      U1               EN37     SOCKET4677_AZIFS054P001C01-SOCA
GND                      U1               EN39     SOCKET4677_AZIFS054P001C01-SOCA
GND                      U1               EN41     SOCKET4677_AZIFS054P001C01-SOCA
GND                      U1               EN43     SOCKET4677_AZIFS054P001C01-SOCA
GND                      U1               EN45     SOCKET4677_AZIFS054P001C01-SOCA
GND                      U1               EN48     SOCKET4677_AZIFS054P001C01-SOCA
GND                      U1               EN50     SOCKET4677_AZIFS054P001C01-SOCA
GND                      U1               EN52     SOCKET4677_AZIFS054P001C01-SOCA
GND                      U1               EN54     SOCKET4677_AZIFS054P001C01-SOCA
GND                      U1               EN56     SOCKET4677_AZIFS054P001C01-SOCA
GND                      U1               EN58     SOCKET4677_AZIFS054P001C01-SOCA
GND                      U1               EN60     SOCKET4677_AZIFS054P001C01-SOCA
GND                      U1               EN62     SOCKET4677_AZIFS054P001C01-SOCA
GND                      U1               EN64     SOCKET4677_AZIFS054P001C01-SOCA
GND                      U1               EN66     SOCKET4677_AZIFS054P001C01-SOCA
GND                      U1               EN72     SOCKET4677_AZIFS054P001C01-SOCA
GND                      U1               EN78     SOCKET4677_AZIFS054P001C01-SOCA
GND                      U1               EN80     SOCKET4677_AZIFS054P001C01-SOCA
GND                      U1               EN88     SOCKET4677_AZIFS054P001C01-SOCA
GND                      U1               EP67     SOCKET4677_AZIFS054P001C01-SOCA
GND                      U1               EP69     SOCKET4677_AZIFS054P001C01-SOCA
GND                      U1               EP71     SOCKET4677_AZIFS054P001C01-SOCA
GND                      U1               EP77     SOCKET4677_AZIFS054P001C01-SOCA
GND                      U1               EP83     SOCKET4677_AZIFS054P001C01-SOCA
GND                      U1               ER5      SOCKET4677_AZIFS054P001C01-SOCA
GND                      U1               ER7      SOCKET4677_AZIFS054P001C01-SOCA
GND                      U1               ER9      SOCKET4677_AZIFS054P001C01-SOCA
GND                      U1               ER15     SOCKET4677_AZIFS054P001C01-SOCA
GND                      U1               ER21     SOCKET4677_AZIFS054P001C01-SOCA
GND                      U1               ER27     SOCKET4677_AZIFS054P001C01-SOCA
GND                      U1               ER33     SOCKET4677_AZIFS054P001C01-SOCA
GND                      U1               ER39     SOCKET4677_AZIFS054P001C01-SOCA
GND                      U1               ER41     SOCKET4677_AZIFS054P001C01-SOCA
GND                      U1               ER43     SOCKET4677_AZIFS054P001C01-SOCA
GND                      U1               ER48     SOCKET4677_AZIFS054P001C01-SOCA
GND                      U1               ER50     SOCKET4677_AZIFS054P001C01-SOCA
GND                      U1               ER52     SOCKET4677_AZIFS054P001C01-SOCA
GND                      U1               ER58     SOCKET4677_AZIFS054P001C01-SOCA
GND                      U1               ER64     SOCKET4677_AZIFS054P001C01-SOCA
GND                      U1               ER70     SOCKET4677_AZIFS054P001C01-SOCA
GND                      U1               ER74     SOCKET4677_AZIFS054P001C01-SOCA
GND                      U1               ER78     SOCKET4677_AZIFS054P001C01-SOCA
GND                      U1               ER80     SOCKET4677_AZIFS054P001C01-SOCA
GND                      U1               ER84     SOCKET4677_AZIFS054P001C01-SOCA
GND                      U1               ER86     SOCKET4677_AZIFS054P001C01-SOCA
GND                      U1               ET10     SOCKET4677_AZIFS054P001C01-SOCA
GND                      U1               ET14     SOCKET4677_AZIFS054P001C01-SOCA
GND                      U1               ET16     SOCKET4677_AZIFS054P001C01-SOCA
GND                      U1               ET20     SOCKET4677_AZIFS054P001C01-SOCA
GND                      U1               ET22     SOCKET4677_AZIFS054P001C01-SOCA
GND                      U1               ET26     SOCKET4677_AZIFS054P001C01-SOCA
GND                      U1               ET28     SOCKET4677_AZIFS054P001C01-SOCA
GND                      U1               ET32     SOCKET4677_AZIFS054P001C01-SOCA
GND                      U1               ET34     SOCKET4677_AZIFS054P001C01-SOCA
GND                      U1               ET38     SOCKET4677_AZIFS054P001C01-SOCA
GND                      U1               ET53     SOCKET4677_AZIFS054P001C01-SOCA
GND                      U1               ET57     SOCKET4677_AZIFS054P001C01-SOCA
GND                      U1               ET59     SOCKET4677_AZIFS054P001C01-SOCA
GND                      U1               F4       SOCKET4677_AZIFS054P001C01-SOCA
GND                      U1               F6       SOCKET4677_AZIFS054P001C01-SOCA
GND                      U1               F12      SOCKET4677_AZIFS054P001C01-SOCA
GND                      U1               F18      SOCKET4677_AZIFS054P001C01-SOCA
GND                      U1               F24      SOCKET4677_AZIFS054P001C01-SOCA
GND                      U1               F30      SOCKET4677_AZIFS054P001C01-SOCA
GND                      U1               F36      SOCKET4677_AZIFS054P001C01-SOCA
GND                      U1               F42      SOCKET4677_AZIFS054P001C01-SOCA
GND                      U1               F49      SOCKET4677_AZIFS054P001C01-SOCA
GND                      U1               F55      SOCKET4677_AZIFS054P001C01-SOCA
GND                      U1               F61      SOCKET4677_AZIFS054P001C01-SOCA
GND                      U1               F67      SOCKET4677_AZIFS054P001C01-SOCA
GND                      U1               F73      SOCKET4677_AZIFS054P001C01-SOCA
GND                      U1               F79      SOCKET4677_AZIFS054P001C01-SOCA
GND                      U1               F83      SOCKET4677_AZIFS054P001C01-SOCA
GND                      U1               F89      SOCKET4677_AZIFS054P001C01-SOCA
GND                      U1               G3       SOCKET4677_AZIFS054P001C01-SOCA
GND                      U1               G7       SOCKET4677_AZIFS054P001C01-SOCA
GND                      U1               G11      SOCKET4677_AZIFS054P001C01-SOCA
GND                      U1               G13      SOCKET4677_AZIFS054P001C01-SOCA
GND                      U1               G17      SOCKET4677_AZIFS054P001C01-SOCA
GND                      U1               G19      SOCKET4677_AZIFS054P001C01-SOCA
GND                      U1               G23      SOCKET4677_AZIFS054P001C01-SOCA
GND                      U1               G25      SOCKET4677_AZIFS054P001C01-SOCA
GND                      U1               G29      SOCKET4677_AZIFS054P001C01-SOCA
GND                      U1               G31      SOCKET4677_AZIFS054P001C01-SOCA
GND                      U1               G35      SOCKET4677_AZIFS054P001C01-SOCA
GND                      U1               G37      SOCKET4677_AZIFS054P001C01-SOCA
GND                      U1               G41      SOCKET4677_AZIFS054P001C01-SOCA
GND                      U1               G43      SOCKET4677_AZIFS054P001C01-SOCA
GND                      U1               G48      SOCKET4677_AZIFS054P001C01-SOCA
GND                      U1               G50      SOCKET4677_AZIFS054P001C01-SOCA
GND                      U1               G54      SOCKET4677_AZIFS054P001C01-SOCA
GND                      U1               G56      SOCKET4677_AZIFS054P001C01-SOCA
GND                      U1               G60      SOCKET4677_AZIFS054P001C01-SOCA
GND                      U1               G62      SOCKET4677_AZIFS054P001C01-SOCA
GND                      U1               G66      SOCKET4677_AZIFS054P001C01-SOCA
GND                      U1               G68      SOCKET4677_AZIFS054P001C01-SOCA
GND                      U1               G72      SOCKET4677_AZIFS054P001C01-SOCA
GND                      U1               G74      SOCKET4677_AZIFS054P001C01-SOCA
GND                      U1               G84      SOCKET4677_AZIFS054P001C01-SOCA
GND                      U1               G88      SOCKET4677_AZIFS054P001C01-SOCA
GND                      U1               G90      SOCKET4677_AZIFS054P001C01-SOCA
GND                      U1               H2       SOCKET4677_AZIFS054P001C01-SOCA
GND                      U1               H4       SOCKET4677_AZIFS054P001C01-SOCA
GND                      U1               H6       SOCKET4677_AZIFS054P001C01-SOCA
GND                      U1               H8       SOCKET4677_AZIFS054P001C01-SOCA
GND                      U1               H10      SOCKET4677_AZIFS054P001C01-SOCA
GND                      U1               H14      SOCKET4677_AZIFS054P001C01-SOCA
GND                      U1               H16      SOCKET4677_AZIFS054P001C01-SOCA
GND                      U1               H20      SOCKET4677_AZIFS054P001C01-SOCA
GND                      U1               H22      SOCKET4677_AZIFS054P001C01-SOCA
GND                      U1               H26      SOCKET4677_AZIFS054P001C01-SOCA
GND                      U1               H28      SOCKET4677_AZIFS054P001C01-SOCA
GND                      U1               H32      SOCKET4677_AZIFS054P001C01-SOCA
GND                      U1               H34      SOCKET4677_AZIFS054P001C01-SOCA
GND                      U1               H38      SOCKET4677_AZIFS054P001C01-SOCA
GND                      U1               H40      SOCKET4677_AZIFS054P001C01-SOCA
GND                      U1               H44      SOCKET4677_AZIFS054P001C01-SOCA
GND                      U1               H47      SOCKET4677_AZIFS054P001C01-SOCA
GND                      U1               H51      SOCKET4677_AZIFS054P001C01-SOCA
GND                      U1               H53      SOCKET4677_AZIFS054P001C01-SOCA
GND                      U1               H57      SOCKET4677_AZIFS054P001C01-SOCA
GND                      U1               H59      SOCKET4677_AZIFS054P001C01-SOCA
GND                      U1               H63      SOCKET4677_AZIFS054P001C01-SOCA
GND                      U1               H65      SOCKET4677_AZIFS054P001C01-SOCA
GND                      U1               H69      SOCKET4677_AZIFS054P001C01-SOCA
GND                      U1               H71      SOCKET4677_AZIFS054P001C01-SOCA
GND                      U1               H75      SOCKET4677_AZIFS054P001C01-SOCA
GND                      U1               H79      SOCKET4677_AZIFS054P001C01-SOCA
GND                      U1               H81      SOCKET4677_AZIFS054P001C01-SOCA
GND                      U1               J5       SOCKET4677_AZIFS054P001C01-SOCA
GND                      U1               J9       SOCKET4677_AZIFS054P001C01-SOCA
GND                      U1               J15      SOCKET4677_AZIFS054P001C01-SOCA
GND                      U1               J21      SOCKET4677_AZIFS054P001C01-SOCA
GND                      U1               J27      SOCKET4677_AZIFS054P001C01-SOCA
GND                      U1               J33      SOCKET4677_AZIFS054P001C01-SOCA
GND                      U1               J39      SOCKET4677_AZIFS054P001C01-SOCA
GND                      U1               J45      SOCKET4677_AZIFS054P001C01-SOCA
GND                      U1               J52      SOCKET4677_AZIFS054P001C01-SOCA
GND                      U1               J58      SOCKET4677_AZIFS054P001C01-SOCA
GND                      U1               J64      SOCKET4677_AZIFS054P001C01-SOCA
GND                      U1               J70      SOCKET4677_AZIFS054P001C01-SOCA
GND                      U1               J76      SOCKET4677_AZIFS054P001C01-SOCA
GND                      U1               J78      SOCKET4677_AZIFS054P001C01-SOCA
GND                      U1               J84      SOCKET4677_AZIFS054P001C01-SOCA
GND                      U1               J86      SOCKET4677_AZIFS054P001C01-SOCA
GND                      U1               J88      SOCKET4677_AZIFS054P001C01-SOCA
GND                      U1               K2       SOCKET4677_AZIFS054P001C01-SOCA
GND                      U1               K8       SOCKET4677_AZIFS054P001C01-SOCA
GND                      U1               K12      SOCKET4677_AZIFS054P001C01-SOCA
GND                      U1               K14      SOCKET4677_AZIFS054P001C01-SOCA
GND                      U1               K42      SOCKET4677_AZIFS054P001C01-SOCA
GND                      U1               K49      SOCKET4677_AZIFS054P001C01-SOCA
GND                      U1               K77      SOCKET4677_AZIFS054P001C01-SOCA
GND                      U1               K83      SOCKET4677_AZIFS054P001C01-SOCA
GND                      U1               K85      SOCKET4677_AZIFS054P001C01-SOCA
GND                      U1               L5       SOCKET4677_AZIFS054P001C01-SOCA
GND                      U1               L9       SOCKET4677_AZIFS054P001C01-SOCA
GND                      U1               L13      SOCKET4677_AZIFS054P001C01-SOCA
GND                      U1               L15      SOCKET4677_AZIFS054P001C01-SOCA
GND                      U1               L17      SOCKET4677_AZIFS054P001C01-SOCA
GND                      U1               L19      SOCKET4677_AZIFS054P001C01-SOCA
GND                      U1               L21      SOCKET4677_AZIFS054P001C01-SOCA
GND                      U1               L23      SOCKET4677_AZIFS054P001C01-SOCA
GND                      U1               L25      SOCKET4677_AZIFS054P001C01-SOCA
GND                      U1               L27      SOCKET4677_AZIFS054P001C01-SOCA
GND                      U1               L29      SOCKET4677_AZIFS054P001C01-SOCA
GND                      U1               L31      SOCKET4677_AZIFS054P001C01-SOCA
GND                      U1               L33      SOCKET4677_AZIFS054P001C01-SOCA
GND                      U1               L35      SOCKET4677_AZIFS054P001C01-SOCA
GND                      U1               L37      SOCKET4677_AZIFS054P001C01-SOCA
GND                      U1               L39      SOCKET4677_AZIFS054P001C01-SOCA
GND                      U1               L41      SOCKET4677_AZIFS054P001C01-SOCA
GND                      U1               L43      SOCKET4677_AZIFS054P001C01-SOCA
GND                      U1               L45      SOCKET4677_AZIFS054P001C01-SOCA
GND                      U1               L48      SOCKET4677_AZIFS054P001C01-SOCA
GND                      U1               L50      SOCKET4677_AZIFS054P001C01-SOCA
GND                      U1               L52      SOCKET4677_AZIFS054P001C01-SOCA
GND                      U1               L54      SOCKET4677_AZIFS054P001C01-SOCA
GND                      U1               L56      SOCKET4677_AZIFS054P001C01-SOCA
GND                      U1               L58      SOCKET4677_AZIFS054P001C01-SOCA
GND                      U1               L60      SOCKET4677_AZIFS054P001C01-SOCA
GND                      U1               L62      SOCKET4677_AZIFS054P001C01-SOCA
GND                      U1               L64      SOCKET4677_AZIFS054P001C01-SOCA
GND                      U1               L66      SOCKET4677_AZIFS054P001C01-SOCA
GND                      U1               L68      SOCKET4677_AZIFS054P001C01-SOCA
GND                      U1               L70      SOCKET4677_AZIFS054P001C01-SOCA
GND                      U1               L72      SOCKET4677_AZIFS054P001C01-SOCA
GND                      U1               L74      SOCKET4677_AZIFS054P001C01-SOCA
GND                      U1               L76      SOCKET4677_AZIFS054P001C01-SOCA
GND                      U1               L78      SOCKET4677_AZIFS054P001C01-SOCA
GND                      U1               L88      SOCKET4677_AZIFS054P001C01-SOCA
GND                      U1               L90      SOCKET4677_AZIFS054P001C01-SOCA
GND                      U1               M4       SOCKET4677_AZIFS054P001C01-SOCA
GND                      U1               M8       SOCKET4677_AZIFS054P001C01-SOCA
GND                      U1               M12      SOCKET4677_AZIFS054P001C01-SOCA
GND                      U1               M42      SOCKET4677_AZIFS054P001C01-SOCA
GND                      U1               M49      SOCKET4677_AZIFS054P001C01-SOCA
GND                      U1               M81      SOCKET4677_AZIFS054P001C01-SOCA
GND                      U1               M83      SOCKET4677_AZIFS054P001C01-SOCA
GND                      U1               N15      SOCKET4677_AZIFS054P001C01-SOCA
GND                      U1               N21      SOCKET4677_AZIFS054P001C01-SOCA
GND                      U1               N27      SOCKET4677_AZIFS054P001C01-SOCA
GND                      U1               N33      SOCKET4677_AZIFS054P001C01-SOCA
GND                      U1               N39      SOCKET4677_AZIFS054P001C01-SOCA
GND                      U1               N45      SOCKET4677_AZIFS054P001C01-SOCA
GND                      U1               N52      SOCKET4677_AZIFS054P001C01-SOCA
GND                      U1               N58      SOCKET4677_AZIFS054P001C01-SOCA
GND                      U1               N64      SOCKET4677_AZIFS054P001C01-SOCA
GND                      U1               N70      SOCKET4677_AZIFS054P001C01-SOCA
GND                      U1               N76      SOCKET4677_AZIFS054P001C01-SOCA
GND                      U1               N78      SOCKET4677_AZIFS054P001C01-SOCA
GND                      U1               N80      SOCKET4677_AZIFS054P001C01-SOCA
GND                      U1               N82      SOCKET4677_AZIFS054P001C01-SOCA
GND                      U1               N84      SOCKET4677_AZIFS054P001C01-SOCA
GND                      U1               N88      SOCKET4677_AZIFS054P001C01-SOCA
GND                      U1               P4       SOCKET4677_AZIFS054P001C01-SOCA
GND                      U1               P8       SOCKET4677_AZIFS054P001C01-SOCA
GND                      U1               P12      SOCKET4677_AZIFS054P001C01-SOCA
GND                      U1               P16      SOCKET4677_AZIFS054P001C01-SOCA
GND                      U1               P20      SOCKET4677_AZIFS054P001C01-SOCA
GND                      U1               P22      SOCKET4677_AZIFS054P001C01-SOCA
GND                      U1               P26      SOCKET4677_AZIFS054P001C01-SOCA
GND                      U1               P28      SOCKET4677_AZIFS054P001C01-SOCA
GND                      U1               P32      SOCKET4677_AZIFS054P001C01-SOCA
GND                      U1               P34      SOCKET4677_AZIFS054P001C01-SOCA
GND                      U1               P38      SOCKET4677_AZIFS054P001C01-SOCA
GND                      U1               P40      SOCKET4677_AZIFS054P001C01-SOCA
GND                      U1               P44      SOCKET4677_AZIFS054P001C01-SOCA
GND                      U1               P47      SOCKET4677_AZIFS054P001C01-SOCA
GND                      U1               P51      SOCKET4677_AZIFS054P001C01-SOCA
GND                      U1               P53      SOCKET4677_AZIFS054P001C01-SOCA
GND                      U1               P57      SOCKET4677_AZIFS054P001C01-SOCA
GND                      U1               P59      SOCKET4677_AZIFS054P001C01-SOCA
GND                      U1               P63      SOCKET4677_AZIFS054P001C01-SOCA
GND                      U1               P65      SOCKET4677_AZIFS054P001C01-SOCA
GND                      U1               P69      SOCKET4677_AZIFS054P001C01-SOCA
GND                      U1               P71      SOCKET4677_AZIFS054P001C01-SOCA
GND                      U1               P75      SOCKET4677_AZIFS054P001C01-SOCA
GND                      U1               P77      SOCKET4677_AZIFS054P001C01-SOCA
GND                      U1               P87      SOCKET4677_AZIFS054P001C01-SOCA
GND                      U1               P91      SOCKET4677_AZIFS054P001C01-SOCA
GND                      U1               R1       SOCKET4677_AZIFS054P001C01-SOCA
GND                      U1               R5       SOCKET4677_AZIFS054P001C01-SOCA
GND                      U1               R9       SOCKET4677_AZIFS054P001C01-SOCA
GND                      U1               R13      SOCKET4677_AZIFS054P001C01-SOCA
GND                      U1               R17      SOCKET4677_AZIFS054P001C01-SOCA
GND                      U1               R19      SOCKET4677_AZIFS054P001C01-SOCA
GND                      U1               R23      SOCKET4677_AZIFS054P001C01-SOCA
GND                      U1               R25      SOCKET4677_AZIFS054P001C01-SOCA
GND                      U1               R29      SOCKET4677_AZIFS054P001C01-SOCA
GND                      U1               R31      SOCKET4677_AZIFS054P001C01-SOCA
GND                      U1               R35      SOCKET4677_AZIFS054P001C01-SOCA
GND                      U1               R37      SOCKET4677_AZIFS054P001C01-SOCA
GND                      U1               R41      SOCKET4677_AZIFS054P001C01-SOCA
GND                      U1               R43      SOCKET4677_AZIFS054P001C01-SOCA
GND                      U1               R48      SOCKET4677_AZIFS054P001C01-SOCA
GND                      U1               R50      SOCKET4677_AZIFS054P001C01-SOCA
GND                      U1               R54      SOCKET4677_AZIFS054P001C01-SOCA
GND                      U1               R56      SOCKET4677_AZIFS054P001C01-SOCA
GND                      U1               R60      SOCKET4677_AZIFS054P001C01-SOCA
GND                      U1               R62      SOCKET4677_AZIFS054P001C01-SOCA
GND                      U1               R66      SOCKET4677_AZIFS054P001C01-SOCA
GND                      U1               R68      SOCKET4677_AZIFS054P001C01-SOCA
GND                      U1               R72      SOCKET4677_AZIFS054P001C01-SOCA
GND                      U1               R74      SOCKET4677_AZIFS054P001C01-SOCA
GND                      U1               R78      SOCKET4677_AZIFS054P001C01-SOCA
GND                      U1               R84      SOCKET4677_AZIFS054P001C01-SOCA
GND                      U1               R88      SOCKET4677_AZIFS054P001C01-SOCA
GND                      U1               T4       SOCKET4677_AZIFS054P001C01-SOCA
GND                      U1               T8       SOCKET4677_AZIFS054P001C01-SOCA
GND                      U1               T12      SOCKET4677_AZIFS054P001C01-SOCA
GND                      U1               T16      SOCKET4677_AZIFS054P001C01-SOCA
GND                      U1               T18      SOCKET4677_AZIFS054P001C01-SOCA
GND                      U1               T24      SOCKET4677_AZIFS054P001C01-SOCA
GND                      U1               T30      SOCKET4677_AZIFS054P001C01-SOCA
GND                      U1               T36      SOCKET4677_AZIFS054P001C01-SOCA
GND                      U1               T42      SOCKET4677_AZIFS054P001C01-SOCA
GND                      U1               T49      SOCKET4677_AZIFS054P001C01-SOCA
GND                      U1               T55      SOCKET4677_AZIFS054P001C01-SOCA
GND                      U1               T61      SOCKET4677_AZIFS054P001C01-SOCA
GND                      U1               T67      SOCKET4677_AZIFS054P001C01-SOCA
GND                      U1               T73      SOCKET4677_AZIFS054P001C01-SOCA
GND                      U1               T79      SOCKET4677_AZIFS054P001C01-SOCA
GND                      U1               T83      SOCKET4677_AZIFS054P001C01-SOCA
GND                      U1               U39      SOCKET4677_AZIFS054P001C01-SOCA
GND                      U1               U52      SOCKET4677_AZIFS054P001C01-SOCA
GND                      U1               U82      SOCKET4677_AZIFS054P001C01-SOCA
GND                      U1               U84      SOCKET4677_AZIFS054P001C01-SOCA
GND                      U1               U88      SOCKET4677_AZIFS054P001C01-SOCA
GND                      U1               V4       SOCKET4677_AZIFS054P001C01-SOCA
GND                      U1               V8       SOCKET4677_AZIFS054P001C01-SOCA
GND                      U1               V12      SOCKET4677_AZIFS054P001C01-SOCA
GND                      U1               V16      SOCKET4677_AZIFS054P001C01-SOCA
GND                      U1               V18      SOCKET4677_AZIFS054P001C01-SOCA
GND                      U1               V20      SOCKET4677_AZIFS054P001C01-SOCA
GND                      U1               V22      SOCKET4677_AZIFS054P001C01-SOCA
GND                      U1               V24      SOCKET4677_AZIFS054P001C01-SOCA
GND                      U1               V26      SOCKET4677_AZIFS054P001C01-SOCA
GND                      U1               V28      SOCKET4677_AZIFS054P001C01-SOCA
GND                      U1               V30      SOCKET4677_AZIFS054P001C01-SOCA
GND                      U1               V32      SOCKET4677_AZIFS054P001C01-SOCA
GND                      U1               V34      SOCKET4677_AZIFS054P001C01-SOCA
GND                      U1               V36      SOCKET4677_AZIFS054P001C01-SOCA
GND                      U1               V38      SOCKET4677_AZIFS054P001C01-SOCA
GND                      U1               V40      SOCKET4677_AZIFS054P001C01-SOCA
GND                      U1               V42      SOCKET4677_AZIFS054P001C01-SOCA
GND                      U1               V44      SOCKET4677_AZIFS054P001C01-SOCA
GND                      U1               V47      SOCKET4677_AZIFS054P001C01-SOCA
GND                      U1               V49      SOCKET4677_AZIFS054P001C01-SOCA
GND                      U1               V51      SOCKET4677_AZIFS054P001C01-SOCA
GND                      U1               V53      SOCKET4677_AZIFS054P001C01-SOCA
GND                      U1               V55      SOCKET4677_AZIFS054P001C01-SOCA
GND                      U1               V57      SOCKET4677_AZIFS054P001C01-SOCA
GND                      U1               V59      SOCKET4677_AZIFS054P001C01-SOCA
GND                      U1               V61      SOCKET4677_AZIFS054P001C01-SOCA
GND                      U1               V63      SOCKET4677_AZIFS054P001C01-SOCA
GND                      U1               V65      SOCKET4677_AZIFS054P001C01-SOCA
GND                      U1               V67      SOCKET4677_AZIFS054P001C01-SOCA
GND                      U1               V69      SOCKET4677_AZIFS054P001C01-SOCA
GND                      U1               V71      SOCKET4677_AZIFS054P001C01-SOCA
GND                      U1               V73      SOCKET4677_AZIFS054P001C01-SOCA
GND                      U1               V75      SOCKET4677_AZIFS054P001C01-SOCA
GND                      U1               V77      SOCKET4677_AZIFS054P001C01-SOCA
GND                      U1               V79      SOCKET4677_AZIFS054P001C01-SOCA
GND                      U1               V87      SOCKET4677_AZIFS054P001C01-SOCA
GND                      U1               V91      SOCKET4677_AZIFS054P001C01-SOCA
GND                      U1               W1       SOCKET4677_AZIFS054P001C01-SOCA
GND                      U1               W5       SOCKET4677_AZIFS054P001C01-SOCA
GND                      U1               W9       SOCKET4677_AZIFS054P001C01-SOCA
GND                      U1               W13      SOCKET4677_AZIFS054P001C01-SOCA
GND                      U1               W39      SOCKET4677_AZIFS054P001C01-SOCA
GND                      U1               W52      SOCKET4677_AZIFS054P001C01-SOCA
GND                      U1               W84      SOCKET4677_AZIFS054P001C01-SOCA
GND                      U1               W88      SOCKET4677_AZIFS054P001C01-SOCA
GND                      U1               Y4       SOCKET4677_AZIFS054P001C01-SOCA
GND                      U1               Y8       SOCKET4677_AZIFS054P001C01-SOCA
GND                      U1               Y12      SOCKET4677_AZIFS054P001C01-SOCA
GND                      U1               Y16      SOCKET4677_AZIFS054P001C01-SOCA
GND                      U1               Y18      SOCKET4677_AZIFS054P001C01-SOCA
GND                      U1               Y24      SOCKET4677_AZIFS054P001C01-SOCA
GND                      U1               Y30      SOCKET4677_AZIFS054P001C01-SOCA
GND                      U1               Y36      SOCKET4677_AZIFS054P001C01-SOCA
GND                      U1               Y42      SOCKET4677_AZIFS054P001C01-SOCA
GND                      U1               Y49      SOCKET4677_AZIFS054P001C01-SOCA
GND                      U1               Y55      SOCKET4677_AZIFS054P001C01-SOCA
GND                      U1               Y61      SOCKET4677_AZIFS054P001C01-SOCA
GND                      U1               Y67      SOCKET4677_AZIFS054P001C01-SOCA
GND                      U1               Y73      SOCKET4677_AZIFS054P001C01-SOCA
GND                      U2               A11      SOCKET4677_AZIFS054P001C01-SOCA
GND                      U2               A13      SOCKET4677_AZIFS054P001C01-SOCA
GND                      U2               A17      SOCKET4677_AZIFS054P001C01-SOCA
GND                      U2               A19      SOCKET4677_AZIFS054P001C01-SOCA
GND                      U2               A23      SOCKET4677_AZIFS054P001C01-SOCA
GND                      U2               A25      SOCKET4677_AZIFS054P001C01-SOCA
GND                      U2               A29      SOCKET4677_AZIFS054P001C01-SOCA
GND                      U2               A31      SOCKET4677_AZIFS054P001C01-SOCA
GND                      U2               A35      SOCKET4677_AZIFS054P001C01-SOCA
GND                      U2               A37      SOCKET4677_AZIFS054P001C01-SOCA
GND                      U2               A41      SOCKET4677_AZIFS054P001C01-SOCA
GND                      U2               A50      SOCKET4677_AZIFS054P001C01-SOCA
GND                      U2               A54      SOCKET4677_AZIFS054P001C01-SOCA
GND                      U2               A56      SOCKET4677_AZIFS054P001C01-SOCA
GND                      U2               A60      SOCKET4677_AZIFS054P001C01-SOCA
GND                      U2               A62      SOCKET4677_AZIFS054P001C01-SOCA
GND                      U2               AA19     SOCKET4677_AZIFS054P001C01-SOCA
GND                      U2               AA23     SOCKET4677_AZIFS054P001C01-SOCA
GND                      U2               AA25     SOCKET4677_AZIFS054P001C01-SOCA
GND                      U2               AA29     SOCKET4677_AZIFS054P001C01-SOCA
GND                      U2               AA31     SOCKET4677_AZIFS054P001C01-SOCA
GND                      U2               AA35     SOCKET4677_AZIFS054P001C01-SOCA
GND                      U2               AA37     SOCKET4677_AZIFS054P001C01-SOCA
GND                      U2               AA41     SOCKET4677_AZIFS054P001C01-SOCA
GND                      U2               AA43     SOCKET4677_AZIFS054P001C01-SOCA
GND                      U2               AA48     SOCKET4677_AZIFS054P001C01-SOCA
GND                      U2               AA50     SOCKET4677_AZIFS054P001C01-SOCA
GND                      U2               AA54     SOCKET4677_AZIFS054P001C01-SOCA
GND                      U2               AA56     SOCKET4677_AZIFS054P001C01-SOCA
GND                      U2               AA60     SOCKET4677_AZIFS054P001C01-SOCA
GND                      U2               AA62     SOCKET4677_AZIFS054P001C01-SOCA
GND                      U2               AA66     SOCKET4677_AZIFS054P001C01-SOCA
GND                      U2               AA68     SOCKET4677_AZIFS054P001C01-SOCA
GND                      U2               AA72     SOCKET4677_AZIFS054P001C01-SOCA
GND                      U2               AA74     SOCKET4677_AZIFS054P001C01-SOCA
GND                      U2               AA78     SOCKET4677_AZIFS054P001C01-SOCA
GND                      U2               AA80     SOCKET4677_AZIFS054P001C01-SOCA
GND                      U2               AA82     SOCKET4677_AZIFS054P001C01-SOCA
GND                      U2               AA84     SOCKET4677_AZIFS054P001C01-SOCA
GND                      U2               AA88     SOCKET4677_AZIFS054P001C01-SOCA
GND                      U2               AB4      SOCKET4677_AZIFS054P001C01-SOCA
GND                      U2               AB8      SOCKET4677_AZIFS054P001C01-SOCA
GND                      U2               AB12     SOCKET4677_AZIFS054P001C01-SOCA
GND                      U2               AB16     SOCKET4677_AZIFS054P001C01-SOCA
GND                      U2               AB20     SOCKET4677_AZIFS054P001C01-SOCA
GND                      U2               AB22     SOCKET4677_AZIFS054P001C01-SOCA
GND                      U2               AB26     SOCKET4677_AZIFS054P001C01-SOCA
GND                      U2               AB28     SOCKET4677_AZIFS054P001C01-SOCA
GND                      U2               AB32     SOCKET4677_AZIFS054P001C01-SOCA
GND                      U2               AB34     SOCKET4677_AZIFS054P001C01-SOCA
GND                      U2               AB38     SOCKET4677_AZIFS054P001C01-SOCA
GND                      U2               AB40     SOCKET4677_AZIFS054P001C01-SOCA
GND                      U2               AB44     SOCKET4677_AZIFS054P001C01-SOCA
GND                      U2               AB47     SOCKET4677_AZIFS054P001C01-SOCA
GND                      U2               AB51     SOCKET4677_AZIFS054P001C01-SOCA
GND                      U2               AB53     SOCKET4677_AZIFS054P001C01-SOCA
GND                      U2               AB57     SOCKET4677_AZIFS054P001C01-SOCA
GND                      U2               AB59     SOCKET4677_AZIFS054P001C01-SOCA
GND                      U2               AB63     SOCKET4677_AZIFS054P001C01-SOCA
GND                      U2               AB65     SOCKET4677_AZIFS054P001C01-SOCA
GND                      U2               AB69     SOCKET4677_AZIFS054P001C01-SOCA
GND                      U2               AB71     SOCKET4677_AZIFS054P001C01-SOCA
GND                      U2               AB75     SOCKET4677_AZIFS054P001C01-SOCA
GND                      U2               AB77     SOCKET4677_AZIFS054P001C01-SOCA
GND                      U2               AB79     SOCKET4677_AZIFS054P001C01-SOCA
GND                      U2               AB81     SOCKET4677_AZIFS054P001C01-SOCA
GND                      U2               AB83     SOCKET4677_AZIFS054P001C01-SOCA
GND                      U2               AB87     SOCKET4677_AZIFS054P001C01-SOCA
GND                      U2               AB91     SOCKET4677_AZIFS054P001C01-SOCA
GND                      U2               AC1      SOCKET4677_AZIFS054P001C01-SOCA
GND                      U2               AC5      SOCKET4677_AZIFS054P001C01-SOCA
GND                      U2               AC9      SOCKET4677_AZIFS054P001C01-SOCA
GND                      U2               AC13     SOCKET4677_AZIFS054P001C01-SOCA
GND                      U2               AC21     SOCKET4677_AZIFS054P001C01-SOCA
GND                      U2               AC27     SOCKET4677_AZIFS054P001C01-SOCA
GND                      U2               AC33     SOCKET4677_AZIFS054P001C01-SOCA
GND                      U2               AC39     SOCKET4677_AZIFS054P001C01-SOCA
GND                      U2               AC45     SOCKET4677_AZIFS054P001C01-SOCA
GND                      U2               AC52     SOCKET4677_AZIFS054P001C01-SOCA
GND                      U2               AC58     SOCKET4677_AZIFS054P001C01-SOCA
GND                      U2               AC64     SOCKET4677_AZIFS054P001C01-SOCA
GND                      U2               AC70     SOCKET4677_AZIFS054P001C01-SOCA
GND                      U2               AC76     SOCKET4677_AZIFS054P001C01-SOCA
GND                      U2               AC84     SOCKET4677_AZIFS054P001C01-SOCA
GND                      U2               AC88     SOCKET4677_AZIFS054P001C01-SOCA
GND                      U2               AD4      SOCKET4677_AZIFS054P001C01-SOCA
GND                      U2               AD8      SOCKET4677_AZIFS054P001C01-SOCA
GND                      U2               AD12     SOCKET4677_AZIFS054P001C01-SOCA
GND                      U2               AD16     SOCKET4677_AZIFS054P001C01-SOCA
GND                      U2               AD42     SOCKET4677_AZIFS054P001C01-SOCA
GND                      U2               AD79     SOCKET4677_AZIFS054P001C01-SOCA
GND                      U2               AD83     SOCKET4677_AZIFS054P001C01-SOCA
GND                      U2               AE17     SOCKET4677_AZIFS054P001C01-SOCA
GND                      U2               AE19     SOCKET4677_AZIFS054P001C01-SOCA
GND                      U2               AE21     SOCKET4677_AZIFS054P001C01-SOCA
GND                      U2               AE23     SOCKET4677_AZIFS054P001C01-SOCA
GND                      U2               AE25     SOCKET4677_AZIFS054P001C01-SOCA
GND                      U2               AE27     SOCKET4677_AZIFS054P001C01-SOCA
GND                      U2               AE29     SOCKET4677_AZIFS054P001C01-SOCA
GND                      U2               AE31     SOCKET4677_AZIFS054P001C01-SOCA
GND                      U2               AE33     SOCKET4677_AZIFS054P001C01-SOCA
GND                      U2               AE35     SOCKET4677_AZIFS054P001C01-SOCA
GND                      U2               AE37     SOCKET4677_AZIFS054P001C01-SOCA
GND                      U2               AE39     SOCKET4677_AZIFS054P001C01-SOCA
GND                      U2               AE41     SOCKET4677_AZIFS054P001C01-SOCA
GND                      U2               AE43     SOCKET4677_AZIFS054P001C01-SOCA
GND                      U2               AE45     SOCKET4677_AZIFS054P001C01-SOCA
GND                      U2               AE48     SOCKET4677_AZIFS054P001C01-SOCA
GND                      U2               AE50     SOCKET4677_AZIFS054P001C01-SOCA
GND                      U2               AE52     SOCKET4677_AZIFS054P001C01-SOCA
GND                      U2               AE54     SOCKET4677_AZIFS054P001C01-SOCA
GND                      U2               AE56     SOCKET4677_AZIFS054P001C01-SOCA
GND                      U2               AE58     SOCKET4677_AZIFS054P001C01-SOCA
GND                      U2               AE60     SOCKET4677_AZIFS054P001C01-SOCA
GND                      U2               AE62     SOCKET4677_AZIFS054P001C01-SOCA
GND                      U2               AE64     SOCKET4677_AZIFS054P001C01-SOCA
GND                      U2               AE66     SOCKET4677_AZIFS054P001C01-SOCA
GND                      U2               AE68     SOCKET4677_AZIFS054P001C01-SOCA
GND                      U2               AE70     SOCKET4677_AZIFS054P001C01-SOCA
GND                      U2               AE72     SOCKET4677_AZIFS054P001C01-SOCA
GND                      U2               AE74     SOCKET4677_AZIFS054P001C01-SOCA
GND                      U2               AE76     SOCKET4677_AZIFS054P001C01-SOCA
GND                      U2               AE78     SOCKET4677_AZIFS054P001C01-SOCA
GND                      U2               AE84     SOCKET4677_AZIFS054P001C01-SOCA
GND                      U2               AE88     SOCKET4677_AZIFS054P001C01-SOCA
GND                      U2               AF4      SOCKET4677_AZIFS054P001C01-SOCA
GND                      U2               AF8      SOCKET4677_AZIFS054P001C01-SOCA
GND                      U2               AF12     SOCKET4677_AZIFS054P001C01-SOCA
GND                      U2               AF16     SOCKET4677_AZIFS054P001C01-SOCA
GND                      U2               AF42     SOCKET4677_AZIFS054P001C01-SOCA
GND                      U2               AF81     SOCKET4677_AZIFS054P001C01-SOCA
GND                      U2               AF87     SOCKET4677_AZIFS054P001C01-SOCA
GND                      U2               AF91     SOCKET4677_AZIFS054P001C01-SOCA
GND                      U2               AG1      SOCKET4677_AZIFS054P001C01-SOCA
GND                      U2               AG5      SOCKET4677_AZIFS054P001C01-SOCA
GND                      U2               AG9      SOCKET4677_AZIFS054P001C01-SOCA
GND                      U2               AG13     SOCKET4677_AZIFS054P001C01-SOCA
GND                      U2               AG21     SOCKET4677_AZIFS054P001C01-SOCA
GND                      U2               AG27     SOCKET4677_AZIFS054P001C01-SOCA
GND                      U2               AG33     SOCKET4677_AZIFS054P001C01-SOCA
GND                      U2               AG39     SOCKET4677_AZIFS054P001C01-SOCA
GND                      U2               AG45     SOCKET4677_AZIFS054P001C01-SOCA
GND                      U2               AG52     SOCKET4677_AZIFS054P001C01-SOCA
GND                      U2               AG58     SOCKET4677_AZIFS054P001C01-SOCA
GND                      U2               AG64     SOCKET4677_AZIFS054P001C01-SOCA
GND                      U2               AG70     SOCKET4677_AZIFS054P001C01-SOCA
GND                      U2               AG76     SOCKET4677_AZIFS054P001C01-SOCA
GND                      U2               AG84     SOCKET4677_AZIFS054P001C01-SOCA
GND                      U2               AG88     SOCKET4677_AZIFS054P001C01-SOCA
GND                      U2               AH4      SOCKET4677_AZIFS054P001C01-SOCA
GND                      U2               AH8      SOCKET4677_AZIFS054P001C01-SOCA
GND                      U2               AH12     SOCKET4677_AZIFS054P001C01-SOCA
GND                      U2               AH16     SOCKET4677_AZIFS054P001C01-SOCA
GND                      U2               AH20     SOCKET4677_AZIFS054P001C01-SOCA
GND                      U2               AH22     SOCKET4677_AZIFS054P001C01-SOCA
GND                      U2               AH26     SOCKET4677_AZIFS054P001C01-SOCA
GND                      U2               AH28     SOCKET4677_AZIFS054P001C01-SOCA
GND                      U2               AH32     SOCKET4677_AZIFS054P001C01-SOCA
GND                      U2               AH34     SOCKET4677_AZIFS054P001C01-SOCA
GND                      U2               AH38     SOCKET4677_AZIFS054P001C01-SOCA
GND                      U2               AH40     SOCKET4677_AZIFS054P001C01-SOCA
GND                      U2               AH44     SOCKET4677_AZIFS054P001C01-SOCA
GND                      U2               AH47     SOCKET4677_AZIFS054P001C01-SOCA
GND                      U2               AH51     SOCKET4677_AZIFS054P001C01-SOCA
GND                      U2               AH53     SOCKET4677_AZIFS054P001C01-SOCA
GND                      U2               AH57     SOCKET4677_AZIFS054P001C01-SOCA
GND                      U2               AH59     SOCKET4677_AZIFS054P001C01-SOCA
GND                      U2               AH63     SOCKET4677_AZIFS054P001C01-SOCA
GND                      U2               AH65     SOCKET4677_AZIFS054P001C01-SOCA
GND                      U2               AH69     SOCKET4677_AZIFS054P001C01-SOCA
GND                      U2               AH71     SOCKET4677_AZIFS054P001C01-SOCA
GND                      U2               AH75     SOCKET4677_AZIFS054P001C01-SOCA
GND                      U2               AH77     SOCKET4677_AZIFS054P001C01-SOCA
GND                      U2               AH79     SOCKET4677_AZIFS054P001C01-SOCA
GND                      U2               AH83     SOCKET4677_AZIFS054P001C01-SOCA
GND                      U2               AJ19     SOCKET4677_AZIFS054P001C01-SOCA
GND                      U2               AJ23     SOCKET4677_AZIFS054P001C01-SOCA
GND                      U2               AJ25     SOCKET4677_AZIFS054P001C01-SOCA
GND                      U2               AJ29     SOCKET4677_AZIFS054P001C01-SOCA
GND                      U2               AJ31     SOCKET4677_AZIFS054P001C01-SOCA
GND                      U2               AJ35     SOCKET4677_AZIFS054P001C01-SOCA
GND                      U2               AJ37     SOCKET4677_AZIFS054P001C01-SOCA
GND                      U2               AJ41     SOCKET4677_AZIFS054P001C01-SOCA
GND                      U2               AJ43     SOCKET4677_AZIFS054P001C01-SOCA
GND                      U2               AJ48     SOCKET4677_AZIFS054P001C01-SOCA
GND                      U2               AJ50     SOCKET4677_AZIFS054P001C01-SOCA
GND                      U2               AJ54     SOCKET4677_AZIFS054P001C01-SOCA
GND                      U2               AJ56     SOCKET4677_AZIFS054P001C01-SOCA
GND                      U2               AJ60     SOCKET4677_AZIFS054P001C01-SOCA
GND                      U2               AJ62     SOCKET4677_AZIFS054P001C01-SOCA
GND                      U2               AJ66     SOCKET4677_AZIFS054P001C01-SOCA
GND                      U2               AJ68     SOCKET4677_AZIFS054P001C01-SOCA
GND                      U2               AJ72     SOCKET4677_AZIFS054P001C01-SOCA
GND                      U2               AJ74     SOCKET4677_AZIFS054P001C01-SOCA
GND                      U2               AJ78     SOCKET4677_AZIFS054P001C01-SOCA
GND                      U2               AJ84     SOCKET4677_AZIFS054P001C01-SOCA
GND                      U2               AJ88     SOCKET4677_AZIFS054P001C01-SOCA
GND                      U2               AK4      SOCKET4677_AZIFS054P001C01-SOCA
GND                      U2               AK8      SOCKET4677_AZIFS054P001C01-SOCA
GND                      U2               AK12     SOCKET4677_AZIFS054P001C01-SOCA
GND                      U2               AK16     SOCKET4677_AZIFS054P001C01-SOCA
GND                      U2               AK18     SOCKET4677_AZIFS054P001C01-SOCA
GND                      U2               AK24     SOCKET4677_AZIFS054P001C01-SOCA
GND                      U2               AK30     SOCKET4677_AZIFS054P001C01-SOCA
GND                      U2               AK36     SOCKET4677_AZIFS054P001C01-SOCA
GND                      U2               AK42     SOCKET4677_AZIFS054P001C01-SOCA
GND                      U2               AK49     SOCKET4677_AZIFS054P001C01-SOCA
GND                      U2               AK55     SOCKET4677_AZIFS054P001C01-SOCA
GND                      U2               AK61     SOCKET4677_AZIFS054P001C01-SOCA
GND                      U2               AK67     SOCKET4677_AZIFS054P001C01-SOCA
GND                      U2               AK73     SOCKET4677_AZIFS054P001C01-SOCA
GND                      U2               AK79     SOCKET4677_AZIFS054P001C01-SOCA
GND                      U2               AK81     SOCKET4677_AZIFS054P001C01-SOCA
GND                      U2               AK83     SOCKET4677_AZIFS054P001C01-SOCA
GND                      U2               AK87     SOCKET4677_AZIFS054P001C01-SOCA
GND                      U2               AK91     SOCKET4677_AZIFS054P001C01-SOCA
GND                      U2               AL1      SOCKET4677_AZIFS054P001C01-SOCA
GND                      U2               AL5      SOCKET4677_AZIFS054P001C01-SOCA
GND                      U2               AL9      SOCKET4677_AZIFS054P001C01-SOCA
GND                      U2               AL13     SOCKET4677_AZIFS054P001C01-SOCA
GND                      U2               AL17     SOCKET4677_AZIFS054P001C01-SOCA
GND                      U2               AL52     SOCKET4677_AZIFS054P001C01-SOCA
GND                      U2               AL80     SOCKET4677_AZIFS054P001C01-SOCA
GND                      U2               AL82     SOCKET4677_AZIFS054P001C01-SOCA
GND                      U2               AL84     SOCKET4677_AZIFS054P001C01-SOCA
GND                      U2               AL88     SOCKET4677_AZIFS054P001C01-SOCA
GND                      U2               AM4      SOCKET4677_AZIFS054P001C01-SOCA
GND                      U2               AM8      SOCKET4677_AZIFS054P001C01-SOCA
GND                      U2               AM12     SOCKET4677_AZIFS054P001C01-SOCA
GND                      U2               AM16     SOCKET4677_AZIFS054P001C01-SOCA
GND                      U2               AM18     SOCKET4677_AZIFS054P001C01-SOCA
GND                      U2               AM20     SOCKET4677_AZIFS054P001C01-SOCA
GND                      U2               AM22     SOCKET4677_AZIFS054P001C01-SOCA
GND                      U2               AM24     SOCKET4677_AZIFS054P001C01-SOCA
GND                      U2               AM26     SOCKET4677_AZIFS054P001C01-SOCA
GND                      U2               AM28     SOCKET4677_AZIFS054P001C01-SOCA
GND                      U2               AM30     SOCKET4677_AZIFS054P001C01-SOCA
GND                      U2               AM32     SOCKET4677_AZIFS054P001C01-SOCA
GND                      U2               AM34     SOCKET4677_AZIFS054P001C01-SOCA
GND                      U2               AM36     SOCKET4677_AZIFS054P001C01-SOCA
GND                      U2               AM38     SOCKET4677_AZIFS054P001C01-SOCA
GND                      U2               AM40     SOCKET4677_AZIFS054P001C01-SOCA
GND                      U2               AM42     SOCKET4677_AZIFS054P001C01-SOCA
GND                      U2               AM44     SOCKET4677_AZIFS054P001C01-SOCA
GND                      U2               AM47     SOCKET4677_AZIFS054P001C01-SOCA
GND                      U2               AM49     SOCKET4677_AZIFS054P001C01-SOCA
GND                      U2               AM51     SOCKET4677_AZIFS054P001C01-SOCA
GND                      U2               AM53     SOCKET4677_AZIFS054P001C01-SOCA
GND                      U2               AM55     SOCKET4677_AZIFS054P001C01-SOCA
GND                      U2               AM57     SOCKET4677_AZIFS054P001C01-SOCA
GND                      U2               AM59     SOCKET4677_AZIFS054P001C01-SOCA
GND                      U2               AM61     SOCKET4677_AZIFS054P001C01-SOCA
GND                      U2               AM63     SOCKET4677_AZIFS054P001C01-SOCA
GND                      U2               AM65     SOCKET4677_AZIFS054P001C01-SOCA
GND                      U2               AM67     SOCKET4677_AZIFS054P001C01-SOCA
GND                      U2               AM69     SOCKET4677_AZIFS054P001C01-SOCA
GND                      U2               AM71     SOCKET4677_AZIFS054P001C01-SOCA
GND                      U2               AM73     SOCKET4677_AZIFS054P001C01-SOCA
GND                      U2               AM75     SOCKET4677_AZIFS054P001C01-SOCA
GND                      U2               AM77     SOCKET4677_AZIFS054P001C01-SOCA
GND                      U2               AN52     SOCKET4677_AZIFS054P001C01-SOCA
GND                      U2               AN84     SOCKET4677_AZIFS054P001C01-SOCA
GND                      U2               AN88     SOCKET4677_AZIFS054P001C01-SOCA
GND                      U2               AP4      SOCKET4677_AZIFS054P001C01-SOCA
GND                      U2               AP8      SOCKET4677_AZIFS054P001C01-SOCA
GND                      U2               AP12     SOCKET4677_AZIFS054P001C01-SOCA
GND                      U2               AP16     SOCKET4677_AZIFS054P001C01-SOCA
GND                      U2               AP18     SOCKET4677_AZIFS054P001C01-SOCA
GND                      U2               AP24     SOCKET4677_AZIFS054P001C01-SOCA
GND                      U2               AP30     SOCKET4677_AZIFS054P001C01-SOCA
GND                      U2               AP36     SOCKET4677_AZIFS054P001C01-SOCA
GND                      U2               AP42     SOCKET4677_AZIFS054P001C01-SOCA
GND                      U2               AP49     SOCKET4677_AZIFS054P001C01-SOCA
GND                      U2               AP55     SOCKET4677_AZIFS054P001C01-SOCA
GND                      U2               AP61     SOCKET4677_AZIFS054P001C01-SOCA
GND                      U2               AP67     SOCKET4677_AZIFS054P001C01-SOCA
GND                      U2               AP73     SOCKET4677_AZIFS054P001C01-SOCA
GND                      U2               AP79     SOCKET4677_AZIFS054P001C01-SOCA
GND                      U2               AP83     SOCKET4677_AZIFS054P001C01-SOCA
GND                      U2               AP87     SOCKET4677_AZIFS054P001C01-SOCA
GND                      U2               AP91     SOCKET4677_AZIFS054P001C01-SOCA
GND                      U2               AR1      SOCKET4677_AZIFS054P001C01-SOCA
GND                      U2               AR5      SOCKET4677_AZIFS054P001C01-SOCA
GND                      U2               AR9      SOCKET4677_AZIFS054P001C01-SOCA
GND                      U2               AR13     SOCKET4677_AZIFS054P001C01-SOCA
GND                      U2               AR19     SOCKET4677_AZIFS054P001C01-SOCA
GND                      U2               AR23     SOCKET4677_AZIFS054P001C01-SOCA
GND                      U2               AR25     SOCKET4677_AZIFS054P001C01-SOCA
GND                      U2               AR29     SOCKET4677_AZIFS054P001C01-SOCA
GND                      U2               AR31     SOCKET4677_AZIFS054P001C01-SOCA
GND                      U2               AR35     SOCKET4677_AZIFS054P001C01-SOCA
GND                      U2               AR37     SOCKET4677_AZIFS054P001C01-SOCA
GND                      U2               AR41     SOCKET4677_AZIFS054P001C01-SOCA
GND                      U2               AR43     SOCKET4677_AZIFS054P001C01-SOCA
GND                      U2               AR48     SOCKET4677_AZIFS054P001C01-SOCA
GND                      U2               AR50     SOCKET4677_AZIFS054P001C01-SOCA
GND                      U2               AR54     SOCKET4677_AZIFS054P001C01-SOCA
GND                      U2               AR56     SOCKET4677_AZIFS054P001C01-SOCA
GND                      U2               AR60     SOCKET4677_AZIFS054P001C01-SOCA
GND                      U2               AR62     SOCKET4677_AZIFS054P001C01-SOCA
GND                      U2               AR66     SOCKET4677_AZIFS054P001C01-SOCA
GND                      U2               AR68     SOCKET4677_AZIFS054P001C01-SOCA
GND                      U2               AR72     SOCKET4677_AZIFS054P001C01-SOCA
GND                      U2               AR74     SOCKET4677_AZIFS054P001C01-SOCA
GND                      U2               AR78     SOCKET4677_AZIFS054P001C01-SOCA
GND                      U2               AR82     SOCKET4677_AZIFS054P001C01-SOCA
GND                      U2               AR84     SOCKET4677_AZIFS054P001C01-SOCA
GND                      U2               AR88     SOCKET4677_AZIFS054P001C01-SOCA
GND                      U2               AT4      SOCKET4677_AZIFS054P001C01-SOCA
GND                      U2               AT8      SOCKET4677_AZIFS054P001C01-SOCA
GND                      U2               AT12     SOCKET4677_AZIFS054P001C01-SOCA
GND                      U2               AT16     SOCKET4677_AZIFS054P001C01-SOCA
GND                      U2               AT20     SOCKET4677_AZIFS054P001C01-SOCA
GND                      U2               AT22     SOCKET4677_AZIFS054P001C01-SOCA
GND                      U2               AT26     SOCKET4677_AZIFS054P001C01-SOCA
GND                      U2               AT28     SOCKET4677_AZIFS054P001C01-SOCA
GND                      U2               AT32     SOCKET4677_AZIFS054P001C01-SOCA
GND                      U2               AT34     SOCKET4677_AZIFS054P001C01-SOCA
GND                      U2               AT38     SOCKET4677_AZIFS054P001C01-SOCA
GND                      U2               AT40     SOCKET4677_AZIFS054P001C01-SOCA
GND                      U2               AT44     SOCKET4677_AZIFS054P001C01-SOCA
GND                      U2               AT51     SOCKET4677_AZIFS054P001C01-SOCA
GND                      U2               AT53     SOCKET4677_AZIFS054P001C01-SOCA
GND                      U2               AT57     SOCKET4677_AZIFS054P001C01-SOCA
GND                      U2               AT59     SOCKET4677_AZIFS054P001C01-SOCA
GND                      U2               AT63     SOCKET4677_AZIFS054P001C01-SOCA
GND                      U2               AT65     SOCKET4677_AZIFS054P001C01-SOCA
GND                      U2               AT69     SOCKET4677_AZIFS054P001C01-SOCA
GND                      U2               AT71     SOCKET4677_AZIFS054P001C01-SOCA
GND                      U2               AT75     SOCKET4677_AZIFS054P001C01-SOCA
GND                      U2               AT77     SOCKET4677_AZIFS054P001C01-SOCA
GND                      U2               AT79     SOCKET4677_AZIFS054P001C01-SOCA
GND                      U2               AU27     SOCKET4677_AZIFS054P001C01-SOCA
GND                      U2               AU31     SOCKET4677_AZIFS054P001C01-SOCA
GND                      U2               AU37     SOCKET4677_AZIFS054P001C01-SOCA
GND                      U2               AU39     SOCKET4677_AZIFS054P001C01-SOCA
GND                      U2               AU41     SOCKET4677_AZIFS054P001C01-SOCA
GND                      U2               AU45     SOCKET4677_AZIFS054P001C01-SOCA
GND                      U2               AU48     SOCKET4677_AZIFS054P001C01-SOCA
GND                      U2               AU70     SOCKET4677_AZIFS054P001C01-SOCA
GND                      U2               AU72     SOCKET4677_AZIFS054P001C01-SOCA
GND                      U2               AU74     SOCKET4677_AZIFS054P001C01-SOCA
GND                      U2               AU76     SOCKET4677_AZIFS054P001C01-SOCA
GND                      U2               AU80     SOCKET4677_AZIFS054P001C01-SOCA
GND                      U2               AU84     SOCKET4677_AZIFS054P001C01-SOCA
GND                      U2               AU88     SOCKET4677_AZIFS054P001C01-SOCA
GND                      U2               AV4      SOCKET4677_AZIFS054P001C01-SOCA
GND                      U2               AV8      SOCKET4677_AZIFS054P001C01-SOCA
GND                      U2               AV12     SOCKET4677_AZIFS054P001C01-SOCA
GND                      U2               AV16     SOCKET4677_AZIFS054P001C01-SOCA
GND                      U2               AV77     SOCKET4677_AZIFS054P001C01-SOCA
GND                      U2               AV87     SOCKET4677_AZIFS054P001C01-SOCA
GND                      U2               AV91     SOCKET4677_AZIFS054P001C01-SOCA
GND                      U2               AW1      SOCKET4677_AZIFS054P001C01-SOCA
GND                      U2               AW5      SOCKET4677_AZIFS054P001C01-SOCA
GND                      U2               AW9      SOCKET4677_AZIFS054P001C01-SOCA
GND                      U2               AW13     SOCKET4677_AZIFS054P001C01-SOCA
GND                      U2               AW21     SOCKET4677_AZIFS054P001C01-SOCA
GND                      U2               AW23     SOCKET4677_AZIFS054P001C01-SOCA
GND                      U2               AW25     SOCKET4677_AZIFS054P001C01-SOCA
GND                      U2               AW62     SOCKET4677_AZIFS054P001C01-SOCA
GND                      U2               AW66     SOCKET4677_AZIFS054P001C01-SOCA
GND                      U2               AW68     SOCKET4677_AZIFS054P001C01-SOCA
GND                      U2               AW72     SOCKET4677_AZIFS054P001C01-SOCA
GND                      U2               AW80     SOCKET4677_AZIFS054P001C01-SOCA
GND                      U2               AW82     SOCKET4677_AZIFS054P001C01-SOCA
GND                      U2               AW84     SOCKET4677_AZIFS054P001C01-SOCA
GND                      U2               AW88     SOCKET4677_AZIFS054P001C01-SOCA
GND                      U2               AY4      SOCKET4677_AZIFS054P001C01-SOCA
GND                      U2               AY8      SOCKET4677_AZIFS054P001C01-SOCA
GND                      U2               AY12     SOCKET4677_AZIFS054P001C01-SOCA
GND                      U2               AY16     SOCKET4677_AZIFS054P001C01-SOCA
GND                      U2               AY71     SOCKET4677_AZIFS054P001C01-SOCA
GND                      U2               AY77     SOCKET4677_AZIFS054P001C01-SOCA
GND                      U2               AY79     SOCKET4677_AZIFS054P001C01-SOCA
GND                      U2               AY81     SOCKET4677_AZIFS054P001C01-SOCA
GND                      U2               AY83     SOCKET4677_AZIFS054P001C01-SOCA
GND                      U2               B6       SOCKET4677_AZIFS054P001C01-SOCA
GND                      U2               B12      SOCKET4677_AZIFS054P001C01-SOCA
GND                      U2               B18      SOCKET4677_AZIFS054P001C01-SOCA
GND                      U2               B24      SOCKET4677_AZIFS054P001C01-SOCA
GND                      U2               B30      SOCKET4677_AZIFS054P001C01-SOCA
GND                      U2               B36      SOCKET4677_AZIFS054P001C01-SOCA
GND                      U2               B42      SOCKET4677_AZIFS054P001C01-SOCA
GND                      U2               B49      SOCKET4677_AZIFS054P001C01-SOCA
GND                      U2               B55      SOCKET4677_AZIFS054P001C01-SOCA
GND                      U2               B61      SOCKET4677_AZIFS054P001C01-SOCA
GND                      U2               B67      SOCKET4677_AZIFS054P001C01-SOCA
GND                      U2               B75      SOCKET4677_AZIFS054P001C01-SOCA
GND                      U2               B83      SOCKET4677_AZIFS054P001C01-SOCA
GND                      U2               B87      SOCKET4677_AZIFS054P001C01-SOCA
GND                      U2               BA17     SOCKET4677_AZIFS054P001C01-SOCA
GND                      U2               BA60     SOCKET4677_AZIFS054P001C01-SOCA
GND                      U2               BA64     SOCKET4677_AZIFS054P001C01-SOCA
GND                      U2               BA74     SOCKET4677_AZIFS054P001C01-SOCA
GND                      U2               BA84     SOCKET4677_AZIFS054P001C01-SOCA
GND                      U2               BA88     SOCKET4677_AZIFS054P001C01-SOCA
GND                      U2               BB4      SOCKET4677_AZIFS054P001C01-SOCA
GND                      U2               BB8      SOCKET4677_AZIFS054P001C01-SOCA
GND                      U2               BB10     SOCKET4677_AZIFS054P001C01-SOCA
GND                      U2               BB12     SOCKET4677_AZIFS054P001C01-SOCA
GND                      U2               BB16     SOCKET4677_AZIFS054P001C01-SOCA
GND                      U2               BB20     SOCKET4677_AZIFS054P001C01-SOCA
GND                      U2               BB22     SOCKET4677_AZIFS054P001C01-SOCA
GND                      U2               BB24     SOCKET4677_AZIFS054P001C01-SOCA
GND                      U2               BB26     SOCKET4677_AZIFS054P001C01-SOCA
GND                      U2               BB63     SOCKET4677_AZIFS054P001C01-SOCA
GND                      U2               BB69     SOCKET4677_AZIFS054P001C01-SOCA
GND                      U2               BB71     SOCKET4677_AZIFS054P001C01-SOCA
GND                      U2               BB77     SOCKET4677_AZIFS054P001C01-SOCA
GND                      U2               BB79     SOCKET4677_AZIFS054P001C01-SOCA
GND                      U2               BB83     SOCKET4677_AZIFS054P001C01-SOCA
GND                      U2               BB87     SOCKET4677_AZIFS054P001C01-SOCA
GND                      U2               BB91     SOCKET4677_AZIFS054P001C01-SOCA
GND                      U2               BC1      SOCKET4677_AZIFS054P001C01-SOCA
GND                      U2               BC5      SOCKET4677_AZIFS054P001C01-SOCA
GND                      U2               BC9      SOCKET4677_AZIFS054P001C01-SOCA
GND                      U2               BC13     SOCKET4677_AZIFS054P001C01-SOCA
GND                      U2               BC17     SOCKET4677_AZIFS054P001C01-SOCA
GND                      U2               BC62     SOCKET4677_AZIFS054P001C01-SOCA
GND                      U2               BC66     SOCKET4677_AZIFS054P001C01-SOCA
GND                      U2               BC72     SOCKET4677_AZIFS054P001C01-SOCA
GND                      U2               BC76     SOCKET4677_AZIFS054P001C01-SOCA
GND                      U2               BC78     SOCKET4677_AZIFS054P001C01-SOCA
GND                      U2               BC84     SOCKET4677_AZIFS054P001C01-SOCA
GND                      U2               BC86     SOCKET4677_AZIFS054P001C01-SOCA
GND                      U2               BC88     SOCKET4677_AZIFS054P001C01-SOCA
GND                      U2               BD4      SOCKET4677_AZIFS054P001C01-SOCA
GND                      U2               BD8      SOCKET4677_AZIFS054P001C01-SOCA
GND                      U2               BD12     SOCKET4677_AZIFS054P001C01-SOCA
GND                      U2               BD16     SOCKET4677_AZIFS054P001C01-SOCA
GND                      U2               BD20     SOCKET4677_AZIFS054P001C01-SOCA
GND                      U2               BD81     SOCKET4677_AZIFS054P001C01-SOCA
GND                      U2               BD85     SOCKET4677_AZIFS054P001C01-SOCA
GND                      U2               BD89     SOCKET4677_AZIFS054P001C01-SOCA
GND                      U2               BE64     SOCKET4677_AZIFS054P001C01-SOCA
GND                      U2               BE66     SOCKET4677_AZIFS054P001C01-SOCA
GND                      U2               BE68     SOCKET4677_AZIFS054P001C01-SOCA
GND                      U2               BE74     SOCKET4677_AZIFS054P001C01-SOCA
GND                      U2               BE76     SOCKET4677_AZIFS054P001C01-SOCA
GND                      U2               BE78     SOCKET4677_AZIFS054P001C01-SOCA
GND                      U2               BE84     SOCKET4677_AZIFS054P001C01-SOCA
GND                      U2               BF4      SOCKET4677_AZIFS054P001C01-SOCA
GND                      U2               BF8      SOCKET4677_AZIFS054P001C01-SOCA
GND                      U2               BF12     SOCKET4677_AZIFS054P001C01-SOCA
GND                      U2               BF16     SOCKET4677_AZIFS054P001C01-SOCA
GND                      U2               BF20     SOCKET4677_AZIFS054P001C01-SOCA
GND                      U2               BF61     SOCKET4677_AZIFS054P001C01-SOCA
GND                      U2               BF63     SOCKET4677_AZIFS054P001C01-SOCA
GND                      U2               BF73     SOCKET4677_AZIFS054P001C01-SOCA
GND                      U2               BF75     SOCKET4677_AZIFS054P001C01-SOCA
GND                      U2               BF79     SOCKET4677_AZIFS054P001C01-SOCA
GND                      U2               BF83     SOCKET4677_AZIFS054P001C01-SOCA
GND                      U2               BG1      SOCKET4677_AZIFS054P001C01-SOCA
GND                      U2               BG5      SOCKET4677_AZIFS054P001C01-SOCA
GND                      U2               BG9      SOCKET4677_AZIFS054P001C01-SOCA
GND                      U2               BG13     SOCKET4677_AZIFS054P001C01-SOCA
GND                      U2               BG17     SOCKET4677_AZIFS054P001C01-SOCA
GND                      U2               BG21     SOCKET4677_AZIFS054P001C01-SOCA
GND                      U2               BG23     SOCKET4677_AZIFS054P001C01-SOCA
GND                      U2               BG25     SOCKET4677_AZIFS054P001C01-SOCA
GND                      U2               BG70     SOCKET4677_AZIFS054P001C01-SOCA
GND                      U2               BH4      SOCKET4677_AZIFS054P001C01-SOCA
GND                      U2               BH8      SOCKET4677_AZIFS054P001C01-SOCA
GND                      U2               BH12     SOCKET4677_AZIFS054P001C01-SOCA
GND                      U2               BH16     SOCKET4677_AZIFS054P001C01-SOCA
GND                      U2               BH20     SOCKET4677_AZIFS054P001C01-SOCA
GND                      U2               BH67     SOCKET4677_AZIFS054P001C01-SOCA
GND                      U2               BH73     SOCKET4677_AZIFS054P001C01-SOCA
GND                      U2               BH77     SOCKET4677_AZIFS054P001C01-SOCA
GND                      U2               BH81     SOCKET4677_AZIFS054P001C01-SOCA
GND                      U2               BH83     SOCKET4677_AZIFS054P001C01-SOCA
GND                      U2               BJ62     SOCKET4677_AZIFS054P001C01-SOCA
GND                      U2               BJ68     SOCKET4677_AZIFS054P001C01-SOCA
GND                      U2               BJ80     SOCKET4677_AZIFS054P001C01-SOCA
GND                      U2               BJ82     SOCKET4677_AZIFS054P001C01-SOCA
GND                      U2               BJ84     SOCKET4677_AZIFS054P001C01-SOCA
GND                      U2               BJ86     SOCKET4677_AZIFS054P001C01-SOCA
GND                      U2               BJ88     SOCKET4677_AZIFS054P001C01-SOCA
GND                      U2               BJ90     SOCKET4677_AZIFS054P001C01-SOCA
GND                      U2               BK4      SOCKET4677_AZIFS054P001C01-SOCA
GND                      U2               BK8      SOCKET4677_AZIFS054P001C01-SOCA
GND                      U2               BK12     SOCKET4677_AZIFS054P001C01-SOCA
GND                      U2               BK16     SOCKET4677_AZIFS054P001C01-SOCA
GND                      U2               BK20     SOCKET4677_AZIFS054P001C01-SOCA
GND                      U2               BK65     SOCKET4677_AZIFS054P001C01-SOCA
GND                      U2               BK71     SOCKET4677_AZIFS054P001C01-SOCA
GND                      U2               BK75     SOCKET4677_AZIFS054P001C01-SOCA
GND                      U2               BK79     SOCKET4677_AZIFS054P001C01-SOCA
GND                      U2               BL1      SOCKET4677_AZIFS054P001C01-SOCA
GND                      U2               BL5      SOCKET4677_AZIFS054P001C01-SOCA
GND                      U2               BL9      SOCKET4677_AZIFS054P001C01-SOCA
GND                      U2               BL13     SOCKET4677_AZIFS054P001C01-SOCA
GND                      U2               BL17     SOCKET4677_AZIFS054P001C01-SOCA
GND                      U2               BL68     SOCKET4677_AZIFS054P001C01-SOCA
GND                      U2               BL70     SOCKET4677_AZIFS054P001C01-SOCA
GND                      U2               BL72     SOCKET4677_AZIFS054P001C01-SOCA
GND                      U2               BL78     SOCKET4677_AZIFS054P001C01-SOCA
GND                      U2               BM4      SOCKET4677_AZIFS054P001C01-SOCA
GND                      U2               BM8      SOCKET4677_AZIFS054P001C01-SOCA
GND                      U2               BM12     SOCKET4677_AZIFS054P001C01-SOCA
GND                      U2               BM16     SOCKET4677_AZIFS054P001C01-SOCA
GND                      U2               BM20     SOCKET4677_AZIFS054P001C01-SOCA
GND                      U2               BM22     SOCKET4677_AZIFS054P001C01-SOCA
GND                      U2               BM24     SOCKET4677_AZIFS054P001C01-SOCA
GND                      U2               BM26     SOCKET4677_AZIFS054P001C01-SOCA
GND                      U2               BM61     SOCKET4677_AZIFS054P001C01-SOCA
GND                      U2               BM73     SOCKET4677_AZIFS054P001C01-SOCA
GND                      U2               BM77     SOCKET4677_AZIFS054P001C01-SOCA
GND                      U2               BN31     SOCKET4677_AZIFS054P001C01-SOCA
GND                      U2               BN62     SOCKET4677_AZIFS054P001C01-SOCA
GND                      U2               BN70     SOCKET4677_AZIFS054P001C01-SOCA
GND                      U2               BP2      SOCKET4677_AZIFS054P001C01-SOCA
GND                      U2               BP4      SOCKET4677_AZIFS054P001C01-SOCA
GND                      U2               BP8      SOCKET4677_AZIFS054P001C01-SOCA
GND                      U2               BP12     SOCKET4677_AZIFS054P001C01-SOCA
GND                      U2               BP16     SOCKET4677_AZIFS054P001C01-SOCA
GND                      U2               BP20     SOCKET4677_AZIFS054P001C01-SOCA
GND                      U2               BP63     SOCKET4677_AZIFS054P001C01-SOCA
GND                      U2               BP71     SOCKET4677_AZIFS054P001C01-SOCA
GND                      U2               BP73     SOCKET4677_AZIFS054P001C01-SOCA
GND                      U2               BP75     SOCKET4677_AZIFS054P001C01-SOCA
GND                      U2               BP77     SOCKET4677_AZIFS054P001C01-SOCA
GND                      U2               BR5      SOCKET4677_AZIFS054P001C01-SOCA
GND                      U2               BR9      SOCKET4677_AZIFS054P001C01-SOCA
GND                      U2               BR13     SOCKET4677_AZIFS054P001C01-SOCA
GND                      U2               BR17     SOCKET4677_AZIFS054P001C01-SOCA
GND                      U2               BR27     SOCKET4677_AZIFS054P001C01-SOCA
GND                      U2               BR29     SOCKET4677_AZIFS054P001C01-SOCA
GND                      U2               BR31     SOCKET4677_AZIFS054P001C01-SOCA
GND                      U2               BR33     SOCKET4677_AZIFS054P001C01-SOCA
GND                      U2               BR35     SOCKET4677_AZIFS054P001C01-SOCA
GND                      U2               BR37     SOCKET4677_AZIFS054P001C01-SOCA
GND                      U2               BR39     SOCKET4677_AZIFS054P001C01-SOCA
GND                      U2               BR41     SOCKET4677_AZIFS054P001C01-SOCA
GND                      U2               BR43     SOCKET4677_AZIFS054P001C01-SOCA
GND                      U2               BR45     SOCKET4677_AZIFS054P001C01-SOCA
GND                      U2               BR48     SOCKET4677_AZIFS054P001C01-SOCA
GND                      U2               BR50     SOCKET4677_AZIFS054P001C01-SOCA
GND                      U2               BR52     SOCKET4677_AZIFS054P001C01-SOCA
GND                      U2               BR54     SOCKET4677_AZIFS054P001C01-SOCA
GND                      U2               BR56     SOCKET4677_AZIFS054P001C01-SOCA
GND                      U2               BR58     SOCKET4677_AZIFS054P001C01-SOCA
GND                      U2               BR64     SOCKET4677_AZIFS054P001C01-SOCA
GND                      U2               BR66     SOCKET4677_AZIFS054P001C01-SOCA
GND                      U2               BR68     SOCKET4677_AZIFS054P001C01-SOCA
GND                      U2               BR70     SOCKET4677_AZIFS054P001C01-SOCA
GND                      U2               BR72     SOCKET4677_AZIFS054P001C01-SOCA
GND                      U2               BR74     SOCKET4677_AZIFS054P001C01-SOCA
GND                      U2               BR76     SOCKET4677_AZIFS054P001C01-SOCA
GND                      U2               BR80     SOCKET4677_AZIFS054P001C01-SOCA
GND                      U2               BR82     SOCKET4677_AZIFS054P001C01-SOCA
GND                      U2               BR84     SOCKET4677_AZIFS054P001C01-SOCA
GND                      U2               BR86     SOCKET4677_AZIFS054P001C01-SOCA
GND                      U2               BR88     SOCKET4677_AZIFS054P001C01-SOCA
GND                      U2               BR90     SOCKET4677_AZIFS054P001C01-SOCA
GND                      U2               BT4      SOCKET4677_AZIFS054P001C01-SOCA
GND                      U2               BT8      SOCKET4677_AZIFS054P001C01-SOCA
GND                      U2               BT12     SOCKET4677_AZIFS054P001C01-SOCA
GND                      U2               BT16     SOCKET4677_AZIFS054P001C01-SOCA
GND                      U2               BT20     SOCKET4677_AZIFS054P001C01-SOCA
GND                      U2               BU7      SOCKET4677_AZIFS054P001C01-SOCA
GND                      U2               BU15     SOCKET4677_AZIFS054P001C01-SOCA
GND                      U2               BU19     SOCKET4677_AZIFS054P001C01-SOCA
GND                      U2               BU21     SOCKET4677_AZIFS054P001C01-SOCA
GND                      U2               BU23     SOCKET4677_AZIFS054P001C01-SOCA
GND                      U2               BU25     SOCKET4677_AZIFS054P001C01-SOCA
GND                      U2               BU31     SOCKET4677_AZIFS054P001C01-SOCA
GND                      U2               BV2      SOCKET4677_AZIFS054P001C01-SOCA
GND                      U2               BV4      SOCKET4677_AZIFS054P001C01-SOCA
GND                      U2               BV6      SOCKET4677_AZIFS054P001C01-SOCA
GND                      U2               BV8      SOCKET4677_AZIFS054P001C01-SOCA
GND                      U2               BV12     SOCKET4677_AZIFS054P001C01-SOCA
GND                      U2               BV16     SOCKET4677_AZIFS054P001C01-SOCA
GND                      U2               BV18     SOCKET4677_AZIFS054P001C01-SOCA
GND                      U2               BV20     SOCKET4677_AZIFS054P001C01-SOCA
GND                      U2               BW3      SOCKET4677_AZIFS054P001C01-SOCA
GND                      U2               BW5      SOCKET4677_AZIFS054P001C01-SOCA
GND                      U2               BW9      SOCKET4677_AZIFS054P001C01-SOCA
GND                      U2               BW13     SOCKET4677_AZIFS054P001C01-SOCA
GND                      U2               BW17     SOCKET4677_AZIFS054P001C01-SOCA
GND                      U2               BW27     SOCKET4677_AZIFS054P001C01-SOCA
GND                      U2               BW29     SOCKET4677_AZIFS054P001C01-SOCA
GND                      U2               BW31     SOCKET4677_AZIFS054P001C01-SOCA
GND                      U2               BY4      SOCKET4677_AZIFS054P001C01-SOCA
GND                      U2               BY8      SOCKET4677_AZIFS054P001C01-SOCA
GND                      U2               BY12     SOCKET4677_AZIFS054P001C01-SOCA
GND                      U2               BY16     SOCKET4677_AZIFS054P001C01-SOCA
GND                      U2               BY20     SOCKET4677_AZIFS054P001C01-SOCA
GND                      U2               C5       SOCKET4677_AZIFS054P001C01-SOCA
GND                      U2               C39      SOCKET4677_AZIFS054P001C01-SOCA
GND                      U2               C45      SOCKET4677_AZIFS054P001C01-SOCA
GND                      U2               C52      SOCKET4677_AZIFS054P001C01-SOCA
GND                      U2               C72      SOCKET4677_AZIFS054P001C01-SOCA
GND                      U2               C74      SOCKET4677_AZIFS054P001C01-SOCA
GND                      U2               C78      SOCKET4677_AZIFS054P001C01-SOCA
GND                      U2               C80      SOCKET4677_AZIFS054P001C01-SOCA
GND                      U2               C82      SOCKET4677_AZIFS054P001C01-SOCA
GND                      U2               C86      SOCKET4677_AZIFS054P001C01-SOCA
GND                      U2               CA3      SOCKET4677_AZIFS054P001C01-SOCA
GND                      U2               CA31     SOCKET4677_AZIFS054P001C01-SOCA
GND                      U2               CB4      SOCKET4677_AZIFS054P001C01-SOCA
GND                      U2               CB8      SOCKET4677_AZIFS054P001C01-SOCA
GND                      U2               CB12     SOCKET4677_AZIFS054P001C01-SOCA
GND                      U2               CB16     SOCKET4677_AZIFS054P001C01-SOCA
GND                      U2               CB20     SOCKET4677_AZIFS054P001C01-SOCA
GND                      U2               CB22     SOCKET4677_AZIFS054P001C01-SOCA
GND                      U2               CB24     SOCKET4677_AZIFS054P001C01-SOCA
GND                      U2               CB26     SOCKET4677_AZIFS054P001C01-SOCA
GND                      U2               CB28     SOCKET4677_AZIFS054P001C01-SOCA
GND                      U2               CB32     SOCKET4677_AZIFS054P001C01-SOCA
GND                      U2               CB34     SOCKET4677_AZIFS054P001C01-SOCA
GND                      U2               CB36     SOCKET4677_AZIFS054P001C01-SOCA
GND                      U2               CB38     SOCKET4677_AZIFS054P001C01-SOCA
GND                      U2               CB40     SOCKET4677_AZIFS054P001C01-SOCA
GND                      U2               CB42     SOCKET4677_AZIFS054P001C01-SOCA
GND                      U2               CB44     SOCKET4677_AZIFS054P001C01-SOCA
GND                      U2               CB47     SOCKET4677_AZIFS054P001C01-SOCA
GND                      U2               CB49     SOCKET4677_AZIFS054P001C01-SOCA
GND                      U2               CB51     SOCKET4677_AZIFS054P001C01-SOCA
GND                      U2               CB53     SOCKET4677_AZIFS054P001C01-SOCA
GND                      U2               CB55     SOCKET4677_AZIFS054P001C01-SOCA
GND                      U2               CB57     SOCKET4677_AZIFS054P001C01-SOCA
GND                      U2               CB59     SOCKET4677_AZIFS054P001C01-SOCA
GND                      U2               CB63     SOCKET4677_AZIFS054P001C01-SOCA
GND                      U2               CB65     SOCKET4677_AZIFS054P001C01-SOCA
GND                      U2               CB67     SOCKET4677_AZIFS054P001C01-SOCA
GND                      U2               CB69     SOCKET4677_AZIFS054P001C01-SOCA
GND                      U2               CB71     SOCKET4677_AZIFS054P001C01-SOCA
GND                      U2               CB73     SOCKET4677_AZIFS054P001C01-SOCA
GND                      U2               CB79     SOCKET4677_AZIFS054P001C01-SOCA
GND                      U2               CB81     SOCKET4677_AZIFS054P001C01-SOCA
GND                      U2               CB83     SOCKET4677_AZIFS054P001C01-SOCA
GND                      U2               CB85     SOCKET4677_AZIFS054P001C01-SOCA
GND                      U2               CB87     SOCKET4677_AZIFS054P001C01-SOCA
GND                      U2               CB89     SOCKET4677_AZIFS054P001C01-SOCA
GND                      U2               CC5      SOCKET4677_AZIFS054P001C01-SOCA
GND                      U2               CC9      SOCKET4677_AZIFS054P001C01-SOCA
GND                      U2               CC13     SOCKET4677_AZIFS054P001C01-SOCA
GND                      U2               CC17     SOCKET4677_AZIFS054P001C01-SOCA
GND                      U2               CC31     SOCKET4677_AZIFS054P001C01-SOCA
GND                      U2               CC62     SOCKET4677_AZIFS054P001C01-SOCA
GND                      U2               CC70     SOCKET4677_AZIFS054P001C01-SOCA
GND                      U2               CC72     SOCKET4677_AZIFS054P001C01-SOCA
GND                      U2               CC74     SOCKET4677_AZIFS054P001C01-SOCA
GND                      U2               CD4      SOCKET4677_AZIFS054P001C01-SOCA
GND                      U2               CD8      SOCKET4677_AZIFS054P001C01-SOCA
GND                      U2               CD12     SOCKET4677_AZIFS054P001C01-SOCA
GND                      U2               CD16     SOCKET4677_AZIFS054P001C01-SOCA
GND                      U2               CD20     SOCKET4677_AZIFS054P001C01-SOCA
GND                      U2               CD61     SOCKET4677_AZIFS054P001C01-SOCA
GND                      U2               CD75     SOCKET4677_AZIFS054P001C01-SOCA
GND                      U2               CD77     SOCKET4677_AZIFS054P001C01-SOCA
GND                      U2               CE3      SOCKET4677_AZIFS054P001C01-SOCA
GND                      U2               CE60     SOCKET4677_AZIFS054P001C01-SOCA
GND                      U2               CE66     SOCKET4677_AZIFS054P001C01-SOCA
GND                      U2               CE72     SOCKET4677_AZIFS054P001C01-SOCA
GND                      U2               CE76     SOCKET4677_AZIFS054P001C01-SOCA
GND                      U2               CE78     SOCKET4677_AZIFS054P001C01-SOCA
GND                      U2               CF4      SOCKET4677_AZIFS054P001C01-SOCA
GND                      U2               CF8      SOCKET4677_AZIFS054P001C01-SOCA
GND                      U2               CF12     SOCKET4677_AZIFS054P001C01-SOCA
GND                      U2               CF16     SOCKET4677_AZIFS054P001C01-SOCA
GND                      U2               CF20     SOCKET4677_AZIFS054P001C01-SOCA
GND                      U2               CF69     SOCKET4677_AZIFS054P001C01-SOCA
GND                      U2               CF71     SOCKET4677_AZIFS054P001C01-SOCA
GND                      U2               CG1      SOCKET4677_AZIFS054P001C01-SOCA
GND                      U2               CG5      SOCKET4677_AZIFS054P001C01-SOCA
GND                      U2               CG9      SOCKET4677_AZIFS054P001C01-SOCA
GND                      U2               CG13     SOCKET4677_AZIFS054P001C01-SOCA
GND                      U2               CG17     SOCKET4677_AZIFS054P001C01-SOCA
GND                      U2               CG21     SOCKET4677_AZIFS054P001C01-SOCA
GND                      U2               CG23     SOCKET4677_AZIFS054P001C01-SOCA
GND                      U2               CG25     SOCKET4677_AZIFS054P001C01-SOCA
GND                      U2               CG62     SOCKET4677_AZIFS054P001C01-SOCA
GND                      U2               CG64     SOCKET4677_AZIFS054P001C01-SOCA
GND                      U2               CG70     SOCKET4677_AZIFS054P001C01-SOCA
GND                      U2               CG72     SOCKET4677_AZIFS054P001C01-SOCA
GND                      U2               CG74     SOCKET4677_AZIFS054P001C01-SOCA
GND                      U2               CG78     SOCKET4677_AZIFS054P001C01-SOCA
GND                      U2               CH4      SOCKET4677_AZIFS054P001C01-SOCA
GND                      U2               CH8      SOCKET4677_AZIFS054P001C01-SOCA
GND                      U2               CH12     SOCKET4677_AZIFS054P001C01-SOCA
GND                      U2               CH16     SOCKET4677_AZIFS054P001C01-SOCA
GND                      U2               CH20     SOCKET4677_AZIFS054P001C01-SOCA
GND                      U2               CH67     SOCKET4677_AZIFS054P001C01-SOCA
GND                      U2               CH73     SOCKET4677_AZIFS054P001C01-SOCA
GND                      U2               CH79     SOCKET4677_AZIFS054P001C01-SOCA
GND                      U2               CH83     SOCKET4677_AZIFS054P001C01-SOCA
GND                      U2               CH85     SOCKET4677_AZIFS054P001C01-SOCA
GND                      U2               CH87     SOCKET4677_AZIFS054P001C01-SOCA
GND                      U2               CH89     SOCKET4677_AZIFS054P001C01-SOCA
GND                      U2               CJ60     SOCKET4677_AZIFS054P001C01-SOCA
GND                      U2               CJ76     SOCKET4677_AZIFS054P001C01-SOCA
GND                      U2               CJ80     SOCKET4677_AZIFS054P001C01-SOCA
GND                      U2               CK4      SOCKET4677_AZIFS054P001C01-SOCA
GND                      U2               CK8      SOCKET4677_AZIFS054P001C01-SOCA
GND                      U2               CK12     SOCKET4677_AZIFS054P001C01-SOCA
GND                      U2               CK16     SOCKET4677_AZIFS054P001C01-SOCA
GND                      U2               CK20     SOCKET4677_AZIFS054P001C01-SOCA
GND                      U2               CK26     SOCKET4677_AZIFS054P001C01-SOCA
GND                      U2               CK63     SOCKET4677_AZIFS054P001C01-SOCA
GND                      U2               CK69     SOCKET4677_AZIFS054P001C01-SOCA
GND                      U2               CK81     SOCKET4677_AZIFS054P001C01-SOCA
GND                      U2               CL1      SOCKET4677_AZIFS054P001C01-SOCA
GND                      U2               CL5      SOCKET4677_AZIFS054P001C01-SOCA
GND                      U2               CL9      SOCKET4677_AZIFS054P001C01-SOCA
GND                      U2               CL13     SOCKET4677_AZIFS054P001C01-SOCA
GND                      U2               CL17     SOCKET4677_AZIFS054P001C01-SOCA
GND                      U2               CL62     SOCKET4677_AZIFS054P001C01-SOCA
GND                      U2               CL74     SOCKET4677_AZIFS054P001C01-SOCA
GND                      U2               CL78     SOCKET4677_AZIFS054P001C01-SOCA
GND                      U2               CL80     SOCKET4677_AZIFS054P001C01-SOCA
GND                      U2               CL82     SOCKET4677_AZIFS054P001C01-SOCA
GND                      U2               CM4      SOCKET4677_AZIFS054P001C01-SOCA
GND                      U2               CM8      SOCKET4677_AZIFS054P001C01-SOCA
GND                      U2               CM12     SOCKET4677_AZIFS054P001C01-SOCA
GND                      U2               CM16     SOCKET4677_AZIFS054P001C01-SOCA
GND                      U2               CM20     SOCKET4677_AZIFS054P001C01-SOCA
GND                      U2               CM22     SOCKET4677_AZIFS054P001C01-SOCA
GND                      U2               CM24     SOCKET4677_AZIFS054P001C01-SOCA
GND                      U2               CM61     SOCKET4677_AZIFS054P001C01-SOCA
GND                      U2               CM65     SOCKET4677_AZIFS054P001C01-SOCA
GND                      U2               CM67     SOCKET4677_AZIFS054P001C01-SOCA
GND                      U2               CM79     SOCKET4677_AZIFS054P001C01-SOCA
GND                      U2               CM81     SOCKET4677_AZIFS054P001C01-SOCA
GND                      U2               CM83     SOCKET4677_AZIFS054P001C01-SOCA
GND                      U2               CM85     SOCKET4677_AZIFS054P001C01-SOCA
GND                      U2               CN68     SOCKET4677_AZIFS054P001C01-SOCA
GND                      U2               CN70     SOCKET4677_AZIFS054P001C01-SOCA
GND                      U2               CN72     SOCKET4677_AZIFS054P001C01-SOCA
GND                      U2               CN74     SOCKET4677_AZIFS054P001C01-SOCA
GND                      U2               CN76     SOCKET4677_AZIFS054P001C01-SOCA
GND                      U2               CN84     SOCKET4677_AZIFS054P001C01-SOCA
GND                      U2               CN86     SOCKET4677_AZIFS054P001C01-SOCA
GND                      U2               CP4      SOCKET4677_AZIFS054P001C01-SOCA
GND                      U2               CP8      SOCKET4677_AZIFS054P001C01-SOCA
GND                      U2               CP12     SOCKET4677_AZIFS054P001C01-SOCA
GND                      U2               CP16     SOCKET4677_AZIFS054P001C01-SOCA
GND                      U2               CP18     SOCKET4677_AZIFS054P001C01-SOCA
GND                      U2               CP75     SOCKET4677_AZIFS054P001C01-SOCA
GND                      U2               CP77     SOCKET4677_AZIFS054P001C01-SOCA
GND                      U2               CP79     SOCKET4677_AZIFS054P001C01-SOCA
GND                      U2               CP83     SOCKET4677_AZIFS054P001C01-SOCA
GND                      U2               CP87     SOCKET4677_AZIFS054P001C01-SOCA
GND                      U2               CP91     SOCKET4677_AZIFS054P001C01-SOCA
GND                      U2               CR1      SOCKET4677_AZIFS054P001C01-SOCA
GND                      U2               CR5      SOCKET4677_AZIFS054P001C01-SOCA
GND                      U2               CR9      SOCKET4677_AZIFS054P001C01-SOCA
GND                      U2               CR11     SOCKET4677_AZIFS054P001C01-SOCA
GND                      U2               CR13     SOCKET4677_AZIFS054P001C01-SOCA
GND                      U2               CR17     SOCKET4677_AZIFS054P001C01-SOCA
GND                      U2               CR62     SOCKET4677_AZIFS054P001C01-SOCA
GND                      U2               CR64     SOCKET4677_AZIFS054P001C01-SOCA
GND                      U2               CR78     SOCKET4677_AZIFS054P001C01-SOCA
GND                      U2               CR84     SOCKET4677_AZIFS054P001C01-SOCA
GND                      U2               CR88     SOCKET4677_AZIFS054P001C01-SOCA
GND                      U2               CR90     SOCKET4677_AZIFS054P001C01-SOCA
GND                      U2               CT4      SOCKET4677_AZIFS054P001C01-SOCA
GND                      U2               CT8      SOCKET4677_AZIFS054P001C01-SOCA
GND                      U2               CT10     SOCKET4677_AZIFS054P001C01-SOCA
GND                      U2               CT12     SOCKET4677_AZIFS054P001C01-SOCA
GND                      U2               CT16     SOCKET4677_AZIFS054P001C01-SOCA
GND                      U2               CT69     SOCKET4677_AZIFS054P001C01-SOCA
GND                      U2               CT73     SOCKET4677_AZIFS054P001C01-SOCA
GND                      U2               CT81     SOCKET4677_AZIFS054P001C01-SOCA
GND                      U2               CT89     SOCKET4677_AZIFS054P001C01-SOCA
GND                      U2               CU19     SOCKET4677_AZIFS054P001C01-SOCA
GND                      U2               CU21     SOCKET4677_AZIFS054P001C01-SOCA
GND                      U2               CU23     SOCKET4677_AZIFS054P001C01-SOCA
GND                      U2               CU25     SOCKET4677_AZIFS054P001C01-SOCA
GND                      U2               CU60     SOCKET4677_AZIFS054P001C01-SOCA
GND                      U2               CU66     SOCKET4677_AZIFS054P001C01-SOCA
GND                      U2               CU68     SOCKET4677_AZIFS054P001C01-SOCA
GND                      U2               CU72     SOCKET4677_AZIFS054P001C01-SOCA
GND                      U2               CU78     SOCKET4677_AZIFS054P001C01-SOCA
GND                      U2               CU84     SOCKET4677_AZIFS054P001C01-SOCA
GND                      U2               CU88     SOCKET4677_AZIFS054P001C01-SOCA
GND                      U2               CV4      SOCKET4677_AZIFS054P001C01-SOCA
GND                      U2               CV8      SOCKET4677_AZIFS054P001C01-SOCA
GND                      U2               CV12     SOCKET4677_AZIFS054P001C01-SOCA
GND                      U2               CV16     SOCKET4677_AZIFS054P001C01-SOCA
GND                      U2               CV26     SOCKET4677_AZIFS054P001C01-SOCA
GND                      U2               CV75     SOCKET4677_AZIFS054P001C01-SOCA
GND                      U2               CV79     SOCKET4677_AZIFS054P001C01-SOCA
GND                      U2               CV83     SOCKET4677_AZIFS054P001C01-SOCA
GND                      U2               CV87     SOCKET4677_AZIFS054P001C01-SOCA
GND                      U2               CV91     SOCKET4677_AZIFS054P001C01-SOCA
GND                      U2               CW1      SOCKET4677_AZIFS054P001C01-SOCA
GND                      U2               CW5      SOCKET4677_AZIFS054P001C01-SOCA
GND                      U2               CW9      SOCKET4677_AZIFS054P001C01-SOCA
GND                      U2               CW13     SOCKET4677_AZIFS054P001C01-SOCA
GND                      U2               CW17     SOCKET4677_AZIFS054P001C01-SOCA
GND                      U2               CW33     SOCKET4677_AZIFS054P001C01-SOCA
GND                      U2               CW70     SOCKET4677_AZIFS054P001C01-SOCA
GND                      U2               CW72     SOCKET4677_AZIFS054P001C01-SOCA
GND                      U2               CW78     SOCKET4677_AZIFS054P001C01-SOCA
GND                      U2               CW84     SOCKET4677_AZIFS054P001C01-SOCA
GND                      U2               CW88     SOCKET4677_AZIFS054P001C01-SOCA
GND                      U2               CY4      SOCKET4677_AZIFS054P001C01-SOCA
GND                      U2               CY8      SOCKET4677_AZIFS054P001C01-SOCA
GND                      U2               CY12     SOCKET4677_AZIFS054P001C01-SOCA
GND                      U2               CY16     SOCKET4677_AZIFS054P001C01-SOCA
GND                      U2               CY18     SOCKET4677_AZIFS054P001C01-SOCA
GND                      U2               CY26     SOCKET4677_AZIFS054P001C01-SOCA
GND                      U2               CY30     SOCKET4677_AZIFS054P001C01-SOCA
GND                      U2               CY63     SOCKET4677_AZIFS054P001C01-SOCA
GND                      U2               CY73     SOCKET4677_AZIFS054P001C01-SOCA
GND                      U2               CY77     SOCKET4677_AZIFS054P001C01-SOCA
GND                      U2               CY81     SOCKET4677_AZIFS054P001C01-SOCA
GND                      U2               CY83     SOCKET4677_AZIFS054P001C01-SOCA
GND                      U2               D6       SOCKET4677_AZIFS054P001C01-SOCA
GND                      U2               D8       SOCKET4677_AZIFS054P001C01-SOCA
GND                      U2               D10      SOCKET4677_AZIFS054P001C01-SOCA
GND                      U2               D12      SOCKET4677_AZIFS054P001C01-SOCA
GND                      U2               D14      SOCKET4677_AZIFS054P001C01-SOCA
GND                      U2               D16      SOCKET4677_AZIFS054P001C01-SOCA
GND                      U2               D18      SOCKET4677_AZIFS054P001C01-SOCA
GND                      U2               D20      SOCKET4677_AZIFS054P001C01-SOCA
GND                      U2               D22      SOCKET4677_AZIFS054P001C01-SOCA
GND                      U2               D24      SOCKET4677_AZIFS054P001C01-SOCA
GND                      U2               D26      SOCKET4677_AZIFS054P001C01-SOCA
GND                      U2               D28      SOCKET4677_AZIFS054P001C01-SOCA
GND                      U2               D30      SOCKET4677_AZIFS054P001C01-SOCA
GND                      U2               D32      SOCKET4677_AZIFS054P001C01-SOCA
GND                      U2               D34      SOCKET4677_AZIFS054P001C01-SOCA
GND                      U2               D36      SOCKET4677_AZIFS054P001C01-SOCA
GND                      U2               D38      SOCKET4677_AZIFS054P001C01-SOCA
GND                      U2               D40      SOCKET4677_AZIFS054P001C01-SOCA
GND                      U2               D42      SOCKET4677_AZIFS054P001C01-SOCA
GND                      U2               D44      SOCKET4677_AZIFS054P001C01-SOCA
GND                      U2               D47      SOCKET4677_AZIFS054P001C01-SOCA
GND                      U2               D49      SOCKET4677_AZIFS054P001C01-SOCA
GND                      U2               D51      SOCKET4677_AZIFS054P001C01-SOCA
GND                      U2               D53      SOCKET4677_AZIFS054P001C01-SOCA
GND                      U2               D55      SOCKET4677_AZIFS054P001C01-SOCA
GND                      U2               D57      SOCKET4677_AZIFS054P001C01-SOCA
GND                      U2               D59      SOCKET4677_AZIFS054P001C01-SOCA
GND                      U2               D61      SOCKET4677_AZIFS054P001C01-SOCA
GND                      U2               D63      SOCKET4677_AZIFS054P001C01-SOCA
GND                      U2               D65      SOCKET4677_AZIFS054P001C01-SOCA
GND                      U2               D67      SOCKET4677_AZIFS054P001C01-SOCA
GND                      U2               D69      SOCKET4677_AZIFS054P001C01-SOCA
GND                      U2               D71      SOCKET4677_AZIFS054P001C01-SOCA
GND                      U2               D79      SOCKET4677_AZIFS054P001C01-SOCA
GND                      U2               D81      SOCKET4677_AZIFS054P001C01-SOCA
GND                      U2               D83      SOCKET4677_AZIFS054P001C01-SOCA
GND                      U2               DA19     SOCKET4677_AZIFS054P001C01-SOCA
GND                      U2               DA23     SOCKET4677_AZIFS054P001C01-SOCA
GND                      U2               DA25     SOCKET4677_AZIFS054P001C01-SOCA
GND                      U2               DA29     SOCKET4677_AZIFS054P001C01-SOCA
GND                      U2               DA31     SOCKET4677_AZIFS054P001C01-SOCA
GND                      U2               DA33     SOCKET4677_AZIFS054P001C01-SOCA
GND                      U2               DA35     SOCKET4677_AZIFS054P001C01-SOCA
GND                      U2               DA37     SOCKET4677_AZIFS054P001C01-SOCA
GND                      U2               DA41     SOCKET4677_AZIFS054P001C01-SOCA
GND                      U2               DA43     SOCKET4677_AZIFS054P001C01-SOCA
GND                      U2               DA48     SOCKET4677_AZIFS054P001C01-SOCA
GND                      U2               DA50     SOCKET4677_AZIFS054P001C01-SOCA
GND                      U2               DA54     SOCKET4677_AZIFS054P001C01-SOCA
GND                      U2               DA56     SOCKET4677_AZIFS054P001C01-SOCA
GND                      U2               DA58     SOCKET4677_AZIFS054P001C01-SOCA
GND                      U2               DA60     SOCKET4677_AZIFS054P001C01-SOCA
GND                      U2               DA62     SOCKET4677_AZIFS054P001C01-SOCA
GND                      U2               DA66     SOCKET4677_AZIFS054P001C01-SOCA
GND                      U2               DA68     SOCKET4677_AZIFS054P001C01-SOCA
GND                      U2               DA72     SOCKET4677_AZIFS054P001C01-SOCA
GND                      U2               DA74     SOCKET4677_AZIFS054P001C01-SOCA
GND                      U2               DA80     SOCKET4677_AZIFS054P001C01-SOCA
GND                      U2               DA82     SOCKET4677_AZIFS054P001C01-SOCA
GND                      U2               DA84     SOCKET4677_AZIFS054P001C01-SOCA
GND                      U2               DA88     SOCKET4677_AZIFS054P001C01-SOCA
GND                      U2               DB4      SOCKET4677_AZIFS054P001C01-SOCA
GND                      U2               DB8      SOCKET4677_AZIFS054P001C01-SOCA
GND                      U2               DB12     SOCKET4677_AZIFS054P001C01-SOCA
GND                      U2               DB16     SOCKET4677_AZIFS054P001C01-SOCA
GND                      U2               DB20     SOCKET4677_AZIFS054P001C01-SOCA
GND                      U2               DB22     SOCKET4677_AZIFS054P001C01-SOCA
GND                      U2               DB26     SOCKET4677_AZIFS054P001C01-SOCA
GND                      U2               DB28     SOCKET4677_AZIFS054P001C01-SOCA
GND                      U2               DB32     SOCKET4677_AZIFS054P001C01-SOCA
GND                      U2               DB34     SOCKET4677_AZIFS054P001C01-SOCA
GND                      U2               DB38     SOCKET4677_AZIFS054P001C01-SOCA
GND                      U2               DB40     SOCKET4677_AZIFS054P001C01-SOCA
GND                      U2               DB44     SOCKET4677_AZIFS054P001C01-SOCA
GND                      U2               DB47     SOCKET4677_AZIFS054P001C01-SOCA
GND                      U2               DB51     SOCKET4677_AZIFS054P001C01-SOCA
GND                      U2               DB53     SOCKET4677_AZIFS054P001C01-SOCA
GND                      U2               DB57     SOCKET4677_AZIFS054P001C01-SOCA
GND                      U2               DB59     SOCKET4677_AZIFS054P001C01-SOCA
GND                      U2               DB63     SOCKET4677_AZIFS054P001C01-SOCA
GND                      U2               DB65     SOCKET4677_AZIFS054P001C01-SOCA
GND                      U2               DB69     SOCKET4677_AZIFS054P001C01-SOCA
GND                      U2               DB71     SOCKET4677_AZIFS054P001C01-SOCA
GND                      U2               DB75     SOCKET4677_AZIFS054P001C01-SOCA
GND                      U2               DB77     SOCKET4677_AZIFS054P001C01-SOCA
GND                      U2               DB87     SOCKET4677_AZIFS054P001C01-SOCA
GND                      U2               DB91     SOCKET4677_AZIFS054P001C01-SOCA
GND                      U2               DC1      SOCKET4677_AZIFS054P001C01-SOCA
GND                      U2               DC5      SOCKET4677_AZIFS054P001C01-SOCA
GND                      U2               DC9      SOCKET4677_AZIFS054P001C01-SOCA
GND                      U2               DC13     SOCKET4677_AZIFS054P001C01-SOCA
GND                      U2               DC21     SOCKET4677_AZIFS054P001C01-SOCA
GND                      U2               DC27     SOCKET4677_AZIFS054P001C01-SOCA
GND                      U2               DC33     SOCKET4677_AZIFS054P001C01-SOCA
GND                      U2               DC39     SOCKET4677_AZIFS054P001C01-SOCA
GND                      U2               DC45     SOCKET4677_AZIFS054P001C01-SOCA
GND                      U2               DC52     SOCKET4677_AZIFS054P001C01-SOCA
GND                      U2               DC58     SOCKET4677_AZIFS054P001C01-SOCA
GND                      U2               DC64     SOCKET4677_AZIFS054P001C01-SOCA
GND                      U2               DC70     SOCKET4677_AZIFS054P001C01-SOCA
GND                      U2               DC76     SOCKET4677_AZIFS054P001C01-SOCA
GND                      U2               DC78     SOCKET4677_AZIFS054P001C01-SOCA
GND                      U2               DC80     SOCKET4677_AZIFS054P001C01-SOCA
GND                      U2               DC84     SOCKET4677_AZIFS054P001C01-SOCA
GND                      U2               DC88     SOCKET4677_AZIFS054P001C01-SOCA
GND                      U2               DD4      SOCKET4677_AZIFS054P001C01-SOCA
GND                      U2               DD8      SOCKET4677_AZIFS054P001C01-SOCA
GND                      U2               DD12     SOCKET4677_AZIFS054P001C01-SOCA
GND                      U2               DD16     SOCKET4677_AZIFS054P001C01-SOCA
GND                      U2               DD49     SOCKET4677_AZIFS054P001C01-SOCA
GND                      U2               DD79     SOCKET4677_AZIFS054P001C01-SOCA
GND                      U2               DE17     SOCKET4677_AZIFS054P001C01-SOCA
GND                      U2               DE19     SOCKET4677_AZIFS054P001C01-SOCA
GND                      U2               DE21     SOCKET4677_AZIFS054P001C01-SOCA
GND                      U2               DE23     SOCKET4677_AZIFS054P001C01-SOCA
GND                      U2               DE25     SOCKET4677_AZIFS054P001C01-SOCA
GND                      U2               DE27     SOCKET4677_AZIFS054P001C01-SOCA
GND                      U2               DE29     SOCKET4677_AZIFS054P001C01-SOCA
GND                      U2               DE31     SOCKET4677_AZIFS054P001C01-SOCA
GND                      U2               DE33     SOCKET4677_AZIFS054P001C01-SOCA
GND                      U2               DE35     SOCKET4677_AZIFS054P001C01-SOCA
GND                      U2               DE37     SOCKET4677_AZIFS054P001C01-SOCA
GND                      U2               DE39     SOCKET4677_AZIFS054P001C01-SOCA
GND                      U2               DE41     SOCKET4677_AZIFS054P001C01-SOCA
GND                      U2               DE43     SOCKET4677_AZIFS054P001C01-SOCA
GND                      U2               DE45     SOCKET4677_AZIFS054P001C01-SOCA
GND                      U2               DE48     SOCKET4677_AZIFS054P001C01-SOCA
GND                      U2               DE50     SOCKET4677_AZIFS054P001C01-SOCA
GND                      U2               DE52     SOCKET4677_AZIFS054P001C01-SOCA
GND                      U2               DE54     SOCKET4677_AZIFS054P001C01-SOCA
GND                      U2               DE56     SOCKET4677_AZIFS054P001C01-SOCA
GND                      U2               DE58     SOCKET4677_AZIFS054P001C01-SOCA
GND                      U2               DE60     SOCKET4677_AZIFS054P001C01-SOCA
GND                      U2               DE62     SOCKET4677_AZIFS054P001C01-SOCA
GND                      U2               DE64     SOCKET4677_AZIFS054P001C01-SOCA
GND                      U2               DE66     SOCKET4677_AZIFS054P001C01-SOCA
GND                      U2               DE68     SOCKET4677_AZIFS054P001C01-SOCA
GND                      U2               DE70     SOCKET4677_AZIFS054P001C01-SOCA
GND                      U2               DE72     SOCKET4677_AZIFS054P001C01-SOCA
GND                      U2               DE74     SOCKET4677_AZIFS054P001C01-SOCA
GND                      U2               DE76     SOCKET4677_AZIFS054P001C01-SOCA
GND                      U2               DE82     SOCKET4677_AZIFS054P001C01-SOCA
GND                      U2               DE84     SOCKET4677_AZIFS054P001C01-SOCA
GND                      U2               DE88     SOCKET4677_AZIFS054P001C01-SOCA
GND                      U2               DF4      SOCKET4677_AZIFS054P001C01-SOCA
GND                      U2               DF8      SOCKET4677_AZIFS054P001C01-SOCA
GND                      U2               DF12     SOCKET4677_AZIFS054P001C01-SOCA
GND                      U2               DF16     SOCKET4677_AZIFS054P001C01-SOCA
GND                      U2               DF49     SOCKET4677_AZIFS054P001C01-SOCA
GND                      U2               DF79     SOCKET4677_AZIFS054P001C01-SOCA
GND                      U2               DF87     SOCKET4677_AZIFS054P001C01-SOCA
GND                      U2               DF91     SOCKET4677_AZIFS054P001C01-SOCA
GND                      U2               DG1      SOCKET4677_AZIFS054P001C01-SOCA
GND                      U2               DG5      SOCKET4677_AZIFS054P001C01-SOCA
GND                      U2               DG9      SOCKET4677_AZIFS054P001C01-SOCA
GND                      U2               DG13     SOCKET4677_AZIFS054P001C01-SOCA
GND                      U2               DG21     SOCKET4677_AZIFS054P001C01-SOCA
GND                      U2               DG27     SOCKET4677_AZIFS054P001C01-SOCA
GND                      U2               DG33     SOCKET4677_AZIFS054P001C01-SOCA
GND                      U2               DG39     SOCKET4677_AZIFS054P001C01-SOCA
GND                      U2               DG45     SOCKET4677_AZIFS054P001C01-SOCA
GND                      U2               DG52     SOCKET4677_AZIFS054P001C01-SOCA
GND                      U2               DG58     SOCKET4677_AZIFS054P001C01-SOCA
GND                      U2               DG64     SOCKET4677_AZIFS054P001C01-SOCA
GND                      U2               DG70     SOCKET4677_AZIFS054P001C01-SOCA
GND                      U2               DG76     SOCKET4677_AZIFS054P001C01-SOCA
GND                      U2               DG80     SOCKET4677_AZIFS054P001C01-SOCA
GND                      U2               DG84     SOCKET4677_AZIFS054P001C01-SOCA
GND                      U2               DG88     SOCKET4677_AZIFS054P001C01-SOCA
GND                      U2               DH4      SOCKET4677_AZIFS054P001C01-SOCA
GND                      U2               DH8      SOCKET4677_AZIFS054P001C01-SOCA
GND                      U2               DH12     SOCKET4677_AZIFS054P001C01-SOCA
GND                      U2               DH16     SOCKET4677_AZIFS054P001C01-SOCA
GND                      U2               DH20     SOCKET4677_AZIFS054P001C01-SOCA
GND                      U2               DH22     SOCKET4677_AZIFS054P001C01-SOCA
GND                      U2               DH26     SOCKET4677_AZIFS054P001C01-SOCA
GND                      U2               DH28     SOCKET4677_AZIFS054P001C01-SOCA
GND                      U2               DH32     SOCKET4677_AZIFS054P001C01-SOCA
GND                      U2               DH34     SOCKET4677_AZIFS054P001C01-SOCA
GND                      U2               DH38     SOCKET4677_AZIFS054P001C01-SOCA
GND                      U2               DH40     SOCKET4677_AZIFS054P001C01-SOCA
GND                      U2               DH44     SOCKET4677_AZIFS054P001C01-SOCA
GND                      U2               DH47     SOCKET4677_AZIFS054P001C01-SOCA
GND                      U2               DH51     SOCKET4677_AZIFS054P001C01-SOCA
GND                      U2               DH53     SOCKET4677_AZIFS054P001C01-SOCA
GND                      U2               DH57     SOCKET4677_AZIFS054P001C01-SOCA
GND                      U2               DH59     SOCKET4677_AZIFS054P001C01-SOCA
GND                      U2               DH63     SOCKET4677_AZIFS054P001C01-SOCA
GND                      U2               DH65     SOCKET4677_AZIFS054P001C01-SOCA
GND                      U2               DH69     SOCKET4677_AZIFS054P001C01-SOCA
GND                      U2               DH71     SOCKET4677_AZIFS054P001C01-SOCA
GND                      U2               DH75     SOCKET4677_AZIFS054P001C01-SOCA
GND                      U2               DH77     SOCKET4677_AZIFS054P001C01-SOCA
GND                      U2               DH85     SOCKET4677_AZIFS054P001C01-SOCA
GND                      U2               DJ19     SOCKET4677_AZIFS054P001C01-SOCA
GND                      U2               DJ23     SOCKET4677_AZIFS054P001C01-SOCA
GND                      U2               DJ25     SOCKET4677_AZIFS054P001C01-SOCA
GND                      U2               DJ29     SOCKET4677_AZIFS054P001C01-SOCA
GND                      U2               DJ31     SOCKET4677_AZIFS054P001C01-SOCA
GND                      U2               DJ35     SOCKET4677_AZIFS054P001C01-SOCA
GND                      U2               DJ37     SOCKET4677_AZIFS054P001C01-SOCA
GND                      U2               DJ41     SOCKET4677_AZIFS054P001C01-SOCA
GND                      U2               DJ43     SOCKET4677_AZIFS054P001C01-SOCA
GND                      U2               DJ48     SOCKET4677_AZIFS054P001C01-SOCA
GND                      U2               DJ50     SOCKET4677_AZIFS054P001C01-SOCA
GND                      U2               DJ54     SOCKET4677_AZIFS054P001C01-SOCA
GND                      U2               DJ56     SOCKET4677_AZIFS054P001C01-SOCA
GND                      U2               DJ60     SOCKET4677_AZIFS054P001C01-SOCA
GND                      U2               DJ62     SOCKET4677_AZIFS054P001C01-SOCA
GND                      U2               DJ66     SOCKET4677_AZIFS054P001C01-SOCA
GND                      U2               DJ68     SOCKET4677_AZIFS054P001C01-SOCA
GND                      U2               DJ72     SOCKET4677_AZIFS054P001C01-SOCA
GND                      U2               DJ74     SOCKET4677_AZIFS054P001C01-SOCA
GND                      U2               DJ80     SOCKET4677_AZIFS054P001C01-SOCA
GND                      U2               DJ82     SOCKET4677_AZIFS054P001C01-SOCA
GND                      U2               DJ84     SOCKET4677_AZIFS054P001C01-SOCA
GND                      U2               DJ88     SOCKET4677_AZIFS054P001C01-SOCA
GND                      U2               DK4      SOCKET4677_AZIFS054P001C01-SOCA
GND                      U2               DK8      SOCKET4677_AZIFS054P001C01-SOCA
GND                      U2               DK12     SOCKET4677_AZIFS054P001C01-SOCA
GND                      U2               DK16     SOCKET4677_AZIFS054P001C01-SOCA
GND                      U2               DK18     SOCKET4677_AZIFS054P001C01-SOCA
GND                      U2               DK24     SOCKET4677_AZIFS054P001C01-SOCA
GND                      U2               DK30     SOCKET4677_AZIFS054P001C01-SOCA
GND                      U2               DK36     SOCKET4677_AZIFS054P001C01-SOCA
GND                      U2               DK42     SOCKET4677_AZIFS054P001C01-SOCA
GND                      U2               DK49     SOCKET4677_AZIFS054P001C01-SOCA
GND                      U2               DK55     SOCKET4677_AZIFS054P001C01-SOCA
GND                      U2               DK61     SOCKET4677_AZIFS054P001C01-SOCA
GND                      U2               DK67     SOCKET4677_AZIFS054P001C01-SOCA
GND                      U2               DK73     SOCKET4677_AZIFS054P001C01-SOCA
GND                      U2               DK77     SOCKET4677_AZIFS054P001C01-SOCA
GND                      U2               DK79     SOCKET4677_AZIFS054P001C01-SOCA
GND                      U2               DK81     SOCKET4677_AZIFS054P001C01-SOCA
GND                      U2               DK83     SOCKET4677_AZIFS054P001C01-SOCA
GND                      U2               DK87     SOCKET4677_AZIFS054P001C01-SOCA
GND                      U2               DK91     SOCKET4677_AZIFS054P001C01-SOCA
GND                      U2               DL1      SOCKET4677_AZIFS054P001C01-SOCA
GND                      U2               DL5      SOCKET4677_AZIFS054P001C01-SOCA
GND                      U2               DL9      SOCKET4677_AZIFS054P001C01-SOCA
GND                      U2               DL13     SOCKET4677_AZIFS054P001C01-SOCA
GND                      U2               DL17     SOCKET4677_AZIFS054P001C01-SOCA
GND                      U2               DL39     SOCKET4677_AZIFS054P001C01-SOCA
GND                      U2               DL52     SOCKET4677_AZIFS054P001C01-SOCA
GND                      U2               DL84     SOCKET4677_AZIFS054P001C01-SOCA
GND                      U2               DL88     SOCKET4677_AZIFS054P001C01-SOCA
GND                      U2               DM4      SOCKET4677_AZIFS054P001C01-SOCA
GND                      U2               DM8      SOCKET4677_AZIFS054P001C01-SOCA
GND                      U2               DM12     SOCKET4677_AZIFS054P001C01-SOCA
GND                      U2               DM16     SOCKET4677_AZIFS054P001C01-SOCA
GND                      U2               DM18     SOCKET4677_AZIFS054P001C01-SOCA
GND                      U2               DM20     SOCKET4677_AZIFS054P001C01-SOCA
GND                      U2               DM22     SOCKET4677_AZIFS054P001C01-SOCA
GND                      U2               DM24     SOCKET4677_AZIFS054P001C01-SOCA
GND                      U2               DM26     SOCKET4677_AZIFS054P001C01-SOCA
GND                      U2               DM28     SOCKET4677_AZIFS054P001C01-SOCA
GND                      U2               DM30     SOCKET4677_AZIFS054P001C01-SOCA
GND                      U2               DM32     SOCKET4677_AZIFS054P001C01-SOCA
GND                      U2               DM34     SOCKET4677_AZIFS054P001C01-SOCA
GND                      U2               DM36     SOCKET4677_AZIFS054P001C01-SOCA
GND                      U2               DM38     SOCKET4677_AZIFS054P001C01-SOCA
GND                      U2               DM40     SOCKET4677_AZIFS054P001C01-SOCA
GND                      U2               DM42     SOCKET4677_AZIFS054P001C01-SOCA
GND                      U2               DM44     SOCKET4677_AZIFS054P001C01-SOCA
GND                      U2               DM47     SOCKET4677_AZIFS054P001C01-SOCA
GND                      U2               DM49     SOCKET4677_AZIFS054P001C01-SOCA
GND                      U2               DM51     SOCKET4677_AZIFS054P001C01-SOCA
GND                      U2               DM53     SOCKET4677_AZIFS054P001C01-SOCA
GND                      U2               DM55     SOCKET4677_AZIFS054P001C01-SOCA
GND                      U2               DM57     SOCKET4677_AZIFS054P001C01-SOCA
GND                      U2               DM59     SOCKET4677_AZIFS054P001C01-SOCA
GND                      U2               DM61     SOCKET4677_AZIFS054P001C01-SOCA
GND                      U2               DM63     SOCKET4677_AZIFS054P001C01-SOCA
GND                      U2               DM65     SOCKET4677_AZIFS054P001C01-SOCA
GND                      U2               DM67     SOCKET4677_AZIFS054P001C01-SOCA
GND                      U2               DM69     SOCKET4677_AZIFS054P001C01-SOCA
GND                      U2               DM71     SOCKET4677_AZIFS054P001C01-SOCA
GND                      U2               DM73     SOCKET4677_AZIFS054P001C01-SOCA
GND                      U2               DM75     SOCKET4677_AZIFS054P001C01-SOCA
GND                      U2               DM77     SOCKET4677_AZIFS054P001C01-SOCA
GND                      U2               DM79     SOCKET4677_AZIFS054P001C01-SOCA
GND                      U2               DN17     SOCKET4677_AZIFS054P001C01-SOCA
GND                      U2               DN39     SOCKET4677_AZIFS054P001C01-SOCA
GND                      U2               DN52     SOCKET4677_AZIFS054P001C01-SOCA
GND                      U2               DN78     SOCKET4677_AZIFS054P001C01-SOCA
GND                      U2               DN84     SOCKET4677_AZIFS054P001C01-SOCA
GND                      U2               DN88     SOCKET4677_AZIFS054P001C01-SOCA
GND                      U2               DP4      SOCKET4677_AZIFS054P001C01-SOCA
GND                      U2               DP8      SOCKET4677_AZIFS054P001C01-SOCA
GND                      U2               DP12     SOCKET4677_AZIFS054P001C01-SOCA
GND                      U2               DP16     SOCKET4677_AZIFS054P001C01-SOCA
GND                      U2               DP18     SOCKET4677_AZIFS054P001C01-SOCA
GND                      U2               DP24     SOCKET4677_AZIFS054P001C01-SOCA
GND                      U2               DP30     SOCKET4677_AZIFS054P001C01-SOCA
GND                      U2               DP36     SOCKET4677_AZIFS054P001C01-SOCA
GND                      U2               DP42     SOCKET4677_AZIFS054P001C01-SOCA
GND                      U2               DP49     SOCKET4677_AZIFS054P001C01-SOCA
GND                      U2               DP55     SOCKET4677_AZIFS054P001C01-SOCA
GND                      U2               DP61     SOCKET4677_AZIFS054P001C01-SOCA
GND                      U2               DP67     SOCKET4677_AZIFS054P001C01-SOCA
GND                      U2               DP73     SOCKET4677_AZIFS054P001C01-SOCA
GND                      U2               DP81     SOCKET4677_AZIFS054P001C01-SOCA
GND                      U2               DP87     SOCKET4677_AZIFS054P001C01-SOCA
GND                      U2               DP91     SOCKET4677_AZIFS054P001C01-SOCA
GND                      U2               DR1      SOCKET4677_AZIFS054P001C01-SOCA
GND                      U2               DR5      SOCKET4677_AZIFS054P001C01-SOCA
GND                      U2               DR9      SOCKET4677_AZIFS054P001C01-SOCA
GND                      U2               DR13     SOCKET4677_AZIFS054P001C01-SOCA
GND                      U2               DR19     SOCKET4677_AZIFS054P001C01-SOCA
GND                      U2               DR23     SOCKET4677_AZIFS054P001C01-SOCA
GND                      U2               DR25     SOCKET4677_AZIFS054P001C01-SOCA
GND                      U2               DR29     SOCKET4677_AZIFS054P001C01-SOCA
GND                      U2               DR31     SOCKET4677_AZIFS054P001C01-SOCA
GND                      U2               DR35     SOCKET4677_AZIFS054P001C01-SOCA
GND                      U2               DR37     SOCKET4677_AZIFS054P001C01-SOCA
GND                      U2               DR41     SOCKET4677_AZIFS054P001C01-SOCA
GND                      U2               DR43     SOCKET4677_AZIFS054P001C01-SOCA
GND                      U2               DR48     SOCKET4677_AZIFS054P001C01-SOCA
GND                      U2               DR50     SOCKET4677_AZIFS054P001C01-SOCA
GND                      U2               DR54     SOCKET4677_AZIFS054P001C01-SOCA
GND                      U2               DR56     SOCKET4677_AZIFS054P001C01-SOCA
GND                      U2               DR60     SOCKET4677_AZIFS054P001C01-SOCA
GND                      U2               DR62     SOCKET4677_AZIFS054P001C01-SOCA
GND                      U2               DR66     SOCKET4677_AZIFS054P001C01-SOCA
GND                      U2               DR68     SOCKET4677_AZIFS054P001C01-SOCA
GND                      U2               DR72     SOCKET4677_AZIFS054P001C01-SOCA
GND                      U2               DR74     SOCKET4677_AZIFS054P001C01-SOCA
GND                      U2               DR78     SOCKET4677_AZIFS054P001C01-SOCA
GND                      U2               DR84     SOCKET4677_AZIFS054P001C01-SOCA
GND                      U2               DR88     SOCKET4677_AZIFS054P001C01-SOCA
GND                      U2               DT4      SOCKET4677_AZIFS054P001C01-SOCA
GND                      U2               DT8      SOCKET4677_AZIFS054P001C01-SOCA
GND                      U2               DT12     SOCKET4677_AZIFS054P001C01-SOCA
GND                      U2               DT16     SOCKET4677_AZIFS054P001C01-SOCA
GND                      U2               DT20     SOCKET4677_AZIFS054P001C01-SOCA
GND                      U2               DT22     SOCKET4677_AZIFS054P001C01-SOCA
GND                      U2               DT26     SOCKET4677_AZIFS054P001C01-SOCA
GND                      U2               DT28     SOCKET4677_AZIFS054P001C01-SOCA
GND                      U2               DT32     SOCKET4677_AZIFS054P001C01-SOCA
GND                      U2               DT34     SOCKET4677_AZIFS054P001C01-SOCA
GND                      U2               DT38     SOCKET4677_AZIFS054P001C01-SOCA
GND                      U2               DT40     SOCKET4677_AZIFS054P001C01-SOCA
GND                      U2               DT44     SOCKET4677_AZIFS054P001C01-SOCA
GND                      U2               DT47     SOCKET4677_AZIFS054P001C01-SOCA
GND                      U2               DT51     SOCKET4677_AZIFS054P001C01-SOCA
GND                      U2               DT53     SOCKET4677_AZIFS054P001C01-SOCA
GND                      U2               DT57     SOCKET4677_AZIFS054P001C01-SOCA
GND                      U2               DT59     SOCKET4677_AZIFS054P001C01-SOCA
GND                      U2               DT63     SOCKET4677_AZIFS054P001C01-SOCA
GND                      U2               DT65     SOCKET4677_AZIFS054P001C01-SOCA
GND                      U2               DT69     SOCKET4677_AZIFS054P001C01-SOCA
GND                      U2               DT71     SOCKET4677_AZIFS054P001C01-SOCA
GND                      U2               DT75     SOCKET4677_AZIFS054P001C01-SOCA
GND                      U2               DT83     SOCKET4677_AZIFS054P001C01-SOCA
GND                      U2               DU21     SOCKET4677_AZIFS054P001C01-SOCA
GND                      U2               DU27     SOCKET4677_AZIFS054P001C01-SOCA
GND                      U2               DU33     SOCKET4677_AZIFS054P001C01-SOCA
GND                      U2               DU39     SOCKET4677_AZIFS054P001C01-SOCA
GND                      U2               DU45     SOCKET4677_AZIFS054P001C01-SOCA
GND                      U2               DU52     SOCKET4677_AZIFS054P001C01-SOCA
GND                      U2               DU58     SOCKET4677_AZIFS054P001C01-SOCA
GND                      U2               DU64     SOCKET4677_AZIFS054P001C01-SOCA
GND                      U2               DU70     SOCKET4677_AZIFS054P001C01-SOCA
GND                      U2               DU76     SOCKET4677_AZIFS054P001C01-SOCA
GND                      U2               DU78     SOCKET4677_AZIFS054P001C01-SOCA
GND                      U2               DU84     SOCKET4677_AZIFS054P001C01-SOCA
GND                      U2               DU88     SOCKET4677_AZIFS054P001C01-SOCA
GND                      U2               DV4      SOCKET4677_AZIFS054P001C01-SOCA
GND                      U2               DV8      SOCKET4677_AZIFS054P001C01-SOCA
GND                      U2               DV12     SOCKET4677_AZIFS054P001C01-SOCA
GND                      U2               DV16     SOCKET4677_AZIFS054P001C01-SOCA
GND                      U2               DV42     SOCKET4677_AZIFS054P001C01-SOCA
GND                      U2               DV77     SOCKET4677_AZIFS054P001C01-SOCA
GND                      U2               DV79     SOCKET4677_AZIFS054P001C01-SOCA
GND                      U2               DV81     SOCKET4677_AZIFS054P001C01-SOCA
GND                      U2               DV83     SOCKET4677_AZIFS054P001C01-SOCA
GND                      U2               DV87     SOCKET4677_AZIFS054P001C01-SOCA
GND                      U2               DV91     SOCKET4677_AZIFS054P001C01-SOCA
GND                      U2               DW1      SOCKET4677_AZIFS054P001C01-SOCA
GND                      U2               DW5      SOCKET4677_AZIFS054P001C01-SOCA
GND                      U2               DW9      SOCKET4677_AZIFS054P001C01-SOCA
GND                      U2               DW13     SOCKET4677_AZIFS054P001C01-SOCA
GND                      U2               DW17     SOCKET4677_AZIFS054P001C01-SOCA
GND                      U2               DW19     SOCKET4677_AZIFS054P001C01-SOCA
GND                      U2               DW21     SOCKET4677_AZIFS054P001C01-SOCA
GND                      U2               DW23     SOCKET4677_AZIFS054P001C01-SOCA
GND                      U2               DW25     SOCKET4677_AZIFS054P001C01-SOCA
GND                      U2               DW27     SOCKET4677_AZIFS054P001C01-SOCA
GND                      U2               DW29     SOCKET4677_AZIFS054P001C01-SOCA
GND                      U2               DW31     SOCKET4677_AZIFS054P001C01-SOCA
GND                      U2               DW33     SOCKET4677_AZIFS054P001C01-SOCA
GND                      U2               DW35     SOCKET4677_AZIFS054P001C01-SOCA
GND                      U2               DW37     SOCKET4677_AZIFS054P001C01-SOCA
GND                      U2               DW39     SOCKET4677_AZIFS054P001C01-SOCA
GND                      U2               DW41     SOCKET4677_AZIFS054P001C01-SOCA
GND                      U2               DW43     SOCKET4677_AZIFS054P001C01-SOCA
GND                      U2               DW45     SOCKET4677_AZIFS054P001C01-SOCA
GND                      U2               DW48     SOCKET4677_AZIFS054P001C01-SOCA
GND                      U2               DW50     SOCKET4677_AZIFS054P001C01-SOCA
GND                      U2               DW52     SOCKET4677_AZIFS054P001C01-SOCA
GND                      U2               DW54     SOCKET4677_AZIFS054P001C01-SOCA
GND                      U2               DW56     SOCKET4677_AZIFS054P001C01-SOCA
GND                      U2               DW58     SOCKET4677_AZIFS054P001C01-SOCA
GND                      U2               DW60     SOCKET4677_AZIFS054P001C01-SOCA
GND                      U2               DW62     SOCKET4677_AZIFS054P001C01-SOCA
GND                      U2               DW64     SOCKET4677_AZIFS054P001C01-SOCA
GND                      U2               DW66     SOCKET4677_AZIFS054P001C01-SOCA
GND                      U2               DW68     SOCKET4677_AZIFS054P001C01-SOCA
GND                      U2               DW70     SOCKET4677_AZIFS054P001C01-SOCA
GND                      U2               DW72     SOCKET4677_AZIFS054P001C01-SOCA
GND                      U2               DW74     SOCKET4677_AZIFS054P001C01-SOCA
GND                      U2               DW76     SOCKET4677_AZIFS054P001C01-SOCA
GND                      U2               DW80     SOCKET4677_AZIFS054P001C01-SOCA
GND                      U2               DW82     SOCKET4677_AZIFS054P001C01-SOCA
GND                      U2               DW84     SOCKET4677_AZIFS054P001C01-SOCA
GND                      U2               DW88     SOCKET4677_AZIFS054P001C01-SOCA
GND                      U2               DY4      SOCKET4677_AZIFS054P001C01-SOCA
GND                      U2               DY8      SOCKET4677_AZIFS054P001C01-SOCA
GND                      U2               DY12     SOCKET4677_AZIFS054P001C01-SOCA
GND                      U2               DY16     SOCKET4677_AZIFS054P001C01-SOCA
GND                      U2               DY42     SOCKET4677_AZIFS054P001C01-SOCA
GND                      U2               DY77     SOCKET4677_AZIFS054P001C01-SOCA
GND                      U2               E5       SOCKET4677_AZIFS054P001C01-SOCA
GND                      U2               E39      SOCKET4677_AZIFS054P001C01-SOCA
GND                      U2               E52      SOCKET4677_AZIFS054P001C01-SOCA
GND                      U2               E74      SOCKET4677_AZIFS054P001C01-SOCA
GND                      U2               E76      SOCKET4677_AZIFS054P001C01-SOCA
GND                      U2               E78      SOCKET4677_AZIFS054P001C01-SOCA
GND                      U2               E86      SOCKET4677_AZIFS054P001C01-SOCA
GND                      U2               EA21     SOCKET4677_AZIFS054P001C01-SOCA
GND                      U2               EA27     SOCKET4677_AZIFS054P001C01-SOCA
GND                      U2               EA33     SOCKET4677_AZIFS054P001C01-SOCA
GND                      U2               EA39     SOCKET4677_AZIFS054P001C01-SOCA
GND                      U2               EA45     SOCKET4677_AZIFS054P001C01-SOCA
GND                      U2               EA52     SOCKET4677_AZIFS054P001C01-SOCA
GND                      U2               EA58     SOCKET4677_AZIFS054P001C01-SOCA
GND                      U2               EA64     SOCKET4677_AZIFS054P001C01-SOCA
GND                      U2               EA70     SOCKET4677_AZIFS054P001C01-SOCA
GND                      U2               EA76     SOCKET4677_AZIFS054P001C01-SOCA
GND                      U2               EA78     SOCKET4677_AZIFS054P001C01-SOCA
GND                      U2               EA80     SOCKET4677_AZIFS054P001C01-SOCA
GND                      U2               EA84     SOCKET4677_AZIFS054P001C01-SOCA
GND                      U2               EA88     SOCKET4677_AZIFS054P001C01-SOCA
GND                      U2               EB4      SOCKET4677_AZIFS054P001C01-SOCA
GND                      U2               EB8      SOCKET4677_AZIFS054P001C01-SOCA
GND                      U2               EB12     SOCKET4677_AZIFS054P001C01-SOCA
GND                      U2               EB16     SOCKET4677_AZIFS054P001C01-SOCA
GND                      U2               EB20     SOCKET4677_AZIFS054P001C01-SOCA
GND                      U2               EB22     SOCKET4677_AZIFS054P001C01-SOCA
GND                      U2               EB26     SOCKET4677_AZIFS054P001C01-SOCA
GND                      U2               EB28     SOCKET4677_AZIFS054P001C01-SOCA
GND                      U2               EB32     SOCKET4677_AZIFS054P001C01-SOCA
GND                      U2               EB34     SOCKET4677_AZIFS054P001C01-SOCA
GND                      U2               EB38     SOCKET4677_AZIFS054P001C01-SOCA
GND                      U2               EB40     SOCKET4677_AZIFS054P001C01-SOCA
GND                      U2               EB44     SOCKET4677_AZIFS054P001C01-SOCA
GND                      U2               EB47     SOCKET4677_AZIFS054P001C01-SOCA
GND                      U2               EB51     SOCKET4677_AZIFS054P001C01-SOCA
GND                      U2               EB53     SOCKET4677_AZIFS054P001C01-SOCA
GND                      U2               EB57     SOCKET4677_AZIFS054P001C01-SOCA
GND                      U2               EB59     SOCKET4677_AZIFS054P001C01-SOCA
GND                      U2               EB63     SOCKET4677_AZIFS054P001C01-SOCA
GND                      U2               EB65     SOCKET4677_AZIFS054P001C01-SOCA
GND                      U2               EB69     SOCKET4677_AZIFS054P001C01-SOCA
GND                      U2               EB71     SOCKET4677_AZIFS054P001C01-SOCA
GND                      U2               EB75     SOCKET4677_AZIFS054P001C01-SOCA
GND                      U2               EB79     SOCKET4677_AZIFS054P001C01-SOCA
GND                      U2               EB83     SOCKET4677_AZIFS054P001C01-SOCA
GND                      U2               EB87     SOCKET4677_AZIFS054P001C01-SOCA
GND                      U2               EB91     SOCKET4677_AZIFS054P001C01-SOCA
GND                      U2               EC1      SOCKET4677_AZIFS054P001C01-SOCA
GND                      U2               EC5      SOCKET4677_AZIFS054P001C01-SOCA
GND                      U2               EC9      SOCKET4677_AZIFS054P001C01-SOCA
GND                      U2               EC13     SOCKET4677_AZIFS054P001C01-SOCA
GND                      U2               EC19     SOCKET4677_AZIFS054P001C01-SOCA
GND                      U2               EC23     SOCKET4677_AZIFS054P001C01-SOCA
GND                      U2               EC25     SOCKET4677_AZIFS054P001C01-SOCA
GND                      U2               EC29     SOCKET4677_AZIFS054P001C01-SOCA
GND                      U2               EC31     SOCKET4677_AZIFS054P001C01-SOCA
GND                      U2               EC35     SOCKET4677_AZIFS054P001C01-SOCA
GND                      U2               EC37     SOCKET4677_AZIFS054P001C01-SOCA
GND                      U2               EC41     SOCKET4677_AZIFS054P001C01-SOCA
GND                      U2               EC43     SOCKET4677_AZIFS054P001C01-SOCA
GND                      U2               EC48     SOCKET4677_AZIFS054P001C01-SOCA
GND                      U2               EC50     SOCKET4677_AZIFS054P001C01-SOCA
GND                      U2               EC54     SOCKET4677_AZIFS054P001C01-SOCA
GND                      U2               EC56     SOCKET4677_AZIFS054P001C01-SOCA
GND                      U2               EC60     SOCKET4677_AZIFS054P001C01-SOCA
GND                      U2               EC62     SOCKET4677_AZIFS054P001C01-SOCA
GND                      U2               EC66     SOCKET4677_AZIFS054P001C01-SOCA
GND                      U2               EC68     SOCKET4677_AZIFS054P001C01-SOCA
GND                      U2               EC72     SOCKET4677_AZIFS054P001C01-SOCA
GND                      U2               EC74     SOCKET4677_AZIFS054P001C01-SOCA
GND                      U2               EC82     SOCKET4677_AZIFS054P001C01-SOCA
GND                      U2               EC84     SOCKET4677_AZIFS054P001C01-SOCA
GND                      U2               EC88     SOCKET4677_AZIFS054P001C01-SOCA
GND                      U2               ED4      SOCKET4677_AZIFS054P001C01-SOCA
GND                      U2               ED8      SOCKET4677_AZIFS054P001C01-SOCA
GND                      U2               ED12     SOCKET4677_AZIFS054P001C01-SOCA
GND                      U2               ED16     SOCKET4677_AZIFS054P001C01-SOCA
GND                      U2               ED18     SOCKET4677_AZIFS054P001C01-SOCA
GND                      U2               ED24     SOCKET4677_AZIFS054P001C01-SOCA
GND                      U2               ED30     SOCKET4677_AZIFS054P001C01-SOCA
GND                      U2               ED36     SOCKET4677_AZIFS054P001C01-SOCA
GND                      U2               ED42     SOCKET4677_AZIFS054P001C01-SOCA
GND                      U2               ED49     SOCKET4677_AZIFS054P001C01-SOCA
GND                      U2               ED55     SOCKET4677_AZIFS054P001C01-SOCA
GND                      U2               ED61     SOCKET4677_AZIFS054P001C01-SOCA
GND                      U2               ED67     SOCKET4677_AZIFS054P001C01-SOCA
GND                      U2               ED73     SOCKET4677_AZIFS054P001C01-SOCA
GND                      U2               EE17     SOCKET4677_AZIFS054P001C01-SOCA
GND                      U2               EE39     SOCKET4677_AZIFS054P001C01-SOCA
GND                      U2               EE52     SOCKET4677_AZIFS054P001C01-SOCA
GND                      U2               EE78     SOCKET4677_AZIFS054P001C01-SOCA
GND                      U2               EE80     SOCKET4677_AZIFS054P001C01-SOCA
GND                      U2               EE88     SOCKET4677_AZIFS054P001C01-SOCA
GND                      U2               EF2      SOCKET4677_AZIFS054P001C01-SOCA
GND                      U2               EF4      SOCKET4677_AZIFS054P001C01-SOCA
GND                      U2               EF8      SOCKET4677_AZIFS054P001C01-SOCA
GND                      U2               EF12     SOCKET4677_AZIFS054P001C01-SOCA
GND                      U2               EF16     SOCKET4677_AZIFS054P001C01-SOCA
GND                      U2               EF18     SOCKET4677_AZIFS054P001C01-SOCA
GND                      U2               EF20     SOCKET4677_AZIFS054P001C01-SOCA
GND                      U2               EF22     SOCKET4677_AZIFS054P001C01-SOCA
GND                      U2               EF24     SOCKET4677_AZIFS054P001C01-SOCA
GND                      U2               EF26     SOCKET4677_AZIFS054P001C01-SOCA
GND                      U2               EF28     SOCKET4677_AZIFS054P001C01-SOCA
GND                      U2               EF30     SOCKET4677_AZIFS054P001C01-SOCA
GND                      U2               EF32     SOCKET4677_AZIFS054P001C01-SOCA
GND                      U2               EF34     SOCKET4677_AZIFS054P001C01-SOCA
GND                      U2               EF36     SOCKET4677_AZIFS054P001C01-SOCA
GND                      U2               EF38     SOCKET4677_AZIFS054P001C01-SOCA
GND                      U2               EF40     SOCKET4677_AZIFS054P001C01-SOCA
GND                      U2               EF42     SOCKET4677_AZIFS054P001C01-SOCA
GND                      U2               EF44     SOCKET4677_AZIFS054P001C01-SOCA
GND                      U2               EF47     SOCKET4677_AZIFS054P001C01-SOCA
GND                      U2               EF49     SOCKET4677_AZIFS054P001C01-SOCA
GND                      U2               EF51     SOCKET4677_AZIFS054P001C01-SOCA
GND                      U2               EF53     SOCKET4677_AZIFS054P001C01-SOCA
GND                      U2               EF55     SOCKET4677_AZIFS054P001C01-SOCA
GND                      U2               EF57     SOCKET4677_AZIFS054P001C01-SOCA
GND                      U2               EF59     SOCKET4677_AZIFS054P001C01-SOCA
GND                      U2               EF61     SOCKET4677_AZIFS054P001C01-SOCA
GND                      U2               EF63     SOCKET4677_AZIFS054P001C01-SOCA
GND                      U2               EF65     SOCKET4677_AZIFS054P001C01-SOCA
GND                      U2               EF67     SOCKET4677_AZIFS054P001C01-SOCA
GND                      U2               EF69     SOCKET4677_AZIFS054P001C01-SOCA
GND                      U2               EF71     SOCKET4677_AZIFS054P001C01-SOCA
GND                      U2               EF73     SOCKET4677_AZIFS054P001C01-SOCA
GND                      U2               EF75     SOCKET4677_AZIFS054P001C01-SOCA
GND                      U2               EF77     SOCKET4677_AZIFS054P001C01-SOCA
GND                      U2               EF85     SOCKET4677_AZIFS054P001C01-SOCA
GND                      U2               EF87     SOCKET4677_AZIFS054P001C01-SOCA
GND                      U2               EF89     SOCKET4677_AZIFS054P001C01-SOCA
GND                      U2               EG5      SOCKET4677_AZIFS054P001C01-SOCA
GND                      U2               EG7      SOCKET4677_AZIFS054P001C01-SOCA
GND                      U2               EG9      SOCKET4677_AZIFS054P001C01-SOCA
GND                      U2               EG13     SOCKET4677_AZIFS054P001C01-SOCA
GND                      U2               EG39     SOCKET4677_AZIFS054P001C01-SOCA
GND                      U2               EG52     SOCKET4677_AZIFS054P001C01-SOCA
GND                      U2               EG82     SOCKET4677_AZIFS054P001C01-SOCA
GND                      U2               EG84     SOCKET4677_AZIFS054P001C01-SOCA
GND                      U2               EG86     SOCKET4677_AZIFS054P001C01-SOCA
GND                      U2               EG88     SOCKET4677_AZIFS054P001C01-SOCA
GND                      U2               EG90     SOCKET4677_AZIFS054P001C01-SOCA
GND                      U2               EH4      SOCKET4677_AZIFS054P001C01-SOCA
GND                      U2               EH6      SOCKET4677_AZIFS054P001C01-SOCA
GND                      U2               EH12     SOCKET4677_AZIFS054P001C01-SOCA
GND                      U2               EH14     SOCKET4677_AZIFS054P001C01-SOCA
GND                      U2               EH16     SOCKET4677_AZIFS054P001C01-SOCA
GND                      U2               EH18     SOCKET4677_AZIFS054P001C01-SOCA
GND                      U2               EH24     SOCKET4677_AZIFS054P001C01-SOCA
GND                      U2               EH30     SOCKET4677_AZIFS054P001C01-SOCA
GND                      U2               EH36     SOCKET4677_AZIFS054P001C01-SOCA
GND                      U2               EH42     SOCKET4677_AZIFS054P001C01-SOCA
GND                      U2               EH49     SOCKET4677_AZIFS054P001C01-SOCA
GND                      U2               EH55     SOCKET4677_AZIFS054P001C01-SOCA
GND                      U2               EH61     SOCKET4677_AZIFS054P001C01-SOCA
GND                      U2               EH67     SOCKET4677_AZIFS054P001C01-SOCA
GND                      U2               EH73     SOCKET4677_AZIFS054P001C01-SOCA
GND                      U2               EH79     SOCKET4677_AZIFS054P001C01-SOCA
GND                      U2               EH81     SOCKET4677_AZIFS054P001C01-SOCA
GND                      U2               EH83     SOCKET4677_AZIFS054P001C01-SOCA
GND                      U2               EJ7      SOCKET4677_AZIFS054P001C01-SOCA
GND                      U2               EJ9      SOCKET4677_AZIFS054P001C01-SOCA
GND                      U2               EJ11     SOCKET4677_AZIFS054P001C01-SOCA
GND                      U2               EJ13     SOCKET4677_AZIFS054P001C01-SOCA
GND                      U2               EJ17     SOCKET4677_AZIFS054P001C01-SOCA
GND                      U2               EJ19     SOCKET4677_AZIFS054P001C01-SOCA
GND                      U2               EJ23     SOCKET4677_AZIFS054P001C01-SOCA
GND                      U2               EJ25     SOCKET4677_AZIFS054P001C01-SOCA
GND                      U2               EJ29     SOCKET4677_AZIFS054P001C01-SOCA
GND                      U2               EJ31     SOCKET4677_AZIFS054P001C01-SOCA
GND                      U2               EJ35     SOCKET4677_AZIFS054P001C01-SOCA
GND                      U2               EJ37     SOCKET4677_AZIFS054P001C01-SOCA
GND                      U2               EJ41     SOCKET4677_AZIFS054P001C01-SOCA
GND                      U2               EJ43     SOCKET4677_AZIFS054P001C01-SOCA
GND                      U2               EJ48     SOCKET4677_AZIFS054P001C01-SOCA
GND                      U2               EJ50     SOCKET4677_AZIFS054P001C01-SOCA
GND                      U2               EJ54     SOCKET4677_AZIFS054P001C01-SOCA
GND                      U2               EJ56     SOCKET4677_AZIFS054P001C01-SOCA
GND                      U2               EJ60     SOCKET4677_AZIFS054P001C01-SOCA
GND                      U2               EJ62     SOCKET4677_AZIFS054P001C01-SOCA
GND                      U2               EJ66     SOCKET4677_AZIFS054P001C01-SOCA
GND                      U2               EJ68     SOCKET4677_AZIFS054P001C01-SOCA
GND                      U2               EJ72     SOCKET4677_AZIFS054P001C01-SOCA
GND                      U2               EJ74     SOCKET4677_AZIFS054P001C01-SOCA
GND                      U2               EJ78     SOCKET4677_AZIFS054P001C01-SOCA
GND                      U2               EJ88     SOCKET4677_AZIFS054P001C01-SOCA
GND                      U2               EK2      SOCKET4677_AZIFS054P001C01-SOCA
GND                      U2               EK4      SOCKET4677_AZIFS054P001C01-SOCA
GND                      U2               EK10     SOCKET4677_AZIFS054P001C01-SOCA
GND                      U2               EK14     SOCKET4677_AZIFS054P001C01-SOCA
GND                      U2               EK16     SOCKET4677_AZIFS054P001C01-SOCA
GND                      U2               EK20     SOCKET4677_AZIFS054P001C01-SOCA
GND                      U2               EK22     SOCKET4677_AZIFS054P001C01-SOCA
GND                      U2               EK26     SOCKET4677_AZIFS054P001C01-SOCA
GND                      U2               EK28     SOCKET4677_AZIFS054P001C01-SOCA
GND                      U2               EK32     SOCKET4677_AZIFS054P001C01-SOCA
GND                      U2               EK34     SOCKET4677_AZIFS054P001C01-SOCA
GND                      U2               EK38     SOCKET4677_AZIFS054P001C01-SOCA
GND                      U2               EK40     SOCKET4677_AZIFS054P001C01-SOCA
GND                      U2               EK44     SOCKET4677_AZIFS054P001C01-SOCA
GND                      U2               EK47     SOCKET4677_AZIFS054P001C01-SOCA
GND                      U2               EK51     SOCKET4677_AZIFS054P001C01-SOCA
GND                      U2               EK53     SOCKET4677_AZIFS054P001C01-SOCA
GND                      U2               EK57     SOCKET4677_AZIFS054P001C01-SOCA
GND                      U2               EK59     SOCKET4677_AZIFS054P001C01-SOCA
GND                      U2               EK63     SOCKET4677_AZIFS054P001C01-SOCA
GND                      U2               EK65     SOCKET4677_AZIFS054P001C01-SOCA
GND                      U2               EK69     SOCKET4677_AZIFS054P001C01-SOCA
GND                      U2               EK71     SOCKET4677_AZIFS054P001C01-SOCA
GND                      U2               EK75     SOCKET4677_AZIFS054P001C01-SOCA
GND                      U2               EK77     SOCKET4677_AZIFS054P001C01-SOCA
GND                      U2               EK79     SOCKET4677_AZIFS054P001C01-SOCA
GND                      U2               EK83     SOCKET4677_AZIFS054P001C01-SOCA
GND                      U2               EK89     SOCKET4677_AZIFS054P001C01-SOCA
GND                      U2               EL3      SOCKET4677_AZIFS054P001C01-SOCA
GND                      U2               EL5      SOCKET4677_AZIFS054P001C01-SOCA
GND                      U2               EL7      SOCKET4677_AZIFS054P001C01-SOCA
GND                      U2               EL9      SOCKET4677_AZIFS054P001C01-SOCA
GND                      U2               EL15     SOCKET4677_AZIFS054P001C01-SOCA
GND                      U2               EL21     SOCKET4677_AZIFS054P001C01-SOCA
GND                      U2               EL27     SOCKET4677_AZIFS054P001C01-SOCA
GND                      U2               EL33     SOCKET4677_AZIFS054P001C01-SOCA
GND                      U2               EL39     SOCKET4677_AZIFS054P001C01-SOCA
GND                      U2               EL45     SOCKET4677_AZIFS054P001C01-SOCA
GND                      U2               EL52     SOCKET4677_AZIFS054P001C01-SOCA
GND                      U2               EL58     SOCKET4677_AZIFS054P001C01-SOCA
GND                      U2               EL64     SOCKET4677_AZIFS054P001C01-SOCA
GND                      U2               EL70     SOCKET4677_AZIFS054P001C01-SOCA
GND                      U2               EL72     SOCKET4677_AZIFS054P001C01-SOCA
GND                      U2               EL76     SOCKET4677_AZIFS054P001C01-SOCA
GND                      U2               EL86     SOCKET4677_AZIFS054P001C01-SOCA
GND                      U2               EM8      SOCKET4677_AZIFS054P001C01-SOCA
GND                      U2               EM42     SOCKET4677_AZIFS054P001C01-SOCA
GND                      U2               EM49     SOCKET4677_AZIFS054P001C01-SOCA
GND                      U2               EM73     SOCKET4677_AZIFS054P001C01-SOCA
GND                      U2               EM79     SOCKET4677_AZIFS054P001C01-SOCA
GND                      U2               EM81     SOCKET4677_AZIFS054P001C01-SOCA
GND                      U2               EM83     SOCKET4677_AZIFS054P001C01-SOCA
GND                      U2               EN9      SOCKET4677_AZIFS054P001C01-SOCA
GND                      U2               EN11     SOCKET4677_AZIFS054P001C01-SOCA
GND                      U2               EN13     SOCKET4677_AZIFS054P001C01-SOCA
GND                      U2               EN15     SOCKET4677_AZIFS054P001C01-SOCA
GND                      U2               EN17     SOCKET4677_AZIFS054P001C01-SOCA
GND                      U2               EN19     SOCKET4677_AZIFS054P001C01-SOCA
GND                      U2               EN21     SOCKET4677_AZIFS054P001C01-SOCA
GND                      U2               EN23     SOCKET4677_AZIFS054P001C01-SOCA
GND                      U2               EN25     SOCKET4677_AZIFS054P001C01-SOCA
GND                      U2               EN27     SOCKET4677_AZIFS054P001C01-SOCA
GND                      U2               EN29     SOCKET4677_AZIFS054P001C01-SOCA
GND                      U2               EN31     SOCKET4677_AZIFS054P001C01-SOCA
GND                      U2               EN33     SOCKET4677_AZIFS054P001C01-SOCA
GND                      U2               EN35     SOCKET4677_AZIFS054P001C01-SOCA
GND                      U2               EN37     SOCKET4677_AZIFS054P001C01-SOCA
GND                      U2               EN39     SOCKET4677_AZIFS054P001C01-SOCA
GND                      U2               EN41     SOCKET4677_AZIFS054P001C01-SOCA
GND                      U2               EN43     SOCKET4677_AZIFS054P001C01-SOCA
GND                      U2               EN45     SOCKET4677_AZIFS054P001C01-SOCA
GND                      U2               EN48     SOCKET4677_AZIFS054P001C01-SOCA
GND                      U2               EN50     SOCKET4677_AZIFS054P001C01-SOCA
GND                      U2               EN52     SOCKET4677_AZIFS054P001C01-SOCA
GND                      U2               EN54     SOCKET4677_AZIFS054P001C01-SOCA
GND                      U2               EN56     SOCKET4677_AZIFS054P001C01-SOCA
GND                      U2               EN58     SOCKET4677_AZIFS054P001C01-SOCA
GND                      U2               EN60     SOCKET4677_AZIFS054P001C01-SOCA
GND                      U2               EN62     SOCKET4677_AZIFS054P001C01-SOCA
GND                      U2               EN64     SOCKET4677_AZIFS054P001C01-SOCA
GND                      U2               EN66     SOCKET4677_AZIFS054P001C01-SOCA
GND                      U2               EN72     SOCKET4677_AZIFS054P001C01-SOCA
GND                      U2               EN78     SOCKET4677_AZIFS054P001C01-SOCA
GND                      U2               EN80     SOCKET4677_AZIFS054P001C01-SOCA
GND                      U2               EN88     SOCKET4677_AZIFS054P001C01-SOCA
GND                      U2               EP67     SOCKET4677_AZIFS054P001C01-SOCA
GND                      U2               EP69     SOCKET4677_AZIFS054P001C01-SOCA
GND                      U2               EP71     SOCKET4677_AZIFS054P001C01-SOCA
GND                      U2               EP77     SOCKET4677_AZIFS054P001C01-SOCA
GND                      U2               EP83     SOCKET4677_AZIFS054P001C01-SOCA
GND                      U2               ER5      SOCKET4677_AZIFS054P001C01-SOCA
GND                      U2               ER7      SOCKET4677_AZIFS054P001C01-SOCA
GND                      U2               ER9      SOCKET4677_AZIFS054P001C01-SOCA
GND                      U2               ER15     SOCKET4677_AZIFS054P001C01-SOCA
GND                      U2               ER21     SOCKET4677_AZIFS054P001C01-SOCA
GND                      U2               ER27     SOCKET4677_AZIFS054P001C01-SOCA
GND                      U2               ER33     SOCKET4677_AZIFS054P001C01-SOCA
GND                      U2               ER39     SOCKET4677_AZIFS054P001C01-SOCA
GND                      U2               ER41     SOCKET4677_AZIFS054P001C01-SOCA
GND                      U2               ER43     SOCKET4677_AZIFS054P001C01-SOCA
GND                      U2               ER48     SOCKET4677_AZIFS054P001C01-SOCA
GND                      U2               ER50     SOCKET4677_AZIFS054P001C01-SOCA
GND                      U2               ER52     SOCKET4677_AZIFS054P001C01-SOCA
GND                      U2               ER58     SOCKET4677_AZIFS054P001C01-SOCA
GND                      U2               ER64     SOCKET4677_AZIFS054P001C01-SOCA
GND                      U2               ER70     SOCKET4677_AZIFS054P001C01-SOCA
GND                      U2               ER74     SOCKET4677_AZIFS054P001C01-SOCA
GND                      U2               ER78     SOCKET4677_AZIFS054P001C01-SOCA
GND                      U2               ER80     SOCKET4677_AZIFS054P001C01-SOCA
GND                      U2               ER84     SOCKET4677_AZIFS054P001C01-SOCA
GND                      U2               ER86     SOCKET4677_AZIFS054P001C01-SOCA
GND                      U2               ET10     SOCKET4677_AZIFS054P001C01-SOCA
GND                      U2               ET14     SOCKET4677_AZIFS054P001C01-SOCA
GND                      U2               ET16     SOCKET4677_AZIFS054P001C01-SOCA
GND                      U2               ET20     SOCKET4677_AZIFS054P001C01-SOCA
GND                      U2               ET22     SOCKET4677_AZIFS054P001C01-SOCA
GND                      U2               ET26     SOCKET4677_AZIFS054P001C01-SOCA
GND                      U2               ET28     SOCKET4677_AZIFS054P001C01-SOCA
GND                      U2               ET32     SOCKET4677_AZIFS054P001C01-SOCA
GND                      U2               ET34     SOCKET4677_AZIFS054P001C01-SOCA
GND                      U2               ET38     SOCKET4677_AZIFS054P001C01-SOCA
GND                      U2               ET53     SOCKET4677_AZIFS054P001C01-SOCA
GND                      U2               ET57     SOCKET4677_AZIFS054P001C01-SOCA
GND                      U2               ET59     SOCKET4677_AZIFS054P001C01-SOCA
GND                      U2               F4       SOCKET4677_AZIFS054P001C01-SOCA
GND                      U2               F6       SOCKET4677_AZIFS054P001C01-SOCA
GND                      U2               F12      SOCKET4677_AZIFS054P001C01-SOCA
GND                      U2               F18      SOCKET4677_AZIFS054P001C01-SOCA
GND                      U2               F24      SOCKET4677_AZIFS054P001C01-SOCA
GND                      U2               F30      SOCKET4677_AZIFS054P001C01-SOCA
GND                      U2               F36      SOCKET4677_AZIFS054P001C01-SOCA
GND                      U2               F42      SOCKET4677_AZIFS054P001C01-SOCA
GND                      U2               F49      SOCKET4677_AZIFS054P001C01-SOCA
GND                      U2               F55      SOCKET4677_AZIFS054P001C01-SOCA
GND                      U2               F61      SOCKET4677_AZIFS054P001C01-SOCA
GND                      U2               F67      SOCKET4677_AZIFS054P001C01-SOCA
GND                      U2               F73      SOCKET4677_AZIFS054P001C01-SOCA
GND                      U2               F79      SOCKET4677_AZIFS054P001C01-SOCA
GND                      U2               F83      SOCKET4677_AZIFS054P001C01-SOCA
GND                      U2               F89      SOCKET4677_AZIFS054P001C01-SOCA
GND                      U2               G3       SOCKET4677_AZIFS054P001C01-SOCA
GND                      U2               G7       SOCKET4677_AZIFS054P001C01-SOCA
GND                      U2               G11      SOCKET4677_AZIFS054P001C01-SOCA
GND                      U2               G13      SOCKET4677_AZIFS054P001C01-SOCA
GND                      U2               G17      SOCKET4677_AZIFS054P001C01-SOCA
GND                      U2               G19      SOCKET4677_AZIFS054P001C01-SOCA
GND                      U2               G23      SOCKET4677_AZIFS054P001C01-SOCA
GND                      U2               G25      SOCKET4677_AZIFS054P001C01-SOCA
GND                      U2               G29      SOCKET4677_AZIFS054P001C01-SOCA
GND                      U2               G31      SOCKET4677_AZIFS054P001C01-SOCA
GND                      U2               G35      SOCKET4677_AZIFS054P001C01-SOCA
GND                      U2               G37      SOCKET4677_AZIFS054P001C01-SOCA
GND                      U2               G41      SOCKET4677_AZIFS054P001C01-SOCA
GND                      U2               G43      SOCKET4677_AZIFS054P001C01-SOCA
GND                      U2               G48      SOCKET4677_AZIFS054P001C01-SOCA
GND                      U2               G50      SOCKET4677_AZIFS054P001C01-SOCA
GND                      U2               G54      SOCKET4677_AZIFS054P001C01-SOCA
GND                      U2               G56      SOCKET4677_AZIFS054P001C01-SOCA
GND                      U2               G60      SOCKET4677_AZIFS054P001C01-SOCA
GND                      U2               G62      SOCKET4677_AZIFS054P001C01-SOCA
GND                      U2               G66      SOCKET4677_AZIFS054P001C01-SOCA
GND                      U2               G68      SOCKET4677_AZIFS054P001C01-SOCA
GND                      U2               G72      SOCKET4677_AZIFS054P001C01-SOCA
GND                      U2               G74      SOCKET4677_AZIFS054P001C01-SOCA
GND                      U2               G84      SOCKET4677_AZIFS054P001C01-SOCA
GND                      U2               G88      SOCKET4677_AZIFS054P001C01-SOCA
GND                      U2               G90      SOCKET4677_AZIFS054P001C01-SOCA
GND                      U2               H2       SOCKET4677_AZIFS054P001C01-SOCA
GND                      U2               H4       SOCKET4677_AZIFS054P001C01-SOCA
GND                      U2               H6       SOCKET4677_AZIFS054P001C01-SOCA
GND                      U2               H8       SOCKET4677_AZIFS054P001C01-SOCA
GND                      U2               H10      SOCKET4677_AZIFS054P001C01-SOCA
GND                      U2               H14      SOCKET4677_AZIFS054P001C01-SOCA
GND                      U2               H16      SOCKET4677_AZIFS054P001C01-SOCA
GND                      U2               H20      SOCKET4677_AZIFS054P001C01-SOCA
GND                      U2               H22      SOCKET4677_AZIFS054P001C01-SOCA
GND                      U2               H26      SOCKET4677_AZIFS054P001C01-SOCA
GND                      U2               H28      SOCKET4677_AZIFS054P001C01-SOCA
GND                      U2               H32      SOCKET4677_AZIFS054P001C01-SOCA
GND                      U2               H34      SOCKET4677_AZIFS054P001C01-SOCA
GND                      U2               H38      SOCKET4677_AZIFS054P001C01-SOCA
GND                      U2               H40      SOCKET4677_AZIFS054P001C01-SOCA
GND                      U2               H44      SOCKET4677_AZIFS054P001C01-SOCA
GND                      U2               H47      SOCKET4677_AZIFS054P001C01-SOCA
GND                      U2               H51      SOCKET4677_AZIFS054P001C01-SOCA
GND                      U2               H53      SOCKET4677_AZIFS054P001C01-SOCA
GND                      U2               H57      SOCKET4677_AZIFS054P001C01-SOCA
GND                      U2               H59      SOCKET4677_AZIFS054P001C01-SOCA
GND                      U2               H63      SOCKET4677_AZIFS054P001C01-SOCA
GND                      U2               H65      SOCKET4677_AZIFS054P001C01-SOCA
GND                      U2               H69      SOCKET4677_AZIFS054P001C01-SOCA
GND                      U2               H71      SOCKET4677_AZIFS054P001C01-SOCA
GND                      U2               H75      SOCKET4677_AZIFS054P001C01-SOCA
GND                      U2               H79      SOCKET4677_AZIFS054P001C01-SOCA
GND                      U2               H81      SOCKET4677_AZIFS054P001C01-SOCA
GND                      U2               J5       SOCKET4677_AZIFS054P001C01-SOCA
GND                      U2               J9       SOCKET4677_AZIFS054P001C01-SOCA
GND                      U2               J15      SOCKET4677_AZIFS054P001C01-SOCA
GND                      U2               J21      SOCKET4677_AZIFS054P001C01-SOCA
GND                      U2               J27      SOCKET4677_AZIFS054P001C01-SOCA
GND                      U2               J33      SOCKET4677_AZIFS054P001C01-SOCA
GND                      U2               J39      SOCKET4677_AZIFS054P001C01-SOCA
GND                      U2               J45      SOCKET4677_AZIFS054P001C01-SOCA
GND                      U2               J52      SOCKET4677_AZIFS054P001C01-SOCA
GND                      U2               J58      SOCKET4677_AZIFS054P001C01-SOCA
GND                      U2               J64      SOCKET4677_AZIFS054P001C01-SOCA
GND                      U2               J70      SOCKET4677_AZIFS054P001C01-SOCA
GND                      U2               J76      SOCKET4677_AZIFS054P001C01-SOCA
GND                      U2               J78      SOCKET4677_AZIFS054P001C01-SOCA
GND                      U2               J84      SOCKET4677_AZIFS054P001C01-SOCA
GND                      U2               J86      SOCKET4677_AZIFS054P001C01-SOCA
GND                      U2               J88      SOCKET4677_AZIFS054P001C01-SOCA
GND                      U2               K2       SOCKET4677_AZIFS054P001C01-SOCA
GND                      U2               K8       SOCKET4677_AZIFS054P001C01-SOCA
GND                      U2               K12      SOCKET4677_AZIFS054P001C01-SOCA
GND                      U2               K14      SOCKET4677_AZIFS054P001C01-SOCA
GND                      U2               K42      SOCKET4677_AZIFS054P001C01-SOCA
GND                      U2               K49      SOCKET4677_AZIFS054P001C01-SOCA
GND                      U2               K77      SOCKET4677_AZIFS054P001C01-SOCA
GND                      U2               K83      SOCKET4677_AZIFS054P001C01-SOCA
GND                      U2               K85      SOCKET4677_AZIFS054P001C01-SOCA
GND                      U2               L5       SOCKET4677_AZIFS054P001C01-SOCA
GND                      U2               L9       SOCKET4677_AZIFS054P001C01-SOCA
GND                      U2               L13      SOCKET4677_AZIFS054P001C01-SOCA
GND                      U2               L15      SOCKET4677_AZIFS054P001C01-SOCA
GND                      U2               L17      SOCKET4677_AZIFS054P001C01-SOCA
GND                      U2               L19      SOCKET4677_AZIFS054P001C01-SOCA
GND                      U2               L21      SOCKET4677_AZIFS054P001C01-SOCA
GND                      U2               L23      SOCKET4677_AZIFS054P001C01-SOCA
GND                      U2               L25      SOCKET4677_AZIFS054P001C01-SOCA
GND                      U2               L27      SOCKET4677_AZIFS054P001C01-SOCA
GND                      U2               L29      SOCKET4677_AZIFS054P001C01-SOCA
GND                      U2               L31      SOCKET4677_AZIFS054P001C01-SOCA
GND                      U2               L33      SOCKET4677_AZIFS054P001C01-SOCA
GND                      U2               L35      SOCKET4677_AZIFS054P001C01-SOCA
GND                      U2               L37      SOCKET4677_AZIFS054P001C01-SOCA
GND                      U2               L39      SOCKET4677_AZIFS054P001C01-SOCA
GND                      U2               L41      SOCKET4677_AZIFS054P001C01-SOCA
GND                      U2               L43      SOCKET4677_AZIFS054P001C01-SOCA
GND                      U2               L45      SOCKET4677_AZIFS054P001C01-SOCA
GND                      U2               L48      SOCKET4677_AZIFS054P001C01-SOCA
GND                      U2               L50      SOCKET4677_AZIFS054P001C01-SOCA
GND                      U2               L52      SOCKET4677_AZIFS054P001C01-SOCA
GND                      U2               L54      SOCKET4677_AZIFS054P001C01-SOCA
GND                      U2               L56      SOCKET4677_AZIFS054P001C01-SOCA
GND                      U2               L58      SOCKET4677_AZIFS054P001C01-SOCA
GND                      U2               L60      SOCKET4677_AZIFS054P001C01-SOCA
GND                      U2               L62      SOCKET4677_AZIFS054P001C01-SOCA
GND                      U2               L64      SOCKET4677_AZIFS054P001C01-SOCA
GND                      U2               L66      SOCKET4677_AZIFS054P001C01-SOCA
GND                      U2               L68      SOCKET4677_AZIFS054P001C01-SOCA
GND                      U2               L70      SOCKET4677_AZIFS054P001C01-SOCA
GND                      U2               L72      SOCKET4677_AZIFS054P001C01-SOCA
GND                      U2               L74      SOCKET4677_AZIFS054P001C01-SOCA
GND                      U2               L76      SOCKET4677_AZIFS054P001C01-SOCA
GND                      U2               L78      SOCKET4677_AZIFS054P001C01-SOCA
GND                      U2               L88      SOCKET4677_AZIFS054P001C01-SOCA
GND                      U2               L90      SOCKET4677_AZIFS054P001C01-SOCA
GND                      U2               M4       SOCKET4677_AZIFS054P001C01-SOCA
GND                      U2               M8       SOCKET4677_AZIFS054P001C01-SOCA
GND                      U2               M12      SOCKET4677_AZIFS054P001C01-SOCA
GND                      U2               M42      SOCKET4677_AZIFS054P001C01-SOCA
GND                      U2               M49      SOCKET4677_AZIFS054P001C01-SOCA
GND                      U2               M81      SOCKET4677_AZIFS054P001C01-SOCA
GND                      U2               M83      SOCKET4677_AZIFS054P001C01-SOCA
GND                      U2               N15      SOCKET4677_AZIFS054P001C01-SOCA
GND                      U2               N21      SOCKET4677_AZIFS054P001C01-SOCA
GND                      U2               N27      SOCKET4677_AZIFS054P001C01-SOCA
GND                      U2               N33      SOCKET4677_AZIFS054P001C01-SOCA
GND                      U2               N39      SOCKET4677_AZIFS054P001C01-SOCA
GND                      U2               N45      SOCKET4677_AZIFS054P001C01-SOCA
GND                      U2               N52      SOCKET4677_AZIFS054P001C01-SOCA
GND                      U2               N58      SOCKET4677_AZIFS054P001C01-SOCA
GND                      U2               N64      SOCKET4677_AZIFS054P001C01-SOCA
GND                      U2               N70      SOCKET4677_AZIFS054P001C01-SOCA
GND                      U2               N76      SOCKET4677_AZIFS054P001C01-SOCA
GND                      U2               N78      SOCKET4677_AZIFS054P001C01-SOCA
GND                      U2               N80      SOCKET4677_AZIFS054P001C01-SOCA
GND                      U2               N82      SOCKET4677_AZIFS054P001C01-SOCA
GND                      U2               N84      SOCKET4677_AZIFS054P001C01-SOCA
GND                      U2               N88      SOCKET4677_AZIFS054P001C01-SOCA
GND                      U2               P4       SOCKET4677_AZIFS054P001C01-SOCA
GND                      U2               P8       SOCKET4677_AZIFS054P001C01-SOCA
GND                      U2               P12      SOCKET4677_AZIFS054P001C01-SOCA
GND                      U2               P16      SOCKET4677_AZIFS054P001C01-SOCA
GND                      U2               P20      SOCKET4677_AZIFS054P001C01-SOCA
GND                      U2               P22      SOCKET4677_AZIFS054P001C01-SOCA
GND                      U2               P26      SOCKET4677_AZIFS054P001C01-SOCA
GND                      U2               P28      SOCKET4677_AZIFS054P001C01-SOCA
GND                      U2               P32      SOCKET4677_AZIFS054P001C01-SOCA
GND                      U2               P34      SOCKET4677_AZIFS054P001C01-SOCA
GND                      U2               P38      SOCKET4677_AZIFS054P001C01-SOCA
GND                      U2               P40      SOCKET4677_AZIFS054P001C01-SOCA
GND                      U2               P44      SOCKET4677_AZIFS054P001C01-SOCA
GND                      U2               P47      SOCKET4677_AZIFS054P001C01-SOCA
GND                      U2               P51      SOCKET4677_AZIFS054P001C01-SOCA
GND                      U2               P53      SOCKET4677_AZIFS054P001C01-SOCA
GND                      U2               P57      SOCKET4677_AZIFS054P001C01-SOCA
GND                      U2               P59      SOCKET4677_AZIFS054P001C01-SOCA
GND                      U2               P63      SOCKET4677_AZIFS054P001C01-SOCA
GND                      U2               P65      SOCKET4677_AZIFS054P001C01-SOCA
GND                      U2               P69      SOCKET4677_AZIFS054P001C01-SOCA
GND                      U2               P71      SOCKET4677_AZIFS054P001C01-SOCA
GND                      U2               P75      SOCKET4677_AZIFS054P001C01-SOCA
GND                      U2               P77      SOCKET4677_AZIFS054P001C01-SOCA
GND                      U2               P87      SOCKET4677_AZIFS054P001C01-SOCA
GND                      U2               P91      SOCKET4677_AZIFS054P001C01-SOCA
GND                      U2               R1       SOCKET4677_AZIFS054P001C01-SOCA
GND                      U2               R5       SOCKET4677_AZIFS054P001C01-SOCA
GND                      U2               R9       SOCKET4677_AZIFS054P001C01-SOCA
GND                      U2               R13      SOCKET4677_AZIFS054P001C01-SOCA
GND                      U2               R17      SOCKET4677_AZIFS054P001C01-SOCA
GND                      U2               R19      SOCKET4677_AZIFS054P001C01-SOCA
GND                      U2               R23      SOCKET4677_AZIFS054P001C01-SOCA
GND                      U2               R25      SOCKET4677_AZIFS054P001C01-SOCA
GND                      U2               R29      SOCKET4677_AZIFS054P001C01-SOCA
GND                      U2               R31      SOCKET4677_AZIFS054P001C01-SOCA
GND                      U2               R35      SOCKET4677_AZIFS054P001C01-SOCA
GND                      U2               R37      SOCKET4677_AZIFS054P001C01-SOCA
GND                      U2               R41      SOCKET4677_AZIFS054P001C01-SOCA
GND                      U2               R43      SOCKET4677_AZIFS054P001C01-SOCA
GND                      U2               R48      SOCKET4677_AZIFS054P001C01-SOCA
GND                      U2               R50      SOCKET4677_AZIFS054P001C01-SOCA
GND                      U2               R54      SOCKET4677_AZIFS054P001C01-SOCA
GND                      U2               R56      SOCKET4677_AZIFS054P001C01-SOCA
GND                      U2               R60      SOCKET4677_AZIFS054P001C01-SOCA
GND                      U2               R62      SOCKET4677_AZIFS054P001C01-SOCA
GND                      U2               R66      SOCKET4677_AZIFS054P001C01-SOCA
GND                      U2               R68      SOCKET4677_AZIFS054P001C01-SOCA
GND                      U2               R72      SOCKET4677_AZIFS054P001C01-SOCA
GND                      U2               R74      SOCKET4677_AZIFS054P001C01-SOCA
GND                      U2               R78      SOCKET4677_AZIFS054P001C01-SOCA
GND                      U2               R84      SOCKET4677_AZIFS054P001C01-SOCA
GND                      U2               R88      SOCKET4677_AZIFS054P001C01-SOCA
GND                      U2               T4       SOCKET4677_AZIFS054P001C01-SOCA
GND                      U2               T8       SOCKET4677_AZIFS054P001C01-SOCA
GND                      U2               T12      SOCKET4677_AZIFS054P001C01-SOCA
GND                      U2               T16      SOCKET4677_AZIFS054P001C01-SOCA
GND                      U2               T18      SOCKET4677_AZIFS054P001C01-SOCA
GND                      U2               T24      SOCKET4677_AZIFS054P001C01-SOCA
GND                      U2               T30      SOCKET4677_AZIFS054P001C01-SOCA
GND                      U2               T36      SOCKET4677_AZIFS054P001C01-SOCA
GND                      U2               T42      SOCKET4677_AZIFS054P001C01-SOCA
GND                      U2               T49      SOCKET4677_AZIFS054P001C01-SOCA
GND                      U2               T55      SOCKET4677_AZIFS054P001C01-SOCA
GND                      U2               T61      SOCKET4677_AZIFS054P001C01-SOCA
GND                      U2               T67      SOCKET4677_AZIFS054P001C01-SOCA
GND                      U2               T73      SOCKET4677_AZIFS054P001C01-SOCA
GND                      U2               T79      SOCKET4677_AZIFS054P001C01-SOCA
GND                      U2               T83      SOCKET4677_AZIFS054P001C01-SOCA
GND                      U2               U39      SOCKET4677_AZIFS054P001C01-SOCA
GND                      U2               U52      SOCKET4677_AZIFS054P001C01-SOCA
GND                      U2               U82      SOCKET4677_AZIFS054P001C01-SOCA
GND                      U2               U84      SOCKET4677_AZIFS054P001C01-SOCA
GND                      U2               U88      SOCKET4677_AZIFS054P001C01-SOCA
GND                      U2               V4       SOCKET4677_AZIFS054P001C01-SOCA
GND                      U2               V8       SOCKET4677_AZIFS054P001C01-SOCA
GND                      U2               V12      SOCKET4677_AZIFS054P001C01-SOCA
GND                      U2               V16      SOCKET4677_AZIFS054P001C01-SOCA
GND                      U2               V18      SOCKET4677_AZIFS054P001C01-SOCA
GND                      U2               V20      SOCKET4677_AZIFS054P001C01-SOCA
GND                      U2               V22      SOCKET4677_AZIFS054P001C01-SOCA
GND                      U2               V24      SOCKET4677_AZIFS054P001C01-SOCA
GND                      U2               V26      SOCKET4677_AZIFS054P001C01-SOCA
GND                      U2               V28      SOCKET4677_AZIFS054P001C01-SOCA
GND                      U2               V30      SOCKET4677_AZIFS054P001C01-SOCA
GND                      U2               V32      SOCKET4677_AZIFS054P001C01-SOCA
GND                      U2               V34      SOCKET4677_AZIFS054P001C01-SOCA
GND                      U2               V36      SOCKET4677_AZIFS054P001C01-SOCA
GND                      U2               V38      SOCKET4677_AZIFS054P001C01-SOCA
GND                      U2               V40      SOCKET4677_AZIFS054P001C01-SOCA
GND                      U2               V42      SOCKET4677_AZIFS054P001C01-SOCA
GND                      U2               V44      SOCKET4677_AZIFS054P001C01-SOCA
GND                      U2               V47      SOCKET4677_AZIFS054P001C01-SOCA
GND                      U2               V49      SOCKET4677_AZIFS054P001C01-SOCA
GND                      U2               V51      SOCKET4677_AZIFS054P001C01-SOCA
GND                      U2               V53      SOCKET4677_AZIFS054P001C01-SOCA
GND                      U2               V55      SOCKET4677_AZIFS054P001C01-SOCA
GND                      U2               V57      SOCKET4677_AZIFS054P001C01-SOCA
GND                      U2               V59      SOCKET4677_AZIFS054P001C01-SOCA
GND                      U2               V61      SOCKET4677_AZIFS054P001C01-SOCA
GND                      U2               V63      SOCKET4677_AZIFS054P001C01-SOCA
GND                      U2               V65      SOCKET4677_AZIFS054P001C01-SOCA
GND                      U2               V67      SOCKET4677_AZIFS054P001C01-SOCA
GND                      U2               V69      SOCKET4677_AZIFS054P001C01-SOCA
GND                      U2               V71      SOCKET4677_AZIFS054P001C01-SOCA
GND                      U2               V73      SOCKET4677_AZIFS054P001C01-SOCA
GND                      U2               V75      SOCKET4677_AZIFS054P001C01-SOCA
GND                      U2               V77      SOCKET4677_AZIFS054P001C01-SOCA
GND                      U2               V79      SOCKET4677_AZIFS054P001C01-SOCA
GND                      U2               V87      SOCKET4677_AZIFS054P001C01-SOCA
GND                      U2               V91      SOCKET4677_AZIFS054P001C01-SOCA
GND                      U2               W1       SOCKET4677_AZIFS054P001C01-SOCA
GND                      U2               W5       SOCKET4677_AZIFS054P001C01-SOCA
GND                      U2               W9       SOCKET4677_AZIFS054P001C01-SOCA
GND                      U2               W13      SOCKET4677_AZIFS054P001C01-SOCA
GND                      U2               W39      SOCKET4677_AZIFS054P001C01-SOCA
GND                      U2               W52      SOCKET4677_AZIFS054P001C01-SOCA
GND                      U2               W84      SOCKET4677_AZIFS054P001C01-SOCA
GND                      U2               W88      SOCKET4677_AZIFS054P001C01-SOCA
GND                      U2               Y4       SOCKET4677_AZIFS054P001C01-SOCA
GND                      U2               Y8       SOCKET4677_AZIFS054P001C01-SOCA
GND                      U2               Y12      SOCKET4677_AZIFS054P001C01-SOCA
GND                      U2               Y16      SOCKET4677_AZIFS054P001C01-SOCA
GND                      U2               Y18      SOCKET4677_AZIFS054P001C01-SOCA
GND                      U2               Y24      SOCKET4677_AZIFS054P001C01-SOCA
GND                      U2               Y30      SOCKET4677_AZIFS054P001C01-SOCA
GND                      U2               Y36      SOCKET4677_AZIFS054P001C01-SOCA
GND                      U2               Y42      SOCKET4677_AZIFS054P001C01-SOCA
GND                      U2               Y49      SOCKET4677_AZIFS054P001C01-SOCA
GND                      U2               Y55      SOCKET4677_AZIFS054P001C01-SOCA
GND                      U2               Y61      SOCKET4677_AZIFS054P001C01-SOCA
GND                      U2               Y67      SOCKET4677_AZIFS054P001C01-SOCA
GND                      U2               Y73      SOCKET4677_AZIFS054P001C01-SOCA
GND                      U4               A6       EMMITSBURG_REV0P9-GFNOCPU04302A
GND                      U4               A20      EMMITSBURG_REV0P9-GFNOCPU04302A
GND                      U4               A22      EMMITSBURG_REV0P9-GFNOCPU04302A
GND                      U4               A24      EMMITSBURG_REV0P9-GFNOCPU04302A
GND                      U4               A26      EMMITSBURG_REV0P9-GFNOCPU04302A
GND                      U4               A38      EMMITSBURG_REV0P9-GFNOCPU04302A
GND                      U4               A40      EMMITSBURG_REV0P9-GFNOCPU04302A
GND                      U4               AA5      EMMITSBURG_REV0P9-GFNOCPU04302A
GND                      U4               AA17     EMMITSBURG_REV0P9-GFNOCPU04302A
GND                      U4               AA19     EMMITSBURG_REV0P9-GFNOCPU04302A
GND                      U4               AA20     EMMITSBURG_REV0P9-GFNOCPU04302A
GND                      U4               AA22     EMMITSBURG_REV0P9-GFNOCPU04302A
GND                      U4               AA24     EMMITSBURG_REV0P9-GFNOCPU04302A
GND                      U4               AA25     EMMITSBURG_REV0P9-GFNOCPU04302A
GND                      U4               AA27     EMMITSBURG_REV0P9-GFNOCPU04302A
GND                      U4               AA32     EMMITSBURG_REV0P9-GFNOCPU04302A
GND                      U4               AA36     EMMITSBURG_REV0P9-GFNOCPU04302A
GND                      U4               AA39     EMMITSBURG_REV0P9-GFNOCPU04302A
GND                      U4               AB15     EMMITSBURG_REV0P9-GFNOCPU04302A
GND                      U4               AB17     EMMITSBURG_REV0P9-GFNOCPU04302A
GND                      U4               AB25     EMMITSBURG_REV0P9-GFNOCPU04302A
GND                      U4               AB37     EMMITSBURG_REV0P9-GFNOCPU04302A
GND                      U4               AC5      EMMITSBURG_REV0P9-GFNOCPU04302A
GND                      U4               AC29     EMMITSBURG_REV0P9-GFNOCPU04302A
GND                      U4               AC32     EMMITSBURG_REV0P9-GFNOCPU04302A
GND                      U4               AC36     EMMITSBURG_REV0P9-GFNOCPU04302A
GND                      U4               AC39     EMMITSBURG_REV0P9-GFNOCPU04302A
GND                      U4               AD8      EMMITSBURG_REV0P9-GFNOCPU04302A
GND                      U4               AD11     EMMITSBURG_REV0P9-GFNOCPU04302A
GND                      U4               AD19     EMMITSBURG_REV0P9-GFNOCPU04302A
GND                      U4               AD20     EMMITSBURG_REV0P9-GFNOCPU04302A
GND                      U4               AD22     EMMITSBURG_REV0P9-GFNOCPU04302A
GND                      U4               AD24     EMMITSBURG_REV0P9-GFNOCPU04302A
GND                      U4               AD31     EMMITSBURG_REV0P9-GFNOCPU04302A
GND                      U4               AD34     EMMITSBURG_REV0P9-GFNOCPU04302A
GND                      U4               AE5      EMMITSBURG_REV0P9-GFNOCPU04302A
GND                      U4               AE13     EMMITSBURG_REV0P9-GFNOCPU04302A
GND                      U4               AE39     EMMITSBURG_REV0P9-GFNOCPU04302A
GND                      U4               AF19     EMMITSBURG_REV0P9-GFNOCPU04302A
GND                      U4               AF24     EMMITSBURG_REV0P9-GFNOCPU04302A
GND                      U4               AF31     EMMITSBURG_REV0P9-GFNOCPU04302A
GND                      U4               AF40     EMMITSBURG_REV0P9-GFNOCPU04302A
GND                      U4               AF42     EMMITSBURG_REV0P9-GFNOCPU04302A
GND                      U4               AG5      EMMITSBURG_REV0P9-GFNOCPU04302A
GND                      U4               AG13     EMMITSBURG_REV0P9-GFNOCPU04302A
GND                      U4               AG19     EMMITSBURG_REV0P9-GFNOCPU04302A
GND                      U4               AG24     EMMITSBURG_REV0P9-GFNOCPU04302A
GND                      U4               AG39     EMMITSBURG_REV0P9-GFNOCPU04302A
GND                      U4               AH8      EMMITSBURG_REV0P9-GFNOCPU04302A
GND                      U4               AH31     EMMITSBURG_REV0P9-GFNOCPU04302A
GND                      U4               AJ5      EMMITSBURG_REV0P9-GFNOCPU04302A
GND                      U4               AJ19     EMMITSBURG_REV0P9-GFNOCPU04302A
GND                      U4               AJ24     EMMITSBURG_REV0P9-GFNOCPU04302A
GND                      U4               AJ29     EMMITSBURG_REV0P9-GFNOCPU04302A
GND                      U4               AJ36     EMMITSBURG_REV0P9-GFNOCPU04302A
GND                      U4               AJ39     EMMITSBURG_REV0P9-GFNOCPU04302A
GND                      U4               AK2      EMMITSBURG_REV0P9-GFNOCPU04302A
GND                      U4               AK4      EMMITSBURG_REV0P9-GFNOCPU04302A
GND                      U4               AK11     EMMITSBURG_REV0P9-GFNOCPU04302A
GND                      U4               AK37     EMMITSBURG_REV0P9-GFNOCPU04302A
GND                      U4               AL19     EMMITSBURG_REV0P9-GFNOCPU04302A
GND                      U4               AL24     EMMITSBURG_REV0P9-GFNOCPU04302A
GND                      U4               AL27     EMMITSBURG_REV0P9-GFNOCPU04302A
GND                      U4               AL29     EMMITSBURG_REV0P9-GFNOCPU04302A
GND                      U4               AL39     EMMITSBURG_REV0P9-GFNOCPU04302A
GND                      U4               AM8      EMMITSBURG_REV0P9-GFNOCPU04302A
GND                      U4               AM15     EMMITSBURG_REV0P9-GFNOCPU04302A
GND                      U4               AM31     EMMITSBURG_REV0P9-GFNOCPU04302A
GND                      U4               AN13     EMMITSBURG_REV0P9-GFNOCPU04302A
GND                      U4               AN16     EMMITSBURG_REV0P9-GFNOCPU04302A
GND                      U4               AN29     EMMITSBURG_REV0P9-GFNOCPU04302A
GND                      U4               AN32     EMMITSBURG_REV0P9-GFNOCPU04302A
GND                      U4               AP5      EMMITSBURG_REV0P9-GFNOCPU04302A
GND                      U4               AP11     EMMITSBURG_REV0P9-GFNOCPU04302A
GND                      U4               AP18     EMMITSBURG_REV0P9-GFNOCPU04302A
GND                      U4               AP24     EMMITSBURG_REV0P9-GFNOCPU04302A
GND                      U4               AP28     EMMITSBURG_REV0P9-GFNOCPU04302A
GND                      U4               AP37     EMMITSBURG_REV0P9-GFNOCPU04302A
GND                      U4               AP39     EMMITSBURG_REV0P9-GFNOCPU04302A
GND                      U4               AR20     EMMITSBURG_REV0P9-GFNOCPU04302A
GND                      U4               AR32     EMMITSBURG_REV0P9-GFNOCPU04302A
GND                      U4               AT5      EMMITSBURG_REV0P9-GFNOCPU04302A
GND                      U4               AT8      EMMITSBURG_REV0P9-GFNOCPU04302A
GND                      U4               AT11     EMMITSBURG_REV0P9-GFNOCPU04302A
GND                      U4               AT15     EMMITSBURG_REV0P9-GFNOCPU04302A
GND                      U4               AT21     EMMITSBURG_REV0P9-GFNOCPU04302A
GND                      U4               AT24     EMMITSBURG_REV0P9-GFNOCPU04302A
GND                      U4               AT28     EMMITSBURG_REV0P9-GFNOCPU04302A
GND                      U4               AT31     EMMITSBURG_REV0P9-GFNOCPU04302A
GND                      U4               AT34     EMMITSBURG_REV0P9-GFNOCPU04302A
GND                      U4               AT39     EMMITSBURG_REV0P9-GFNOCPU04302A
GND                      U4               AU20     EMMITSBURG_REV0P9-GFNOCPU04302A
GND                      U4               AU23     EMMITSBURG_REV0P9-GFNOCPU04302A
GND                      U4               AU26     EMMITSBURG_REV0P9-GFNOCPU04302A
GND                      U4               AU29     EMMITSBURG_REV0P9-GFNOCPU04302A
GND                      U4               AU32     EMMITSBURG_REV0P9-GFNOCPU04302A
GND                      U4               AU36     EMMITSBURG_REV0P9-GFNOCPU04302A
GND                      U4               AV5      EMMITSBURG_REV0P9-GFNOCPU04302A
GND                      U4               AV8      EMMITSBURG_REV0P9-GFNOCPU04302A
GND                      U4               AV37     EMMITSBURG_REV0P9-GFNOCPU04302A
GND                      U4               AV39     EMMITSBURG_REV0P9-GFNOCPU04302A
GND                      U4               AW7      EMMITSBURG_REV0P9-GFNOCPU04302A
GND                      U4               AY3      EMMITSBURG_REV0P9-GFNOCPU04302A
GND                      U4               AY5      EMMITSBURG_REV0P9-GFNOCPU04302A
GND                      U4               AY8      EMMITSBURG_REV0P9-GFNOCPU04302A
GND                      U4               AY11     EMMITSBURG_REV0P9-GFNOCPU04302A
GND                      U4               AY15     EMMITSBURG_REV0P9-GFNOCPU04302A
GND                      U4               AY18     EMMITSBURG_REV0P9-GFNOCPU04302A
GND                      U4               AY21     EMMITSBURG_REV0P9-GFNOCPU04302A
GND                      U4               AY24     EMMITSBURG_REV0P9-GFNOCPU04302A
GND                      U4               AY28     EMMITSBURG_REV0P9-GFNOCPU04302A
GND                      U4               AY31     EMMITSBURG_REV0P9-GFNOCPU04302A
GND                      U4               AY34     EMMITSBURG_REV0P9-GFNOCPU04302A
GND                      U4               AY37     EMMITSBURG_REV0P9-GFNOCPU04302A
GND                      U4               AY39     EMMITSBURG_REV0P9-GFNOCPU04302A
GND                      U4               B9       EMMITSBURG_REV0P9-GFNOCPU04302A
GND                      U4               B13      EMMITSBURG_REV0P9-GFNOCPU04302A
GND                      U4               B29      EMMITSBURG_REV0P9-GFNOCPU04302A
GND                      U4               B39      EMMITSBURG_REV0P9-GFNOCPU04302A
GND                      U4               BB1      EMMITSBURG_REV0P9-GFNOCPU04302A
GND                      U4               BB5      EMMITSBURG_REV0P9-GFNOCPU04302A
GND                      U4               BB39     EMMITSBURG_REV0P9-GFNOCPU04302A
GND                      U4               BC2      EMMITSBURG_REV0P9-GFNOCPU04302A
GND                      U4               BC6      EMMITSBURG_REV0P9-GFNOCPU04302A
GND                      U4               BC8      EMMITSBURG_REV0P9-GFNOCPU04302A
GND                      U4               BC10     EMMITSBURG_REV0P9-GFNOCPU04302A
GND                      U4               BC12     EMMITSBURG_REV0P9-GFNOCPU04302A
GND                      U4               BC14     EMMITSBURG_REV0P9-GFNOCPU04302A
GND                      U4               BC16     EMMITSBURG_REV0P9-GFNOCPU04302A
GND                      U4               BC18     EMMITSBURG_REV0P9-GFNOCPU04302A
GND                      U4               BC20     EMMITSBURG_REV0P9-GFNOCPU04302A
GND                      U4               BC22     EMMITSBURG_REV0P9-GFNOCPU04302A
GND                      U4               BC24     EMMITSBURG_REV0P9-GFNOCPU04302A
GND                      U4               BC26     EMMITSBURG_REV0P9-GFNOCPU04302A
GND                      U4               BC28     EMMITSBURG_REV0P9-GFNOCPU04302A
GND                      U4               BC30     EMMITSBURG_REV0P9-GFNOCPU04302A
GND                      U4               BC32     EMMITSBURG_REV0P9-GFNOCPU04302A
GND                      U4               BC34     EMMITSBURG_REV0P9-GFNOCPU04302A
GND                      U4               BC36     EMMITSBURG_REV0P9-GFNOCPU04302A
GND                      U4               BC38     EMMITSBURG_REV0P9-GFNOCPU04302A
GND                      U4               BC42     EMMITSBURG_REV0P9-GFNOCPU04302A
GND                      U4               BD1      EMMITSBURG_REV0P9-GFNOCPU04302A
GND                      U4               BD3      EMMITSBURG_REV0P9-GFNOCPU04302A
GND                      U4               BD5      EMMITSBURG_REV0P9-GFNOCPU04302A
GND                      U4               BD21     EMMITSBURG_REV0P9-GFNOCPU04302A
GND                      U4               BD39     EMMITSBURG_REV0P9-GFNOCPU04302A
GND                      U4               BD41     EMMITSBURG_REV0P9-GFNOCPU04302A
GND                      U4               BD43     EMMITSBURG_REV0P9-GFNOCPU04302A
GND                      U4               BE1      EMMITSBURG_REV0P9-GFNOCPU04302A
GND                      U4               BE3      EMMITSBURG_REV0P9-GFNOCPU04302A
GND                      U4               BE10     EMMITSBURG_REV0P9-GFNOCPU04302A
GND                      U4               BE34     EMMITSBURG_REV0P9-GFNOCPU04302A
GND                      U4               BE41     EMMITSBURG_REV0P9-GFNOCPU04302A
GND                      U4               BE43     EMMITSBURG_REV0P9-GFNOCPU04302A
GND                      U4               BF21     EMMITSBURG_REV0P9-GFNOCPU04302A
GND                      U4               BG4      EMMITSBURG_REV0P9-GFNOCPU04302A
GND                      U4               BG6      EMMITSBURG_REV0P9-GFNOCPU04302A
GND                      U4               BG10     EMMITSBURG_REV0P9-GFNOCPU04302A
GND                      U4               BG34     EMMITSBURG_REV0P9-GFNOCPU04302A
GND                      U4               BG38     EMMITSBURG_REV0P9-GFNOCPU04302A
GND                      U4               BG40     EMMITSBURG_REV0P9-GFNOCPU04302A
GND                      U4               BG41     EMMITSBURG_REV0P9-GFNOCPU04302A
GND                      U4               C3       EMMITSBURG_REV0P9-GFNOCPU04302A
GND                      U4               C4       EMMITSBURG_REV0P9-GFNOCPU04302A
GND                      U4               C20      EMMITSBURG_REV0P9-GFNOCPU04302A
GND                      U4               C22      EMMITSBURG_REV0P9-GFNOCPU04302A
GND                      U4               C24      EMMITSBURG_REV0P9-GFNOCPU04302A
GND                      U4               C26      EMMITSBURG_REV0P9-GFNOCPU04302A
GND                      U4               C38      EMMITSBURG_REV0P9-GFNOCPU04302A
GND                      U4               C41      EMMITSBURG_REV0P9-GFNOCPU04302A
GND                      U4               C43      EMMITSBURG_REV0P9-GFNOCPU04302A
GND                      U4               D1       EMMITSBURG_REV0P9-GFNOCPU04302A
GND                      U4               D3       EMMITSBURG_REV0P9-GFNOCPU04302A
GND                      U4               D5       EMMITSBURG_REV0P9-GFNOCPU04302A
GND                      U4               D9       EMMITSBURG_REV0P9-GFNOCPU04302A
GND                      U4               D13      EMMITSBURG_REV0P9-GFNOCPU04302A
GND                      U4               D29      EMMITSBURG_REV0P9-GFNOCPU04302A
GND                      U4               D41      EMMITSBURG_REV0P9-GFNOCPU04302A
GND                      U4               D43      EMMITSBURG_REV0P9-GFNOCPU04302A
GND                      U4               E2       EMMITSBURG_REV0P9-GFNOCPU04302A
GND                      U4               E6       EMMITSBURG_REV0P9-GFNOCPU04302A
GND                      U4               E8       EMMITSBURG_REV0P9-GFNOCPU04302A
GND                      U4               E10      EMMITSBURG_REV0P9-GFNOCPU04302A
GND                      U4               E12      EMMITSBURG_REV0P9-GFNOCPU04302A
GND                      U4               E14      EMMITSBURG_REV0P9-GFNOCPU04302A
GND                      U4               E16      EMMITSBURG_REV0P9-GFNOCPU04302A
GND                      U4               E18      EMMITSBURG_REV0P9-GFNOCPU04302A
GND                      U4               E20      EMMITSBURG_REV0P9-GFNOCPU04302A
GND                      U4               E22      EMMITSBURG_REV0P9-GFNOCPU04302A
GND                      U4               E24      EMMITSBURG_REV0P9-GFNOCPU04302A
GND                      U4               E26      EMMITSBURG_REV0P9-GFNOCPU04302A
GND                      U4               E28      EMMITSBURG_REV0P9-GFNOCPU04302A
GND                      U4               E30      EMMITSBURG_REV0P9-GFNOCPU04302A
GND                      U4               E32      EMMITSBURG_REV0P9-GFNOCPU04302A
GND                      U4               E34      EMMITSBURG_REV0P9-GFNOCPU04302A
GND                      U4               E36      EMMITSBURG_REV0P9-GFNOCPU04302A
GND                      U4               E38      EMMITSBURG_REV0P9-GFNOCPU04302A
GND                      U4               E40      EMMITSBURG_REV0P9-GFNOCPU04302A
GND                      U4               E42      EMMITSBURG_REV0P9-GFNOCPU04302A
GND                      U4               F15      EMMITSBURG_REV0P9-GFNOCPU04302A
GND                      U4               F24      EMMITSBURG_REV0P9-GFNOCPU04302A
GND                      U4               F31      EMMITSBURG_REV0P9-GFNOCPU04302A
GND                      U4               F34      EMMITSBURG_REV0P9-GFNOCPU04302A
GND                      U4               F39      EMMITSBURG_REV0P9-GFNOCPU04302A
GND                      U4               F41      EMMITSBURG_REV0P9-GFNOCPU04302A
GND                      U4               F43      EMMITSBURG_REV0P9-GFNOCPU04302A
GND                      U4               G13      EMMITSBURG_REV0P9-GFNOCPU04302A
GND                      U4               G20      EMMITSBURG_REV0P9-GFNOCPU04302A
GND                      U4               G26      EMMITSBURG_REV0P9-GFNOCPU04302A
GND                      U4               H5       EMMITSBURG_REV0P9-GFNOCPU04302A
GND                      U4               H8       EMMITSBURG_REV0P9-GFNOCPU04302A
GND                      U4               H39      EMMITSBURG_REV0P9-GFNOCPU04302A
GND                      U4               J13      EMMITSBURG_REV0P9-GFNOCPU04302A
GND                      U4               J20      EMMITSBURG_REV0P9-GFNOCPU04302A
GND                      U4               J26      EMMITSBURG_REV0P9-GFNOCPU04302A
GND                      U4               K5       EMMITSBURG_REV0P9-GFNOCPU04302A
GND                      U4               K11      EMMITSBURG_REV0P9-GFNOCPU04302A
GND                      U4               K15      EMMITSBURG_REV0P9-GFNOCPU04302A
GND                      U4               K24      EMMITSBURG_REV0P9-GFNOCPU04302A
GND                      U4               K34      EMMITSBURG_REV0P9-GFNOCPU04302A
GND                      U4               K39      EMMITSBURG_REV0P9-GFNOCPU04302A
GND                      U4               L10      EMMITSBURG_REV0P9-GFNOCPU04302A
GND                      U4               L16      EMMITSBURG_REV0P9-GFNOCPU04302A
GND                      U4               L20      EMMITSBURG_REV0P9-GFNOCPU04302A
GND                      U4               L23      EMMITSBURG_REV0P9-GFNOCPU04302A
GND                      U4               L26      EMMITSBURG_REV0P9-GFNOCPU04302A
GND                      U4               L29      EMMITSBURG_REV0P9-GFNOCPU04302A
GND                      U4               L36      EMMITSBURG_REV0P9-GFNOCPU04302A
GND                      U4               M1       EMMITSBURG_REV0P9-GFNOCPU04302A
GND                      U4               M3       EMMITSBURG_REV0P9-GFNOCPU04302A
GND                      U4               M5       EMMITSBURG_REV0P9-GFNOCPU04302A
GND                      U4               M11      EMMITSBURG_REV0P9-GFNOCPU04302A
GND                      U4               M15      EMMITSBURG_REV0P9-GFNOCPU04302A
GND                      U4               M18      EMMITSBURG_REV0P9-GFNOCPU04302A
GND                      U4               M21      EMMITSBURG_REV0P9-GFNOCPU04302A
GND                      U4               M28      EMMITSBURG_REV0P9-GFNOCPU04302A
GND                      U4               M31      EMMITSBURG_REV0P9-GFNOCPU04302A
GND                      U4               M34      EMMITSBURG_REV0P9-GFNOCPU04302A
GND                      U4               M37      EMMITSBURG_REV0P9-GFNOCPU04302A
GND                      U4               M39      EMMITSBURG_REV0P9-GFNOCPU04302A
GND                      U4               N16      EMMITSBURG_REV0P9-GFNOCPU04302A
GND                      U4               N32      EMMITSBURG_REV0P9-GFNOCPU04302A
GND                      U4               P5       EMMITSBURG_REV0P9-GFNOCPU04302A
GND                      U4               P8       EMMITSBURG_REV0P9-GFNOCPU04302A
GND                      U4               P11      EMMITSBURG_REV0P9-GFNOCPU04302A
GND                      U4               P24      EMMITSBURG_REV0P9-GFNOCPU04302A
GND                      U4               P28      EMMITSBURG_REV0P9-GFNOCPU04302A
GND                      U4               P31      EMMITSBURG_REV0P9-GFNOCPU04302A
GND                      U4               P37      EMMITSBURG_REV0P9-GFNOCPU04302A
GND                      U4               P39      EMMITSBURG_REV0P9-GFNOCPU04302A
GND                      U4               P41      EMMITSBURG_REV0P9-GFNOCPU04302A
GND                      U4               P43      EMMITSBURG_REV0P9-GFNOCPU04302A
GND                      U4               R13      EMMITSBURG_REV0P9-GFNOCPU04302A
GND                      U4               R16      EMMITSBURG_REV0P9-GFNOCPU04302A
GND                      U4               R20      EMMITSBURG_REV0P9-GFNOCPU04302A
GND                      U4               R36      EMMITSBURG_REV0P9-GFNOCPU04302A
GND                      U4               T31      EMMITSBURG_REV0P9-GFNOCPU04302A
GND                      U4               U5       EMMITSBURG_REV0P9-GFNOCPU04302A
GND                      U4               U10      EMMITSBURG_REV0P9-GFNOCPU04302A
GND                      U4               U13      EMMITSBURG_REV0P9-GFNOCPU04302A
GND                      U4               U25      EMMITSBURG_REV0P9-GFNOCPU04302A
GND                      U4               U39      EMMITSBURG_REV0P9-GFNOCPU04302A
GND                      U4               V2       EMMITSBURG_REV0P9-GFNOCPU04302A
GND                      U4               V31      EMMITSBURG_REV0P9-GFNOCPU04302A
GND                      U4               W3       EMMITSBURG_REV0P9-GFNOCPU04302A
GND                      U4               W5       EMMITSBURG_REV0P9-GFNOCPU04302A
GND                      U4               W25      EMMITSBURG_REV0P9-GFNOCPU04302A
GND                      U4               W39      EMMITSBURG_REV0P9-GFNOCPU04302A
GND                      U4               Y8       EMMITSBURG_REV0P9-GFNOCPU04302A
GND                      U4               Y11      EMMITSBURG_REV0P9-GFNOCPU04302A
GND                      U4               Y15      EMMITSBURG_REV0P9-GFNOCPU04302A
GND                      U4               Y31      EMMITSBURG_REV0P9-GFNOCPU04302A
GND                      U4               Y34      EMMITSBURG_REV0P9-GFNOCPU04302A
GND                      U10              8        PCA9546APWR-PCA9546APWR,SMLF,IA
GND                      U13              A14      9SQ440NQQI8-9SQ440NQQI8,SMLF,IA
GND                      U13              B10      9SQ440NQQI8-9SQ440NQQI8,SMLF,IA
GND                      U13              B12      9SQ440NQQI8-9SQ440NQQI8,SMLF,IA
GND                      U13              C1       9SQ440NQQI8-9SQ440NQQI8,SMLF,IA
GND                      U14              8        IDTQS3VH257QG_SMLF-IDTQS3VH257A
GND                      U15              8        IDTQS3VH257QG_SMLF-IDTQS3VH257A
GND                      U16              3        NC7SZ66M5X_SMLF-NC7SZ66M5X,NC7A
GND                      U17              7        74CBTLV3126PW-74CBTLV3126PW,SMA
GND                      U18              7        74CBTLV3126PW-74CBTLV3126PW,SMA
GND                      U19              S        MOSFET_N_SMLF-BSS138K,BSS138K,A
GND                      U21              2        NC7SB3157_SMLF-NC7SB3157P6X,NCA
GND                      U22              2        NC7SB3157_SMLF-NC7SB3157P6X,NCA
GND                      U23              3        74LVC1G02GW_SMLF-74LVC1G02GW,IA
GND                      U24              12       PCA9548APW-PCA9548APW,SMLF,IC,A
GND                      U27              2        TPS2553DBVR1-TPS2553DBVR-1,SMLA
GND                      U28              4        PCA9617ADP-PCA9617ADP,SMLF,IC,A
GND                      U29              4        PCA9617ADP-PCA9617ADP,SMLF,IC,A
GND                      U30              4        PCA9617ADP-PCA9617ADP,SMLF,IC,A
GND                      U31              4        PCA9617ADP-PCA9617ADP,SMLF,IC,A
GND                      U36              8        PCA9546APWR-PCA9546APWR,SMLF,IA
GND                      U38              TH       9QXL2001BNHGI8-9QXL2001BNHGI8,A
GND                      U40              8        TPS259520DSGR-TPS259520DSGR,SMA
GND                      U40              TH       TPS259520DSGR-TPS259520DSGR,SMA
GND                      U49              S        MOSFET_N_SMLF-BSS138K,BSS138K,A
GND                      U50              3        SN74LVC1G08DBVR_SMLF-SN74LVC1GA
GND                      U51              12       PCA9555PW_SMLF-PCA9555PW,IC,TMA
GND                      U52              1        APX80929SAG7-APX809-29SAG-7,SMA
GND                      U53              3        SN74LVC1G08DBVR_SMLF-SN74LVC1GA
GND                      U54              3        74LVC1G07GV-74LVC1G07GV,SMLF,IA
GND                      U56              8        TPS259520DSGR-TPS259520DSGR,SMA
GND                      U56              TH       TPS259520DSGR-TPS259520DSGR,SMA
GND                      U57              4        TPS259824ONRGER-TPS259824ONRGEA
GND                      U57              5        TPS259824ONRGER-TPS259824ONRGEA
GND                      U57              14       TPS259824ONRGER-TPS259824ONRGEA
GND                      U57              26       TPS259824ONRGER-TPS259824ONRGEA
GND                      U58              2        SN74LVC2G07DCKR_SMLF-SN74LVC2GA
GND                      U59              2        SN74LVC2G07DCKR_SMLF-SN74LVC2GA
GND                      U60              2        NC7SB3157_SMLF-NC7SB3157P6X,NCA
GND                      U61              2        NC7SB3157_SMLF-NC7SB3157P6X,NCA
GND                      U63              4        TMP75AIDR-TMP75AIDR,SMLF,IC,ALA
GND                      U64              4        M24128BWDW6TP-M24128-BWDW6TP,SA
GND                      U65              4        TMP75AIDR-TMP75AIDR,SMLF,IC,ALA
GND                      U66              3        74HC1G126GW-74HC1G126GW,SMLF,IA
GND                      U67              7        74CBTLV3126PW-74CBTLV3126PW,SMA
GND                      U68              7        74CBTLV3126PW-74CBTLV3126PW,SMA
GND                      U70              S        MOSFET_N_SMLF-BSS138K,BSS138K,A
GND                      U75              3        SN74LVC1G17DCKR-SN74LVC1G17DCKA
GND                      U77              7        74CBTLV3126PW-74CBTLV3126PW,SMB
GND                      U79              4        SLG55221120010VTR-SLG55221-120A
GND                      U79              TH       SLG55221120010VTR-SLG55221-120A
GND                      U81              6        MP5981GLUZ-MP5981GLU-Z,SMLF,ICA
GND                      U81              7        MP5981GLUZ-MP5981GLU-Z,SMLF,ICA
GND                      U81              17       MP5981GLUZ-MP5981GLU-Z,SMLF,ICA
GND                      U81              20       MP5981GLUZ-MP5981GLU-Z,SMLF,ICA
GND                      U81              TH       MP5981GLUZ-MP5981GLU-Z,SMLF,ICA
GND                      U82              3        74LVC1G126GW_SMLF-74LVC1G126GWA
GND                      U83              7        GTL2014PW-GTL2014PW,SMLF,IC,ALA
GND                      U83              8        GTL2014PW-GTL2014PW,SMLF,IC,ALA
GND                      U83              11       GTL2014PW-GTL2014PW,SMLF,IC,ALA
GND                      U84              7        GTL2014PW-GTL2014PW,SMLF,IC,ALA
GND                      U84              8        GTL2014PW-GTL2014PW,SMLF,IC,ALA
GND                      U84              11       GTL2014PW-GTL2014PW,SMLF,IC,ALA
GND                      U85              2        NC7SB3157_SMLF-NC7SB3157P6X,NCA
GND                      U86              7        74CBTLV3126PW-74CBTLV3126PW,SMA
GND                      U89              S        MOSFET_N_SMLF-BSS138K,BSS138K,A
GND                      U90              4        PI6CV304LE-PI6CV304LE,SMLF,IC,A
GND                      U94              2        ADM1086AKSZREEL7-ADM1086AKSZ-RA
GND                      U95              3        SN74LVC1G07DCKR-SN74LVC1G07DCKA
GND                      U96              5        TS3A24157RSER-TS3A24157RSER,SMA
GND                      U97              5        TS3A24157RSER-TS3A24157RSER,SMA
GND                      U98              1        PCA9306DCTR-PCA9306DCTR,SMLF,IA
GND                      U99              2        RT9818C44GV-RT9818C-44GV,SMLF,A
GND                      U101             3        SN74LVC1G17DCKR-SN74LVC1G17DCKA
GND                      U102             1        MAX9634FEUKT-MAX9634FEUK+T,SMLA
GND                      U102             2        MAX9634FEUKT-MAX9634FEUK+T,SMLA
GND                      U103             1        MAX9634FEUKT-MAX9634FEUK+T,SMLA
GND                      U103             2        MAX9634FEUKT-MAX9634FEUK+T,SMLA
GND                      U104             3        74LVC1G07GV-74LVC1G07GV,SMLF,IA
GND                      U105             3        ADS1015IDGSR-ADS1015IDGSR,SMLFA
GND                      U107             6        MP5981GLUZ-MP5981GLU-Z,SMLF,ICA
GND                      U107             7        MP5981GLUZ-MP5981GLU-Z,SMLF,ICA
GND                      U107             17       MP5981GLUZ-MP5981GLU-Z,SMLF,ICA
GND                      U107             20       MP5981GLUZ-MP5981GLU-Z,SMLF,ICA
GND                      U107             TH       MP5981GLUZ-MP5981GLU-Z,SMLF,ICA
GND                      U117             2        TPS3897PDRYR-TPS3897PDRYR,SMLFA
GND                      U121             7        MAX11607EUAT-MAX11607EUA+T,SMLA
GND                      U122             A1       10M04SAU324I7G-10M04SAU324I7G,A
GND                      U122             A18      10M04SAU324I7G-10M04SAU324I7G,A
GND                      U122             B6       10M04SAU324I7G-10M04SAU324I7G,A
GND                      U122             B10      10M04SAU324I7G-10M04SAU324I7G,A
GND                      U122             B15      10M04SAU324I7G-10M04SAU324I7G,A
GND                      U122             D3       10M04SAU324I7G-10M04SAU324I7G,A
GND                      U122             E3       10M04SAU324I7G-10M04SAU324I7G,A
GND                      U122             E6       10M04SAU324I7G-10M04SAU324I7G,A
GND                      U122             E10      10M04SAU324I7G-10M04SAU324I7G,A
GND                      U122             E13      10M04SAU324I7G-10M04SAU324I7G,A
GND                      U122             F8       10M04SAU324I7G-10M04SAU324I7G,A
GND                      U122             F17      10M04SAU324I7G-10M04SAU324I7G,A
GND                      U122             G2       10M04SAU324I7G-10M04SAU324I7G,A
GND                      U122             G4       10M04SAU324I7G-10M04SAU324I7G,A
GND                      U122             H14      10M04SAU324I7G-10M04SAU324I7G,A
GND                      U122             J10      10M04SAU324I7G-10M04SAU324I7G,A
GND                      U122             J17      10M04SAU324I7G-10M04SAU324I7G,A
GND                      U122             K6       10M04SAU324I7G-10M04SAU324I7G,A
GND                      U122             K9       10M04SAU324I7G-10M04SAU324I7G,A
GND                      U122             K13      10M04SAU324I7G-10M04SAU324I7G,A
GND                      U122             L4       10M04SAU324I7G-10M04SAU324I7G,A
GND                      U122             M14      10M04SAU324I7G-10M04SAU324I7G,A
GND                      U122             N2       10M04SAU324I7G-10M04SAU324I7G,A
GND                      U122             N5       10M04SAU324I7G-10M04SAU324I7G,A
GND                      U122             N10      10M04SAU324I7G-10M04SAU324I7G,A
GND                      U122             N12      10M04SAU324I7G-10M04SAU324I7G,A
GND                      U122             N17      10M04SAU324I7G-10M04SAU324I7G,A
GND                      U122             R7       10M04SAU324I7G-10M04SAU324I7G,A
GND                      U122             U4       10M04SAU324I7G-10M04SAU324I7G,A
GND                      U122             U10      10M04SAU324I7G-10M04SAU324I7G,A
GND                      U122             U14      10M04SAU324I7G-10M04SAU324I7G,A
GND                      U122             V1       10M04SAU324I7G-10M04SAU324I7G,A
GND                      U122             V18      10M04SAU324I7G-10M04SAU324I7G,A
GND                      U123             8        TPS259520DSGR-TPS259520DSGR,SMA
GND                      U123             TH       TPS259520DSGR-TPS259520DSGR,SMA
GND                      U124             8        TPS259520DSGR-TPS259520DSGR,SMA
GND                      U124             TH       TPS259520DSGR-TPS259520DSGR,SMA
GND                      U125             8        TPS259520DSGR-TPS259520DSGR,SMA
GND                      U125             TH       TPS259520DSGR-TPS259520DSGR,SMA
GND                      U126             8        TPS259540DSGR-TPS259540DSGR,SMA
GND                      U126             TH       TPS259540DSGR-TPS259540DSGR,SMA
GND                      U127             8        TPS259540DSGR-TPS259540DSGR,SMA
GND                      U127             TH       TPS259540DSGR-TPS259540DSGR,SMA
GND                      U128             8        TPS259540DSGR-TPS259540DSGR,SMA
GND                      U128             TH       TPS259540DSGR-TPS259540DSGR,SMA
GND                      U129             8        TPS259540DSGR-TPS259540DSGR,SMA
GND                      U129             TH       TPS259540DSGR-TPS259540DSGR,SMA
GND                      U130             12       PCA9555PW_SMLF-PCA9555PW,IC,TMA
GND                      U131             12       PCA9555PW_SMLF-PCA9555PW,IC,TMA
GND                      U132             2        SN74LVC2G17DCKR-SN74LVC2G17DCKA
GND                      U133             2        SN74LVC2G17DCKR-SN74LVC2G17DCKA
GND                      U134             2        SN74LVC2G07DCKR_SMLF-SN74LVC2GA
GND                      U135             2        SN74LVC2G07DCKR_SMLF-SN74LVC2GA
GND                      U136             2        SN74LVC2G07DCKR_SMLF-SN74LVC2GA
GND                      U137             2        SN74LVC2G07DCKR_SMLF-SN74LVC2GA
GND                      U138             8        TPS259540DSGR-TPS259540DSGR,SMA
GND                      U138             TH       TPS259540DSGR-TPS259540DSGR,SMA
GND                      U141             8        PCA9546APWR-PCA9546APWR,SMLF,IA
GND                      Y2               2        Q_XTAL_4P_13_SMLF-25MHZ,IC,BG6A
GND                      Y2               4        Q_XTAL_4P_13_SMLF-25MHZ,IC,BG6A
GND                      Y3               2        Q_XTAL_4P_13BI_24GND-25MHZ,SMLA
GND                      Y3               4        Q_XTAL_4P_13BI_24GND-25MHZ,SMLA
HP_LVC3_OCP_V3_1_ATTN_OUT_SW_N R1147            2        Q_RES_0402LF-0,5%,1/16W,CHIP,CA
HP_LVC3_OCP_V3_1_ATTN_OUT_SW_N R1149            2        Q_RES_0402LF-10K,1%,1/16W,CHIPA
HP_LVC3_OCP_V3_1_ATTN_OUT_SW_N U51              7        PCA9555PW_SMLF-PCA9555PW,IC,TMA
HP_LVC3_OCP_V3_1_EN      U50              4        SN74LVC1G08DBVR_SMLF-SN74LVC1GA
HP_LVC3_OCP_V3_1_EN      U56              2        TPS259520DSGR-TPS259520DSGR,SMA
HP_LVC3_OCP_V3_1_EN      U57              6        TPS259824ONRGER-TPS259824ONRGEA
HP_LVC3_OCP_V3_1_FAULT_N R1143            2        Q_RES_0402LF-10K,1%,1/16W,CHIPA
HP_LVC3_OCP_V3_1_FAULT_N U51              9        PCA9555PW_SMLF-PCA9555PW,IC,TMA
HP_LVC3_OCP_V3_1_FAULT_N U56              6        TPS259520DSGR-TPS259520DSGR,SMA
HP_LVC3_OCP_V3_1_HSC_PWRGD Q45              2        MOSFET_NCH_DUAL-2N7002KDW,SMLFA
HP_LVC3_OCP_V3_1_HSC_PWRGD R429             1        Q_RES_0402LF-0,5%,1/16W,CHIP,CA
HP_LVC3_OCP_V3_1_HSC_PWRGD R1146            2        Q_RES_0402LF-1K,1%,1/16W,CHIP,A
HP_LVC3_OCP_V3_1_HSC_PWRGD U57              13       TPS259824ONRGER-TPS259824ONRGEA
HP_LVC3_OCP_V3_1_PRSNT2  R1129            2        Q_RES_0402LF-1K,5%,1/16W,CHIP,A
HP_LVC3_OCP_V3_1_PRSNT2  U49              D        MOSFET_N_SMLF-BSS138K,BSS138K,A
HP_LVC3_OCP_V3_1_PRSNT2  U50              2        SN74LVC1G08DBVR_SMLF-SN74LVC1GA
HP_LVC3_OCP_V3_1_PRSNT2_N R112             2        Q_RES_0402LF-10K,1%,1/16W,EMPTA
HP_LVC3_OCP_V3_1_PRSNT2_N R1148            2        Q_RES_0402LF-0,5%,1/16W,CHIP,CA
HP_LVC3_OCP_V3_1_PRSNT2_N R1150            2        Q_RES_0402LF-10K,1%,1/16W,CHIPA
HP_LVC3_OCP_V3_1_PRSNT2_N R1543            1        Q_RES_0402LF-0,5%,1/16W,CHIP,CA
HP_LVC3_OCP_V3_1_PRSNT2_N U49              G        MOSFET_N_SMLF-BSS138K,BSS138K,A
HP_LVC3_OCP_V3_1_PRSNT2_N U51              8        PCA9555PW_SMLF-PCA9555PW,IC,TMA
HP_LVC3_OCP_V3_1_PRSNT2_N_R R1147            1        Q_RES_0402LF-0,5%,1/16W,CHIP,CA
HP_LVC3_OCP_V3_1_PRSNT2_N_R R1148            1        Q_RES_0402LF-0,5%,1/16W,CHIP,CA
HP_LVC3_OCP_V3_1_PRSNT2_N_R U58              4        SN74LVC2G07DCKR_SMLF-SN74LVC2GA
HP_LVC3_OCP_V3_1_PRSNT2_N_R U58              6        SN74LVC2G07DCKR_SMLF-SN74LVC2GA
HP_LVC3_OCP_V3_1_PRSNT2_N_R U59              4        SN74LVC2G07DCKR_SMLF-SN74LVC2GA
HP_LVC3_OCP_V3_1_PRSNT2_N_R U59              6        SN74LVC2G07DCKR_SMLF-SN74LVC2GA
HP_LVC3_OCP_V3_1_PWRGD   Q45              3        MOSFET_NCH_DUAL-2N7002KDW,SMLFA
HP_LVC3_OCP_V3_1_PWRGD   R1132            2        Q_RES_0402LF-1K,5%,1/16W,EMPTYA
HP_LVC3_OCP_V3_1_PWRGD   U52              2        APX80929SAG7-APX809-29SAG-7,SMA
HP_LVC3_OCP_V3_1_PWRGD   U53              1        SN74LVC1G08DBVR_SMLF-SN74LVC1GA
HP_LVC3_OCP_V3_1_PWRGD_N Q45              5        MOSFET_NCH_DUAL-2N7002KDW,SMLFA
HP_LVC3_OCP_V3_1_PWRGD_N Q45              6        MOSFET_NCH_DUAL-2N7002KDW,SMLFA
HP_LVC3_OCP_V3_1_PWRGD_N R1133            2        Q_RES_0402LF-10K,1%,1/16W,CHIPA
HP_OCP_V3_1_EN           U50              1        SN74LVC1G08DBVR_SMLF-SN74LVC1GA
HP_OCP_V3_1_EN           U51              6        PCA9555PW_SMLF-PCA9555PW,IC,TMA
H_CPU0_BMCINIT_LVC1      R278             2        Q_RES_0402LF-240,1%,1/16W,EMPTA
H_CPU0_BMCINIT_LVC1      U2               BN23     SOCKET4677_AZIFS054P001C01-SOCA
H_CPU0_CATERR_LVC1_R_N   R297             1        Q_RES_0402LF-0,5%,1/16W,CHIP,CA
H_CPU0_CATERR_LVC1_R_N   U2               BP24     SOCKET4677_AZIFS054P001C01-SOCA
H_CPU0_ERR0_LVC1_R_N     R336             1        Q_RES_0402LF-0,5%,1/16W,CHIP,CA
H_CPU0_ERR0_LVC1_R_N     U2               BF22     SOCKET4677_AZIFS054P001C01-SOCA
H_CPU0_ERR1_LVC1_R_N     R340             1        Q_RES_0402LF-0,5%,1/16W,CHIP,CA
H_CPU0_ERR1_LVC1_R_N     U2               AY22     SOCKET4677_AZIFS054P001C01-SOCA
H_CPU0_ERR2_LVC1_R_N     R344             1        Q_RES_0402LF-0,5%,1/16W,CHIP,CA
H_CPU0_ERR2_LVC1_R_N     U2               BD22     SOCKET4677_AZIFS054P001C01-SOCA
H_CPU0_MEMHOT_IN_LVC1_N  R208             2        Q_RES_0402LF-0,5%,1/16W,CHIP,CA
H_CPU0_MEMHOT_IN_LVC1_N  R219             2        Q_RES_0402LF-100,1%,1/16W,EMPTA
H_CPU0_MEMHOT_IN_LVC1_N  U2               AU21     SOCKET4677_AZIFS054P001C01-SOCA
H_CPU0_MEMHOT_IN_LVC1_R_N R208             1        Q_RES_0402LF-0,5%,1/16W,CHIP,CA
H_CPU0_MEMHOT_IN_LVC1_R_N U122             T8       10M04SAU324I7G-10M04SAU324I7G,A
H_CPU0_MEMHOT_OUT_LVC1_N R203             2        Q_RES_0402LF-33,5%,1/16W,CHIP,A
H_CPU0_MEMHOT_OUT_LVC1_N R1425            1        Q_RES_0402LF-100,1%,1/16W,CHIPA
H_CPU0_MEMHOT_OUT_LVC1_N U122             T9       10M04SAU324I7G-10M04SAU324I7G,A
H_CPU0_MEMHOT_OUT_LVC1_R_N R199             2        Q_RES_0402LF-100,1%,1/16W,EMPTA
H_CPU0_MEMHOT_OUT_LVC1_R_N R203             1        Q_RES_0402LF-33,5%,1/16W,CHIP,A
H_CPU0_MEMHOT_OUT_LVC1_R_N U2               CF26     SOCKET4677_AZIFS054P001C01-SOCA
H_CPU0_MEMTRIP_LVC1_N    R205             2        Q_RES_0402LF-33,5%,1/16W,CHIP,A
H_CPU0_MEMTRIP_LVC1_N    R1429            1        Q_RES_0402LF-100,1%,1/16W,CHIPA
H_CPU0_MEMTRIP_LVC1_N    U122             V4       10M04SAU324I7G-10M04SAU324I7G,A
H_CPU0_MEMTRIP_LVC1_R_N  R200             2        Q_RES_0402LF-100,1%,1/16W,EMPTA
H_CPU0_MEMTRIP_LVC1_R_N  R205             1        Q_RES_0402LF-33,5%,1/16W,CHIP,A
H_CPU0_MEMTRIP_LVC1_R_N  U2               AV24     SOCKET4677_AZIFS054P001C01-SOCA
H_CPU0_MON_FAIL_LVC1_R_N R100             1        Q_RES_0402LF-33,5%,1/16W,CHIP,A
H_CPU0_MON_FAIL_LVC1_R_N R1956            1        Q_RES_0402LF-100,1%,1/16W,CHIPA
H_CPU0_MON_FAIL_LVC1_R_N U2               BR23     SOCKET4677_AZIFS054P001C01-SOCA
H_CPU0_MON_FAIL_PLD_LVC1_N R100             2        Q_RES_0402LF-33,5%,1/16W,CHIP,A
H_CPU0_MON_FAIL_PLD_LVC1_N U122             V5       10M04SAU324I7G-10M04SAU324I7G,A
H_CPU0_NMI_LVC1_N        R195             2        Q_RES_0402LF-49.9     ,1%  ,1/A
H_CPU0_NMI_LVC1_N        R197             2        Q_RES_0402LF-10K,1%,1/16W,EMPTA
H_CPU0_NMI_LVC1_N        U2               AV18     SOCKET4677_AZIFS054P001C01-SOCA
H_CPU0_PMDOWN_CPU1       R11              1        Q_RES_0402LF-33.2,1%,1/16W,CHIA
H_CPU0_PMDOWN_CPU1       U1               CN25     SOCKET4677_AZIFS054P001C01-SOCA
H_CPU0_PMDOWN_CPU1_R     R11              2        Q_RES_0402LF-33.2,1%,1/16W,CHIA
H_CPU0_PMDOWN_CPU1_R     U2               CW39     SOCKET4677_AZIFS054P001C01-SOCA
H_CPU0_PMDOWN_PCH        R7               2        Q_RES_0402LF-33.2,1%,1/16W,CHIA
H_CPU0_PMDOWN_PCH        U4               AE7      EMMITSBURG_REV0P9-GFNOCPU04302A
H_CPU0_PMDOWN_PCH_R      R7               1        Q_RES_0402LF-33.2,1%,1/16W,CHIA
H_CPU0_PMDOWN_PCH_R      R1959            2        Q_RES_0402LF-0,5%,1/16W,CHIP,CA
H_CPU0_PMDOWN_PCH_R2     R1959            1        Q_RES_0402LF-0,5%,1/16W,CHIP,CA
H_CPU0_PMDOWN_PCH_R2     U2               CY40     SOCKET4677_AZIFS054P001C01-SOCA
H_CPU0_PMSYNC_CPU1       R322             2        Q_RES_0402LF-33.2,1%,1/16W,CHIA
H_CPU0_PMSYNC_CPU1       U1               CW39     SOCKET4677_AZIFS054P001C01-SOCA
H_CPU0_PMSYNC_CPU1_R     R322             1        Q_RES_0402LF-33.2,1%,1/16W,CHIA
H_CPU0_PMSYNC_CPU1_R     U2               CN25     SOCKET4677_AZIFS054P001C01-SOCA
H_CPU0_PMSYNC_PCH        R10              2        Q_RES_0402LF-33.2,1%,1/16W,CHIA
H_CPU0_PMSYNC_PCH        U2               DA39     SOCKET4677_AZIFS054P001C01-SOCA
H_CPU0_PMSYNC_PCH_R      R10              1        Q_RES_0402LF-33.2,1%,1/16W,CHIA
H_CPU0_PMSYNC_PCH_R      R1960            2        Q_RES_0402LF-0,5%,1/16W,CHIP,CA
H_CPU0_PMSYNC_PCH_R2     R1960            1        Q_RES_0402LF-0,5%,1/16W,CHIP,CA
H_CPU0_PMSYNC_PCH_R2     U4               AF8      EMMITSBURG_REV0P9-GFNOCPU04302A
H_CPU0_PM_FAST_WAKE_N    R1240            1        Q_RES_0402LF-0,5%,1/16W,CHIP,CA
H_CPU0_PM_FAST_WAKE_N    U2               CP20     SOCKET4677_AZIFS054P001C01-SOCA
H_CPU0_PRDY_QS_GTL_R_N   R1               2        Q_RES_0402LF-10,1%,1/16W,CHIP,A
H_CPU0_PRDY_QS_GTL_R_N   U2               BP26     SOCKET4677_AZIFS054P001C01-SOCA
H_CPU0_PREQ_QS_GTL_R_N   R2               2        Q_RES_0402LF-100,1%,1/16W,CHIPA
H_CPU0_PREQ_QS_GTL_R_N   U2               AV22     SOCKET4677_AZIFS054P001C01-SOCA
H_CPU0_PROCHOT_LVC1_N    R239             2        Q_RES_0402LF-0,5%,1/16W,CHIP,CA
H_CPU0_PROCHOT_LVC1_N    R243             2        Q_RES_0402LF-100,1%,1/16W,EMPTA
H_CPU0_PROCHOT_LVC1_N    U2               AU19     SOCKET4677_AZIFS054P001C01-SOCA
H_CPU0_PROCHOT_LVC1_R_N  R239             1        Q_RES_0402LF-0,5%,1/16W,CHIP,CA
H_CPU0_PROCHOT_LVC1_R_N  U122             R6       10M04SAU324I7G-10M04SAU324I7G,A
H_CPU0_RMCA_LVC1_R_N     R302             1        Q_RES_0402LF-33.2,1%,1/16W,CHIA
H_CPU0_RMCA_LVC1_R_N     U2               BH22     SOCKET4677_AZIFS054P001C01-SOCA
H_CPU0_THERMTRIP_LVC1_N  R237             2        Q_RES_0402LF-0,5%,1/16W,CHIP,CA
H_CPU0_THERMTRIP_LVC1_N  R241             2        Q_RES_0402LF-1K,1%,1/16W,EMPTYA
H_CPU0_THERMTRIP_LVC1_N  R1427            1        Q_RES_0402LF-100,1%,1/16W,CHIPA
H_CPU0_THERMTRIP_LVC1_N  U122             T10      10M04SAU324I7G-10M04SAU324I7G,A
H_CPU0_THERMTRIP_LVC1_R_N R237             1        Q_RES_0402LF-0,5%,1/16W,CHIP,CA
H_CPU0_THERMTRIP_LVC1_R_N U2               BL62     SOCKET4677_AZIFS054P001C01-SOCA
H_CPU1_BMCINIT_LVC1      R264             2        Q_RES_0402LF-240,1%,1/16W,EMPTA
H_CPU1_BMCINIT_LVC1      U1               BN23     SOCKET4677_AZIFS054P001C01-SOCA
H_CPU1_CATERR_LVC1_R_N   R299             1        Q_RES_0402LF-0,5%,1/16W,CHIP,CA
H_CPU1_CATERR_LVC1_R_N   U1               BP24     SOCKET4677_AZIFS054P001C01-SOCA
H_CPU1_ERR0_LVC1_R_N     R337             1        Q_RES_0402LF-0,5%,1/16W,CHIP,CA
H_CPU1_ERR0_LVC1_R_N     U1               BF22     SOCKET4677_AZIFS054P001C01-SOCA
H_CPU1_ERR1_LVC1_R_N     R341             1        Q_RES_0402LF-0,5%,1/16W,CHIP,CA
H_CPU1_ERR1_LVC1_R_N     U1               AY22     SOCKET4677_AZIFS054P001C01-SOCA
H_CPU1_ERR2_LVC1_R_N     R345             1        Q_RES_0402LF-0,5%,1/16W,CHIP,CA
H_CPU1_ERR2_LVC1_R_N     U1               BD22     SOCKET4677_AZIFS054P001C01-SOCA
H_CPU1_MEMHOT_IN_LVC1_N  R210             2        Q_RES_0402LF-0,5%,1/16W,CHIP,CA
H_CPU1_MEMHOT_IN_LVC1_N  R220             2        Q_RES_0402LF-100,1%,1/16W,EMPTA
H_CPU1_MEMHOT_IN_LVC1_N  U1               AU21     SOCKET4677_AZIFS054P001C01-SOCA
H_CPU1_MEMHOT_IN_LVC1_R_N R210             1        Q_RES_0402LF-0,5%,1/16W,CHIP,CA
H_CPU1_MEMHOT_IN_LVC1_R_N U122             V6       10M04SAU324I7G-10M04SAU324I7G,A
H_CPU1_MEMHOT_OUT_LVC1_N R204             2        Q_RES_0402LF-33,5%,1/16W,CHIP,A
H_CPU1_MEMHOT_OUT_LVC1_N R1426            1        Q_RES_0402LF-100,1%,1/16W,CHIPA
H_CPU1_MEMHOT_OUT_LVC1_N U122             V7       10M04SAU324I7G-10M04SAU324I7G,A
H_CPU1_MEMHOT_OUT_LVC1_R_N R201             2        Q_RES_0402LF-100,1%,1/16W,EMPTA
H_CPU1_MEMHOT_OUT_LVC1_R_N R204             1        Q_RES_0402LF-33,5%,1/16W,CHIP,A
H_CPU1_MEMHOT_OUT_LVC1_R_N U1               CF26     SOCKET4677_AZIFS054P001C01-SOCA
H_CPU1_MEMTRIP_LVC1_N    R206             2        Q_RES_0402LF-33,5%,1/16W,CHIP,A
H_CPU1_MEMTRIP_LVC1_N    R1430            1        Q_RES_0402LF-100,1%,1/16W,CHIPA
H_CPU1_MEMTRIP_LVC1_N    U122             V8       10M04SAU324I7G-10M04SAU324I7G,A
H_CPU1_MEMTRIP_LVC1_R_N  R202             2        Q_RES_0402LF-100,1%,1/16W,EMPTA
H_CPU1_MEMTRIP_LVC1_R_N  R206             1        Q_RES_0402LF-33,5%,1/16W,CHIP,A
H_CPU1_MEMTRIP_LVC1_R_N  U1               AV24     SOCKET4677_AZIFS054P001C01-SOCA
H_CPU1_MON_FAIL_LVC1_R_N R104             1        Q_RES_0402LF-33,5%,1/16W,CHIP,A
H_CPU1_MON_FAIL_LVC1_R_N R1957            1        Q_RES_0402LF-100,1%,1/16W,CHIPA
H_CPU1_MON_FAIL_LVC1_R_N U1               BR23     SOCKET4677_AZIFS054P001C01-SOCA
H_CPU1_MON_FAIL_PLD_LVC1_N R104             2        Q_RES_0402LF-33,5%,1/16W,CHIP,A
H_CPU1_MON_FAIL_PLD_LVC1_N U122             M8       10M04SAU324I7G-10M04SAU324I7G,A
H_CPU1_NMI_LVC1_N        R196             2        Q_RES_0402LF-49.9     ,1%  ,1/A
H_CPU1_NMI_LVC1_N        R198             2        Q_RES_0402LF-10K,1%,1/16W,EMPTA
H_CPU1_NMI_LVC1_N        U1               AV18     SOCKET4677_AZIFS054P001C01-SOCA
H_CPU1_PM_FAST_WAKE_N    R1245            2        Q_RES_0402LF-0,5%,1/16W,CHIP,CA
H_CPU1_PM_FAST_WAKE_N    U1               CP20     SOCKET4677_AZIFS054P001C01-SOCA
H_CPU1_PRDY_QS_GTL_R_N   R61              2        Q_RES_0402LF-10,1%,1/16W,CHIP,A
H_CPU1_PRDY_QS_GTL_R_N   U1               BP26     SOCKET4677_AZIFS054P001C01-SOCA
H_CPU1_PREQ_QS_GTL_R_N   R62              2        Q_RES_0402LF-100,1%,1/16W,CHIPA
H_CPU1_PREQ_QS_GTL_R_N   U1               AV22     SOCKET4677_AZIFS054P001C01-SOCA
H_CPU1_PROCHOT_LVC1_N    R240             2        Q_RES_0402LF-0,5%,1/16W,CHIP,CA
H_CPU1_PROCHOT_LVC1_N    R244             2        Q_RES_0402LF-100,1%,1/16W,EMPTA
H_CPU1_PROCHOT_LVC1_N    U1               AU19     SOCKET4677_AZIFS054P001C01-SOCA
H_CPU1_PROCHOT_LVC1_R_N  R240             1        Q_RES_0402LF-0,5%,1/16W,CHIP,CA
H_CPU1_PROCHOT_LVC1_R_N  U122             P5       10M04SAU324I7G-10M04SAU324I7G,A
H_CPU1_RMCA_LVC1_R_N     R304             1        Q_RES_0402LF-33.2,1%,1/16W,CHIA
H_CPU1_RMCA_LVC1_R_N     U1               BH22     SOCKET4677_AZIFS054P001C01-SOCA
H_CPU1_THERMTRIP_LVC1_N  R238             2        Q_RES_0402LF-0,5%,1/16W,CHIP,CA
H_CPU1_THERMTRIP_LVC1_N  R242             2        Q_RES_0402LF-1K,1%,1/16W,EMPTYA
H_CPU1_THERMTRIP_LVC1_N  R1428            1        Q_RES_0402LF-100,1%,1/16W,CHIPA
H_CPU1_THERMTRIP_LVC1_N  U122             P6       10M04SAU324I7G-10M04SAU324I7G,A
H_CPU1_THERMTRIP_LVC1_R_N R238             1        Q_RES_0402LF-0,5%,1/16W,CHIP,CA
H_CPU1_THERMTRIP_LVC1_R_N U1               BL62     SOCKET4677_AZIFS054P001C01-SOCA
H_CPU_CATERR_LVC1_R_N    R296             2        Q_RES_0402LF-301,1%,1/16W,CHIPA
H_CPU_CATERR_LVC1_R_N    R297             2        Q_RES_0402LF-0,5%,1/16W,CHIP,CA
H_CPU_CATERR_LVC1_R_N    R298             2        Q_RES_0402LF-301,1%,1/16W,CHIPA
H_CPU_CATERR_LVC1_R_N    R299             2        Q_RES_0402LF-0,5%,1/16W,CHIP,CA
H_CPU_CATERR_LVC1_R_N    U122             T5       10M04SAU324I7G-10M04SAU324I7G,A
H_CPU_ERR0_LVC1_N        R338             2        Q_RES_0402LF-33,5%,1/16W,CHIP,A
H_CPU_ERR0_LVC1_N        R1431            1        Q_RES_0402LF-150,1%,1/16W,CHIPA
H_CPU_ERR0_LVC1_N        U122             T6       10M04SAU324I7G-10M04SAU324I7G,A
H_CPU_ERR0_LVC1_R_N      R336             2        Q_RES_0402LF-0,5%,1/16W,CHIP,CA
H_CPU_ERR0_LVC1_R_N      R337             2        Q_RES_0402LF-0,5%,1/16W,CHIP,CA
H_CPU_ERR0_LVC1_R_N      R338             1        Q_RES_0402LF-33,5%,1/16W,CHIP,A
H_CPU_ERR0_LVC1_R_N      R339             1        Q_RES_0402LF-33,5%,1/16W,CHIP,A
H_CPU_ERR0_PCH_R_N       R339             2        Q_RES_0402LF-33,5%,1/16W,CHIP,A
H_CPU_ERR0_PCH_R_N       R1260            2        Q_RES_0402LF-10K,1%,1/16W,EMPTA
H_CPU_ERR0_PCH_R_N       U4               J7       EMMITSBURG_REV0P9-GFNOCPU04302A
H_CPU_ERR1_LVC1_N        R342             2        Q_RES_0402LF-33,5%,1/16W,CHIP,A
H_CPU_ERR1_LVC1_N        R1432            1        Q_RES_0402LF-150,1%,1/16W,CHIPA
H_CPU_ERR1_LVC1_N        U122             V2       10M04SAU324I7G-10M04SAU324I7G,A
H_CPU_ERR1_LVC1_R_N      R340             2        Q_RES_0402LF-0,5%,1/16W,CHIP,CA
H_CPU_ERR1_LVC1_R_N      R341             2        Q_RES_0402LF-0,5%,1/16W,CHIP,CA
H_CPU_ERR1_LVC1_R_N      R342             1        Q_RES_0402LF-33,5%,1/16W,CHIP,A
H_CPU_ERR1_LVC1_R_N      R343             1        Q_RES_0402LF-33,5%,1/16W,CHIP,A
H_CPU_ERR1_PCH_R_N       R343             2        Q_RES_0402LF-33,5%,1/16W,CHIP,A
H_CPU_ERR1_PCH_R_N       R1261            2        Q_RES_0402LF-10K,1%,1/16W,EMPTA
H_CPU_ERR1_PCH_R_N       U4               G7       EMMITSBURG_REV0P9-GFNOCPU04302A
H_CPU_ERR2_LVC1_N        R346             2        Q_RES_0402LF-33,5%,1/16W,CHIP,A
H_CPU_ERR2_LVC1_N        R1433            1        Q_RES_0402LF-150,1%,1/16W,CHIPA
H_CPU_ERR2_LVC1_N        U122             V3       10M04SAU324I7G-10M04SAU324I7G,A
H_CPU_ERR2_LVC1_R_N      R344             2        Q_RES_0402LF-0,5%,1/16W,CHIP,CA
H_CPU_ERR2_LVC1_R_N      R345             2        Q_RES_0402LF-0,5%,1/16W,CHIP,CA
H_CPU_ERR2_LVC1_R_N      R346             1        Q_RES_0402LF-33,5%,1/16W,CHIP,A
H_CPU_ERR2_LVC1_R_N      R347             1        Q_RES_0402LF-33,5%,1/16W,CHIP,A
H_CPU_ERR2_PCH_R_N       R347             2        Q_RES_0402LF-33,5%,1/16W,CHIP,A
H_CPU_ERR2_PCH_R_N       R1262            2        Q_RES_0402LF-10K,1%,1/16W,EMPTA
H_CPU_ERR2_PCH_R_N       U4               L7       EMMITSBURG_REV0P9-GFNOCPU04302A
H_CPU_NMI_LVC1_N         R188             2        Q_RES_0402LF-0,5%,1/16W,CHIP,CA
H_CPU_NMI_LVC1_N         R195             1        Q_RES_0402LF-49.9     ,1%  ,1/A
H_CPU_NMI_LVC1_N         R196             1        Q_RES_0402LF-49.9     ,1%  ,1/A
H_CPU_NMI_LVC1_R_N       R188             1        Q_RES_0402LF-0,5%,1/16W,CHIP,CA
H_CPU_NMI_LVC1_R_N       U122             R5       10M04SAU324I7G-10M04SAU324I7G,A
H_CPU_PM_FAST_WAKE_N     R1240            2        Q_RES_0402LF-0,5%,1/16W,CHIP,CA
H_CPU_PM_FAST_WAKE_N     R1242            2        Q_RES_0402LF-301,1%,1/16W,CHIPA
H_CPU_PM_FAST_WAKE_N     R1244            2        Q_RES_0402LF-301,1%,1/16W,CHIPA
H_CPU_PM_FAST_WAKE_N     R1245            1        Q_RES_0402LF-0,5%,1/16W,CHIP,CA
H_CPU_PRDY_QS_GTL_N      R1               1        Q_RES_0402LF-10,1%,1/16W,CHIP,A
H_CPU_PRDY_QS_GTL_N      R61              1        Q_RES_0402LF-10,1%,1/16W,CHIP,A
H_CPU_PRDY_QS_GTL_N      R759             2        Q_RES_0402LF-150,1%,1/16W,CHIPA
H_CPU_PRDY_QS_GTL_N      U18              8        74CBTLV3126PW-74CBTLV3126PW,SMA
H_CPU_PREQ_QS_GTL_N      R2               1        Q_RES_0402LF-100,1%,1/16W,CHIPA
H_CPU_PREQ_QS_GTL_N      R62              1        Q_RES_0402LF-100,1%,1/16W,CHIPA
H_CPU_PREQ_QS_GTL_N      R758             2        Q_RES_0402LF-150,1%,1/16W,CHIPA
H_CPU_PREQ_QS_GTL_N      U18              11       74CBTLV3126PW-74CBTLV3126PW,SMA
H_CPU_RMCA_LVC1_R_N      R301             2        Q_RES_0402LF-301,1%,1/16W,CHIPA
H_CPU_RMCA_LVC1_R_N      R302             2        Q_RES_0402LF-33.2,1%,1/16W,CHIA
H_CPU_RMCA_LVC1_R_N      R303             2        Q_RES_0402LF-301,1%,1/16W,CHIPA
H_CPU_RMCA_LVC1_R_N      R304             2        Q_RES_0402LF-33.2,1%,1/16W,CHIA
H_CPU_RMCA_LVC1_R_N      U122             T7       10M04SAU324I7G-10M04SAU324I7G,A
H_DBP_PRDY_N_PCH         R751             2        Q_RES_0402LF-150,1%,1/16W,CHIPA
H_DBP_PRDY_N_PCH         R756             2        Q_RES_0402LF-10,1%,1/16W,CHIP,A
H_DBP_PRDY_N_PCH         U4               BB37     EMMITSBURG_REV0P9-GFNOCPU04302A
H_DBP_PREQ_N_PCH         R750             2        Q_RES_0402LF-150,1%,1/16W,CHIPA
H_DBP_PREQ_N_PCH         R755             2        Q_RES_0402LF-10,1%,1/16W,CHIP,A
H_DBP_PREQ_N_PCH         U4               BF37     EMMITSBURG_REV0P9-GFNOCPU04302A
H_PMAX_TRIGGER_IO_CPU0   R1241            1        Q_RES_0402LF-249,1%,1/16W,CHIPA
H_PMAX_TRIGGER_IO_CPU0   U2               BD24     SOCKET4677_AZIFS054P001C01-SOCA
H_PMAX_TRIGGER_IO_CPU1   R1243            1        Q_RES_0402LF-249,1%,1/16W,CHIPA
H_PMAX_TRIGGER_IO_CPU1   U1               BD24     SOCKET4677_AZIFS054P001C01-SOCA
H_THERMTRIP_LVC1_N       R1249            2        Q_RES_0402LF-0,5%,1/16W,CHIP,CA
H_THERMTRIP_LVC1_N       R1266            2        Q_RES_0402LF-49.9     ,1%  ,1/B
H_THERMTRIP_LVC1_N       U4               F3       EMMITSBURG_REV0P9-GFNOCPU04302A
I3C_SPD_DDRABCD_CPU0_BMC_R_SCL J41              OCP_A5   SCONN168_623403212-SCONN168_6-A
I3C_SPD_DDRABCD_CPU0_BMC_R_SCL R593             1        Q_RES_0402LF-0,5%,1/16W,CHIP,CA
I3C_SPD_DDRABCD_CPU0_BMC_R_SDA J41              OCP_A6   SCONN168_623403212-SCONN168_6-A
I3C_SPD_DDRABCD_CPU0_BMC_R_SDA R594             1        Q_RES_0402LF-0,5%,1/16W,CHIP,CA
I3C_SPD_DDRABCD_CPU0_BMC_SCL R593             2        Q_RES_0402LF-0,5%,1/16W,CHIP,CA
I3C_SPD_DDRABCD_CPU0_BMC_SCL U15              3        IDTQS3VH257QG_SMLF-IDTQS3VH257A
I3C_SPD_DDRABCD_CPU0_BMC_SDA R594             2        Q_RES_0402LF-0,5%,1/16W,CHIP,CA
I3C_SPD_DDRABCD_CPU0_BMC_SDA U15              6        IDTQS3VH257QG_SMLF-IDTQS3VH257A
I3C_SPD_DDRABCD_CPU0_LVC1_R_SCL R682             2        Q_RES_0402LF-0,5%,1/16W,EMPTY,A
I3C_SPD_DDRABCD_CPU0_LVC1_R_SCL R691             1        Q_RES_0402LF-0,5%,1/16W,CHIP,CA
I3C_SPD_DDRABCD_CPU0_LVC1_R_SCL U15              4        IDTQS3VH257QG_SMLF-IDTQS3VH257A
I3C_SPD_DDRABCD_CPU0_LVC1_R_SDA R683             2        Q_RES_0402LF-0,5%,1/16W,EMPTY,A
I3C_SPD_DDRABCD_CPU0_LVC1_R_SDA R692             1        Q_RES_0402LF-0,5%,1/16W,CHIP,CA
I3C_SPD_DDRABCD_CPU0_LVC1_R_SDA U15              7        IDTQS3VH257QG_SMLF-IDTQS3VH257A
I3C_SPD_DDRABCD_CPU0_LVC1_SCL J1               4        SCONN288_ADR50001P013C01-SCONNA
I3C_SPD_DDRABCD_CPU0_LVC1_SCL J2               4        SCONN288_ADR50001P003C01-SCONNA
I3C_SPD_DDRABCD_CPU0_LVC1_SCL J3               4        SCONN288_ADR50001P013C01-SCONNA
I3C_SPD_DDRABCD_CPU0_LVC1_SCL J4               4        SCONN288_ADR50001P003C01-SCONNA
I3C_SPD_DDRABCD_CPU0_LVC1_SCL J5               4        SCONN288_ADR50001P013C01-SCONNA
I3C_SPD_DDRABCD_CPU0_LVC1_SCL J6               4        SCONN288_ADR50001P003C01-SCONNA
I3C_SPD_DDRABCD_CPU0_LVC1_SCL J7               4        SCONN288_ADR50001P013C01-SCONNA
I3C_SPD_DDRABCD_CPU0_LVC1_SCL J8               4        SCONN288_ADR50001P003C01-SCONNA
I3C_SPD_DDRABCD_CPU0_LVC1_SCL R691             2        Q_RES_0402LF-0,5%,1/16W,CHIP,CA
I3C_SPD_DDRABCD_CPU0_LVC1_SDA J1               5        SCONN288_ADR50001P013C01-SCONNA
I3C_SPD_DDRABCD_CPU0_LVC1_SDA J2               5        SCONN288_ADR50001P003C01-SCONNA
I3C_SPD_DDRABCD_CPU0_LVC1_SDA J3               5        SCONN288_ADR50001P013C01-SCONNA
I3C_SPD_DDRABCD_CPU0_LVC1_SDA J4               5        SCONN288_ADR50001P003C01-SCONNA
I3C_SPD_DDRABCD_CPU0_LVC1_SDA J5               5        SCONN288_ADR50001P013C01-SCONNA
I3C_SPD_DDRABCD_CPU0_LVC1_SDA J6               5        SCONN288_ADR50001P003C01-SCONNA
I3C_SPD_DDRABCD_CPU0_LVC1_SDA J7               5        SCONN288_ADR50001P013C01-SCONNA
I3C_SPD_DDRABCD_CPU0_LVC1_SDA J8               5        SCONN288_ADR50001P003C01-SCONNA
I3C_SPD_DDRABCD_CPU0_LVC1_SDA R692             2        Q_RES_0402LF-0,5%,1/16W,CHIP,CA
I3C_SPD_DDRABCD_CPU0_R_SCL R682             1        Q_RES_0402LF-0,5%,1/16W,EMPTY,A
I3C_SPD_DDRABCD_CPU0_R_SCL R687             2        Q_RES_0402LF-33.2,1%,1/16W,CHIA
I3C_SPD_DDRABCD_CPU0_R_SCL U15              2        IDTQS3VH257QG_SMLF-IDTQS3VH257A
I3C_SPD_DDRABCD_CPU0_R_SDA R683             1        Q_RES_0402LF-0,5%,1/16W,EMPTY,A
I3C_SPD_DDRABCD_CPU0_R_SDA R688             2        Q_RES_0402LF-33.2,1%,1/16W,CHIA
I3C_SPD_DDRABCD_CPU0_R_SDA U15              5        IDTQS3VH257QG_SMLF-IDTQS3VH257A
I3C_SPD_DDRABCD_CPU0_SCL R679             2        Q_RES_0402LF-249,1%,1/16W,CHIPA
I3C_SPD_DDRABCD_CPU0_SCL R687             1        Q_RES_0402LF-33.2,1%,1/16W,CHIA
I3C_SPD_DDRABCD_CPU0_SCL U2               BT22     SOCKET4677_AZIFS054P001C01-SOCA
I3C_SPD_DDRABCD_CPU0_SDA R680             2        Q_RES_0402LF-249,1%,1/16W,CHIPA
I3C_SPD_DDRABCD_CPU0_SDA R688             1        Q_RES_0402LF-33.2,1%,1/16W,CHIA
I3C_SPD_DDRABCD_CPU0_SDA U2               BY22     SOCKET4677_AZIFS054P001C01-SOCA
I3C_SPD_DDRABCD_CPU1_BMC_R_SCL J41              OCP_A9   SCONN168_623403212-SCONN168_6-A
I3C_SPD_DDRABCD_CPU1_BMC_R_SCL R597             1        Q_RES_0402LF-0,5%,1/16W,CHIP,CA
I3C_SPD_DDRABCD_CPU1_BMC_R_SDA J41              OCP_A10  SCONN168_623403212-SCONN168_6-A
I3C_SPD_DDRABCD_CPU1_BMC_R_SDA R598             1        Q_RES_0402LF-0,5%,1/16W,CHIP,CA
I3C_SPD_DDRABCD_CPU1_BMC_SCL R597             2        Q_RES_0402LF-0,5%,1/16W,CHIP,CA
I3C_SPD_DDRABCD_CPU1_BMC_SCL U14              3        IDTQS3VH257QG_SMLF-IDTQS3VH257A
I3C_SPD_DDRABCD_CPU1_BMC_SDA R598             2        Q_RES_0402LF-0,5%,1/16W,CHIP,CA
I3C_SPD_DDRABCD_CPU1_BMC_SDA U14              6        IDTQS3VH257QG_SMLF-IDTQS3VH257A
I3C_SPD_DDRABCD_CPU1_LVC1_R_SCL R665             2        Q_RES_0402LF-0,5%,1/16W,EMPTY,A
I3C_SPD_DDRABCD_CPU1_LVC1_R_SCL R674             1        Q_RES_0402LF-0,5%,1/16W,CHIP,CA
I3C_SPD_DDRABCD_CPU1_LVC1_R_SCL U14              4        IDTQS3VH257QG_SMLF-IDTQS3VH257A
I3C_SPD_DDRABCD_CPU1_LVC1_R_SDA R666             2        Q_RES_0402LF-0,5%,1/16W,EMPTY,A
I3C_SPD_DDRABCD_CPU1_LVC1_R_SDA R675             1        Q_RES_0402LF-0,5%,1/16W,CHIP,CA
I3C_SPD_DDRABCD_CPU1_LVC1_R_SDA U14              7        IDTQS3VH257QG_SMLF-IDTQS3VH257A
I3C_SPD_DDRABCD_CPU1_LVC1_SCL J17              4        SCONN288_ADR50001P013C01-SCONNA
I3C_SPD_DDRABCD_CPU1_LVC1_SCL J18              4        SCONN288_ADR50001P003C01-SCONNA
I3C_SPD_DDRABCD_CPU1_LVC1_SCL J19              4        SCONN288_ADR50001P013C01-SCONNA
I3C_SPD_DDRABCD_CPU1_LVC1_SCL J20              4        SCONN288_ADR50001P003C01-SCONNA
I3C_SPD_DDRABCD_CPU1_LVC1_SCL J21              4        SCONN288_ADR50001P013C01-SCONNA
I3C_SPD_DDRABCD_CPU1_LVC1_SCL J22              4        SCONN288_ADR50001P003C01-SCONNA
I3C_SPD_DDRABCD_CPU1_LVC1_SCL J23              4        SCONN288_ADR50001P013C01-SCONNA
I3C_SPD_DDRABCD_CPU1_LVC1_SCL J24              4        SCONN288_ADR50001P003C01-SCONNA
I3C_SPD_DDRABCD_CPU1_LVC1_SCL R674             2        Q_RES_0402LF-0,5%,1/16W,CHIP,CA
I3C_SPD_DDRABCD_CPU1_LVC1_SDA J17              5        SCONN288_ADR50001P013C01-SCONNA
I3C_SPD_DDRABCD_CPU1_LVC1_SDA J18              5        SCONN288_ADR50001P003C01-SCONNA
I3C_SPD_DDRABCD_CPU1_LVC1_SDA J19              5        SCONN288_ADR50001P013C01-SCONNA
I3C_SPD_DDRABCD_CPU1_LVC1_SDA J20              5        SCONN288_ADR50001P003C01-SCONNA
I3C_SPD_DDRABCD_CPU1_LVC1_SDA J21              5        SCONN288_ADR50001P013C01-SCONNA
I3C_SPD_DDRABCD_CPU1_LVC1_SDA J22              5        SCONN288_ADR50001P003C01-SCONNA
I3C_SPD_DDRABCD_CPU1_LVC1_SDA J23              5        SCONN288_ADR50001P013C01-SCONNA
I3C_SPD_DDRABCD_CPU1_LVC1_SDA J24              5        SCONN288_ADR50001P003C01-SCONNA
I3C_SPD_DDRABCD_CPU1_LVC1_SDA R675             2        Q_RES_0402LF-0,5%,1/16W,CHIP,CA
I3C_SPD_DDRABCD_CPU1_R_SCL R665             1        Q_RES_0402LF-0,5%,1/16W,EMPTY,A
I3C_SPD_DDRABCD_CPU1_R_SCL R670             2        Q_RES_0402LF-33.2,1%,1/16W,CHIA
I3C_SPD_DDRABCD_CPU1_R_SCL U14              2        IDTQS3VH257QG_SMLF-IDTQS3VH257A
I3C_SPD_DDRABCD_CPU1_R_SDA R666             1        Q_RES_0402LF-0,5%,1/16W,EMPTY,A
I3C_SPD_DDRABCD_CPU1_R_SDA R671             2        Q_RES_0402LF-33.2,1%,1/16W,CHIA
I3C_SPD_DDRABCD_CPU1_R_SDA U14              5        IDTQS3VH257QG_SMLF-IDTQS3VH257A
I3C_SPD_DDRABCD_CPU1_SCL R662             2        Q_RES_0402LF-249,1%,1/16W,CHIPA
I3C_SPD_DDRABCD_CPU1_SCL R670             1        Q_RES_0402LF-33.2,1%,1/16W,CHIA
I3C_SPD_DDRABCD_CPU1_SCL U1               BT22     SOCKET4677_AZIFS054P001C01-SOCA
I3C_SPD_DDRABCD_CPU1_SDA R663             2        Q_RES_0402LF-249,1%,1/16W,CHIPA
I3C_SPD_DDRABCD_CPU1_SDA R671             1        Q_RES_0402LF-33.2,1%,1/16W,CHIA
I3C_SPD_DDRABCD_CPU1_SDA U1               BY22     SOCKET4677_AZIFS054P001C01-SOCA
I3C_SPD_DDREFGH_CPU0_BMC_R_SCL J41              OCP_A7   SCONN168_623403212-SCONN168_6-A
I3C_SPD_DDREFGH_CPU0_BMC_R_SCL R595             1        Q_RES_0402LF-0,5%,1/16W,CHIP,CA
I3C_SPD_DDREFGH_CPU0_BMC_R_SDA J41              OCP_A8   SCONN168_623403212-SCONN168_6-A
I3C_SPD_DDREFGH_CPU0_BMC_R_SDA R596             1        Q_RES_0402LF-0,5%,1/16W,CHIP,CA
I3C_SPD_DDREFGH_CPU0_BMC_SCL R595             2        Q_RES_0402LF-0,5%,1/16W,CHIP,CA
I3C_SPD_DDREFGH_CPU0_BMC_SCL U15              10       IDTQS3VH257QG_SMLF-IDTQS3VH257A
I3C_SPD_DDREFGH_CPU0_BMC_SDA R596             2        Q_RES_0402LF-0,5%,1/16W,CHIP,CA
I3C_SPD_DDREFGH_CPU0_BMC_SDA U15              13       IDTQS3VH257QG_SMLF-IDTQS3VH257A
I3C_SPD_DDREFGH_CPU0_LVC1_R_SCL R684             2        Q_RES_0402LF-0,5%,1/16W,EMPTY,A
I3C_SPD_DDREFGH_CPU0_LVC1_R_SCL R693             1        Q_RES_0402LF-0,5%,1/16W,CHIP,CA
I3C_SPD_DDREFGH_CPU0_LVC1_R_SCL U15              9        IDTQS3VH257QG_SMLF-IDTQS3VH257A
I3C_SPD_DDREFGH_CPU0_LVC1_R_SDA R685             2        Q_RES_0402LF-0,5%,1/16W,EMPTY,A
I3C_SPD_DDREFGH_CPU0_LVC1_R_SDA R694             1        Q_RES_0402LF-0,5%,1/16W,CHIP,CA
I3C_SPD_DDREFGH_CPU0_LVC1_R_SDA U15              12       IDTQS3VH257QG_SMLF-IDTQS3VH257A
I3C_SPD_DDREFGH_CPU0_LVC1_SCL J9               4        SCONN288_ADR50001P013C01-SCONNA
I3C_SPD_DDREFGH_CPU0_LVC1_SCL J10              4        SCONN288_ADR50001P003C01-SCONNA
I3C_SPD_DDREFGH_CPU0_LVC1_SCL J11              4        SCONN288_ADR50001P013C01-SCONNA
I3C_SPD_DDREFGH_CPU0_LVC1_SCL J12              4        SCONN288_ADR50001P003C01-SCONNA
I3C_SPD_DDREFGH_CPU0_LVC1_SCL J13              4        SCONN288_ADR50001P013C01-SCONNA
I3C_SPD_DDREFGH_CPU0_LVC1_SCL J14              4        SCONN288_ADR50001P003C01-SCONNA
I3C_SPD_DDREFGH_CPU0_LVC1_SCL J15              4        SCONN288_ADR50001P013C01-SCONNA
I3C_SPD_DDREFGH_CPU0_LVC1_SCL J16              4        SCONN288_ADR50001P003C01-SCONNA
I3C_SPD_DDREFGH_CPU0_LVC1_SCL R693             2        Q_RES_0402LF-0,5%,1/16W,CHIP,CA
I3C_SPD_DDREFGH_CPU0_LVC1_SDA J9               5        SCONN288_ADR50001P013C01-SCONNA
I3C_SPD_DDREFGH_CPU0_LVC1_SDA J10              5        SCONN288_ADR50001P003C01-SCONNA
I3C_SPD_DDREFGH_CPU0_LVC1_SDA J11              5        SCONN288_ADR50001P013C01-SCONNA
I3C_SPD_DDREFGH_CPU0_LVC1_SDA J12              5        SCONN288_ADR50001P003C01-SCONNA
I3C_SPD_DDREFGH_CPU0_LVC1_SDA J13              5        SCONN288_ADR50001P013C01-SCONNA
I3C_SPD_DDREFGH_CPU0_LVC1_SDA J14              5        SCONN288_ADR50001P003C01-SCONNA
I3C_SPD_DDREFGH_CPU0_LVC1_SDA J15              5        SCONN288_ADR50001P013C01-SCONNA
I3C_SPD_DDREFGH_CPU0_LVC1_SDA J16              5        SCONN288_ADR50001P003C01-SCONNA
I3C_SPD_DDREFGH_CPU0_LVC1_SDA R694             2        Q_RES_0402LF-0,5%,1/16W,CHIP,CA
I3C_SPD_DDREFGH_CPU0_R_SCL R684             1        Q_RES_0402LF-0,5%,1/16W,EMPTY,A
I3C_SPD_DDREFGH_CPU0_R_SCL R689             2        Q_RES_0402LF-33.2,1%,1/16W,CHIA
I3C_SPD_DDREFGH_CPU0_R_SCL U15              11       IDTQS3VH257QG_SMLF-IDTQS3VH257A
I3C_SPD_DDREFGH_CPU0_R_SDA R685             1        Q_RES_0402LF-0,5%,1/16W,EMPTY,A
I3C_SPD_DDREFGH_CPU0_R_SDA R690             2        Q_RES_0402LF-33.2,1%,1/16W,CHIA
I3C_SPD_DDREFGH_CPU0_R_SDA U15              14       IDTQS3VH257QG_SMLF-IDTQS3VH257A
I3C_SPD_DDREFGH_CPU0_SCL R681             2        Q_RES_0402LF-249,1%,1/16W,CHIPA
I3C_SPD_DDREFGH_CPU0_SCL R689             1        Q_RES_0402LF-33.2,1%,1/16W,CHIA
I3C_SPD_DDREFGH_CPU0_SCL U2               CU17     SOCKET4677_AZIFS054P001C01-SOCA
I3C_SPD_DDREFGH_CPU0_SDA R686             2        Q_RES_0402LF-249,1%,1/16W,CHIPA
I3C_SPD_DDREFGH_CPU0_SDA R690             1        Q_RES_0402LF-33.2,1%,1/16W,CHIA
I3C_SPD_DDREFGH_CPU0_SDA U2               CT18     SOCKET4677_AZIFS054P001C01-SOCA
I3C_SPD_DDREFGH_CPU1_BMC_R_SCL J41              OCP_A11  SCONN168_623403212-SCONN168_6-A
I3C_SPD_DDREFGH_CPU1_BMC_R_SCL R599             1        Q_RES_0402LF-0,5%,1/16W,CHIP,CA
I3C_SPD_DDREFGH_CPU1_BMC_R_SDA J41              OCP_A12  SCONN168_623403212-SCONN168_6-A
I3C_SPD_DDREFGH_CPU1_BMC_R_SDA R600             1        Q_RES_0402LF-0,5%,1/16W,CHIP,CA
I3C_SPD_DDREFGH_CPU1_BMC_SCL R599             2        Q_RES_0402LF-0,5%,1/16W,CHIP,CA
I3C_SPD_DDREFGH_CPU1_BMC_SCL U14              10       IDTQS3VH257QG_SMLF-IDTQS3VH257A
I3C_SPD_DDREFGH_CPU1_BMC_SDA R600             2        Q_RES_0402LF-0,5%,1/16W,CHIP,CA
I3C_SPD_DDREFGH_CPU1_BMC_SDA U14              13       IDTQS3VH257QG_SMLF-IDTQS3VH257A
I3C_SPD_DDREFGH_CPU1_LVC1_R_SCL R667             2        Q_RES_0402LF-0,5%,1/16W,EMPTY,A
I3C_SPD_DDREFGH_CPU1_LVC1_R_SCL R676             1        Q_RES_0402LF-0,5%,1/16W,CHIP,CA
I3C_SPD_DDREFGH_CPU1_LVC1_R_SCL U14              9        IDTQS3VH257QG_SMLF-IDTQS3VH257A
I3C_SPD_DDREFGH_CPU1_LVC1_R_SDA R668             2        Q_RES_0402LF-0,5%,1/16W,EMPTY,A
I3C_SPD_DDREFGH_CPU1_LVC1_R_SDA R677             1        Q_RES_0402LF-0,5%,1/16W,CHIP,CA
I3C_SPD_DDREFGH_CPU1_LVC1_R_SDA U14              12       IDTQS3VH257QG_SMLF-IDTQS3VH257A
I3C_SPD_DDREFGH_CPU1_LVC1_SCL J25              4        SCONN288_ADR50001P013C01-SCONNA
I3C_SPD_DDREFGH_CPU1_LVC1_SCL J26              4        SCONN288_ADR50001P003C01-SCONNA
I3C_SPD_DDREFGH_CPU1_LVC1_SCL J27              4        SCONN288_ADR50001P013C01-SCONNA
I3C_SPD_DDREFGH_CPU1_LVC1_SCL J28              4        SCONN288_ADR50001P003C01-SCONNA
I3C_SPD_DDREFGH_CPU1_LVC1_SCL J29              4        SCONN288_ADR50001P013C01-SCONNA
I3C_SPD_DDREFGH_CPU1_LVC1_SCL J30              4        SCONN288_ADR50001P003C01-SCONNA
I3C_SPD_DDREFGH_CPU1_LVC1_SCL J31              4        SCONN288_ADR50001P013C01-SCONNA
I3C_SPD_DDREFGH_CPU1_LVC1_SCL J32              4        SCONN288_ADR50001P003C01-SCONNA
I3C_SPD_DDREFGH_CPU1_LVC1_SCL R676             2        Q_RES_0402LF-0,5%,1/16W,CHIP,CA
I3C_SPD_DDREFGH_CPU1_LVC1_SDA J25              5        SCONN288_ADR50001P013C01-SCONNA
I3C_SPD_DDREFGH_CPU1_LVC1_SDA J26              5        SCONN288_ADR50001P003C01-SCONNA
I3C_SPD_DDREFGH_CPU1_LVC1_SDA J27              5        SCONN288_ADR50001P013C01-SCONNA
I3C_SPD_DDREFGH_CPU1_LVC1_SDA J28              5        SCONN288_ADR50001P003C01-SCONNA
I3C_SPD_DDREFGH_CPU1_LVC1_SDA J29              5        SCONN288_ADR50001P013C01-SCONNA
I3C_SPD_DDREFGH_CPU1_LVC1_SDA J30              5        SCONN288_ADR50001P003C01-SCONNA
I3C_SPD_DDREFGH_CPU1_LVC1_SDA J31              5        SCONN288_ADR50001P013C01-SCONNA
I3C_SPD_DDREFGH_CPU1_LVC1_SDA J32              5        SCONN288_ADR50001P003C01-SCONNA
I3C_SPD_DDREFGH_CPU1_LVC1_SDA R677             2        Q_RES_0402LF-0,5%,1/16W,CHIP,CA
I3C_SPD_DDREFGH_CPU1_R_SCL R667             1        Q_RES_0402LF-0,5%,1/16W,EMPTY,A
I3C_SPD_DDREFGH_CPU1_R_SCL R672             2        Q_RES_0402LF-33.2,1%,1/16W,CHIA
I3C_SPD_DDREFGH_CPU1_R_SCL U14              11       IDTQS3VH257QG_SMLF-IDTQS3VH257A
I3C_SPD_DDREFGH_CPU1_R_SDA R668             1        Q_RES_0402LF-0,5%,1/16W,EMPTY,A
I3C_SPD_DDREFGH_CPU1_R_SDA R673             2        Q_RES_0402LF-33.2,1%,1/16W,CHIA
I3C_SPD_DDREFGH_CPU1_R_SDA U14              14       IDTQS3VH257QG_SMLF-IDTQS3VH257A
I3C_SPD_DDREFGH_CPU1_SCL R664             2        Q_RES_0402LF-249,1%,1/16W,CHIPA
I3C_SPD_DDREFGH_CPU1_SCL R672             1        Q_RES_0402LF-33.2,1%,1/16W,CHIA
I3C_SPD_DDREFGH_CPU1_SCL U1               CU17     SOCKET4677_AZIFS054P001C01-SOCA
I3C_SPD_DDREFGH_CPU1_SDA R669             2        Q_RES_0402LF-249,1%,1/16W,CHIPA
I3C_SPD_DDREFGH_CPU1_SDA R673             1        Q_RES_0402LF-33.2,1%,1/16W,CHIA
I3C_SPD_DDREFGH_CPU1_SDA U1               CT18     SOCKET4677_AZIFS054P001C01-SOCA
IND_P0_CPL1              PL9              3        Q_INDUCTOR4P_14-150NH,SMLF,INDA
IND_P0_CPL1              PL114            2        Q_INDUCTOR4P_14-150NH,SMLF,INDA
IND_P0_CPL2              PL13             2        Q_INDUCTOR4P_14-150NH,SMLF,INDA
IND_P0_CPL2              PL114            3        Q_INDUCTOR4P_14-150NH,SMLF,INDA
IND_P0_CPL3              PL13             3        Q_INDUCTOR4P_14-150NH,SMLF,INDA
IND_P0_CPL3              PL112            2        Q_INDUCTOR4P_14-150NH,SMLF,INDA
IND_P0_CPL4              PL11             2        Q_INDUCTOR4P_14-150NH,SMLF,INDA
IND_P0_CPL4              PL112            3        Q_INDUCTOR4P_14-150NH,SMLF,INDA
IND_P0_CPL5              PL10             2        Q_INDUCTOR4P_14-150NH,SMLF,INDA
IND_P0_CPL5              PL11             3        Q_INDUCTOR4P_14-150NH,SMLF,INDA
IND_P0_CPL6              PL8              3        Q_INDUCTOR4P_14-150NH,SMLF,INDA
IND_P0_CPL6              PL9              2        Q_INDUCTOR4P_14-150NH,SMLF,INDA
IND_P0_CPL7              PL8              2        Q_INDUCTOR4P_14-150NH,SMLF,INDA
IND_P0_CPL7              PL105            1        Q_INDUCTOR_SMLF-120NH/76A,IND,A
IND_P0_CPL8              PL7              2        Q_INDUCTOR4P_14-150NH,SMLF,INDA
IND_P0_CPL8              PL10             3        Q_INDUCTOR4P_14-150NH,SMLF,INDA
IND_P1_CPL1              PL30             3        Q_INDUCTOR4P_14-150NH,SMLF,INDA
IND_P1_CPL1              PL31             2        Q_INDUCTOR4P_14-150NH,SMLF,INDA
IND_P1_CPL2              PL29             3        Q_INDUCTOR4P_14-150NH,SMLF,INDA
IND_P1_CPL2              PL30             2        Q_INDUCTOR4P_14-150NH,SMLF,INDA
IND_P1_CPL3              PL28             3        Q_INDUCTOR4P_14-150NH,SMLF,INDA
IND_P1_CPL3              PL29             2        Q_INDUCTOR4P_14-150NH,SMLF,INDA
IND_P1_CPL4              PL27             3        Q_INDUCTOR4P_14-150NH,SMLF,INDA
IND_P1_CPL4              PL28             2        Q_INDUCTOR4P_14-150NH,SMLF,INDA
IND_P1_CPL5              PL24             3        Q_INDUCTOR4P_14-150NH,SMLF,INDA
IND_P1_CPL5              PL27             2        Q_INDUCTOR4P_14-150NH,SMLF,INDA
IND_P1_CPL6              PL26             2        Q_INDUCTOR4P_14-150NH,SMLF,INDA
IND_P1_CPL6              PL31             3        Q_INDUCTOR4P_14-150NH,SMLF,INDA
IND_P1_CPL7              PL25             2        Q_INDUCTOR4P_14-150NH,SMLF,INDA
IND_P1_CPL7              PL26             3        Q_INDUCTOR4P_14-150NH,SMLF,INDA
IND_P1_CPL8              PL24             2        Q_INDUCTOR4P_14-150NH,SMLF,INDA
IND_P1_CPL8              PL106            1        Q_INDUCTOR_SMLF-120NH/76A,IND,A
IRQ0_A57                 J41              A56      SCONN168_623403212-SCONN168_6-A
IRQ0_A57                 R506             2        Q_RES_0402LF-0,5%,1/16W,CHIP,CA
IRQ0_A57                 R1925            2        Q_RES_0402LF-0,5%,1/16W,CHIP,CA
IRQ0_A57_R               R1925            1        Q_RES_0402LF-0,5%,1/16W,CHIP,CA
IRQ0_A57_R               U122             D1       10M04SAU324I7G-10M04SAU324I7G,A
IRQ_BMC_CPU_NMI_R1       R1465            2        Q_RES_0402LF-10K,1%,1/16W,EMPTA
IRQ_BMC_CPU_NMI_R1       U122             E1       10M04SAU324I7G-10M04SAU324I7G,A
IRQ_BMC_PCH_NMI          R1268            2        Q_RES_0402LF-33,5%,1/16W,CHIP,A
IRQ_BMC_PCH_NMI          R1269            1        Q_RES_0402LF-4.75K,1%,1/16W,CHA
IRQ_BMC_PCH_NMI          U4               BF13     EMMITSBURG_REV0P9-GFNOCPU04302A
IRQ_BMC_PCH_NMI_R        R631             1        Q_RES_0402LF-0,5%,1/16W,EMPTY,A
IRQ_BMC_PCH_NMI_R        U101             2        SN74LVC1G17DCKR-SN74LVC1G17DCKA
IRQ_BMC_PCH_NMI_R        U122             P15      10M04SAU324I7G-10M04SAU324I7G,A
IRQ_BMC_PCH_NMI_R1       R631             2        Q_RES_0402LF-0,5%,1/16W,EMPTY,A
IRQ_BMC_PCH_NMI_R1       R1268            1        Q_RES_0402LF-33,5%,1/16W,CHIP,A
IRQ_BMC_PCH_NMI_R1       U101             4        SN74LVC1G17DCKR-SN74LVC1G17DCKA
IRQ_CPU0_VRHOT_N         PR131            2        Q_RES_0402LF-1K,1%,1/16W,CHIP,A
IRQ_CPU0_VRHOT_N         PR177            2        Q_RES_0402LF-1K,1%,1/16W,CHIP,A
IRQ_CPU0_VRHOT_N         PU5              14       ISL69260IRAZT-ISL69260IRAZ-T,SA
IRQ_CPU0_VRHOT_N         PU14             18       RAA229126GNPHA0-RAA229126GNP#HA
IRQ_CPU0_VRHOT_N         U122             G16      10M04SAU324I7G-10M04SAU324I7G,A
IRQ_CPU1_VRHOT_N         PR249            2        Q_RES_0402LF-1K,1%,1/16W,CHIP,A
IRQ_CPU1_VRHOT_N         PR284            2        Q_RES_0402LF-1K,1%,1/16W,CHIP,A
IRQ_CPU1_VRHOT_N         PU22             14       ISL69260IRAZT-ISL69260IRAZ-T,SA
IRQ_CPU1_VRHOT_N         PU29             18       RAA229126GNPHA0-RAA229126GNP#HA
IRQ_CPU1_VRHOT_N         U122             G17      10M04SAU324I7G-10M04SAU324I7G,A
IRQ_ESPI_LPC_SERIRQ_ALERT_N R1215            1        Q_RES_0402LF-49.9     ,1%  ,1/A
IRQ_ESPI_LPC_SERIRQ_ALERT_N U60              4        NC7SB3157_SMLF-NC7SB3157P6X,NCA
IRQ_ESPI_LPC_SERIRQ_ALERT_R_N J41              B3       SCONN168_623403212-SCONN168_6-A
IRQ_ESPI_LPC_SERIRQ_ALERT_R_N R1215            2        Q_RES_0402LF-49.9     ,1%  ,1/A
IRQ_LPC_PIRQA_N_ESPI_ALERT0_N R1214            1        Q_RES_0402LF-0,5%,1/16W,CHIP,CA
IRQ_LPC_PIRQA_N_ESPI_ALERT0_N R1253            2        Q_RES_0402LF-1K,1%,1/16W,CHIP,A
IRQ_LPC_PIRQA_N_ESPI_ALERT0_N U4               BG20     EMMITSBURG_REV0P9-GFNOCPU04302A
IRQ_LPC_PIRQA_N_ESPI_ALERT0_R_N R1214            2        Q_RES_0402LF-0,5%,1/16W,CHIP,CA
IRQ_LPC_PIRQA_N_ESPI_ALERT0_R_N U60              1        NC7SB3157_SMLF-NC7SB3157P6X,NCA
IRQ_LPC_SERIRQ_ESPI_CS1_N R1254            2        Q_RES_0402LF-10K,1%,1/16W,CHIPA
IRQ_LPC_SERIRQ_ESPI_CS1_N U4               BE16     EMMITSBURG_REV0P9-GFNOCPU04302A
IRQ_LPC_SERIRQ_ESPI_CS1_N U60              3        NC7SB3157_SMLF-NC7SB3157P6X,NCA
IRQ_LVC3_OCP_SFF_WAKE_N  J37              OCP_A3   SCONN168_623403212-SCONN168_6-A
IRQ_LVC3_OCP_SFF_WAKE_N  R1824            2        Q_RES_0402LF-10K,1%,1/16W,CHIPA
IRQ_LVC3_OCP_SFF_WAKE_N  U82              2        74LVC1G126GW_SMLF-74LVC1G126GWA
IRQ_LVC3_WAKE_EDSFF3_N   J35              A42      SCONN140_G64V3431BHR-SCONN140_B
IRQ_LVC3_WAKE_EDSFF3_N   R2078            1        Q_RES_0402LF-33.2,1%,1/16W,CHIA
IRQ_LVC3_WAKE_EDSFF4_N   J88              A42      SCONN84_123318136-SCONN84_1-23A
IRQ_LVC3_WAKE_EDSFF4_N   R2077            1        Q_RES_0402LF-33.2,1%,1/16W,CHIA
IRQ_LVC3_WAKE_N          R494             2        Q_RES_0402LF-4.75K,1%,1/16W,CHA
IRQ_LVC3_WAKE_N          R1481            1        Q_RES_0402LF-33.2,1%,1/16W,CHIA
IRQ_LVC3_WAKE_N          R1482            2        Q_RES_0402LF-33.2,1%,1/16W,CHIA
IRQ_LVC3_WAKE_N          R1594            2        Q_RES_0402LF-33.2,1%,1/16W,CHIA
IRQ_LVC3_WAKE_N          R2077            2        Q_RES_0402LF-33.2,1%,1/16W,CHIA
IRQ_LVC3_WAKE_N          R2078            2        Q_RES_0402LF-33.2,1%,1/16W,CHIA
IRQ_LVC3_WAKE_N          R2171            2        Q_RES_0402LF-33.2,1%,1/16W,CHIA
IRQ_LVC3_WAKE_N          U4               AH11     EMMITSBURG_REV0P9-GFNOCPU04302A
IRQ_LVC3_WAKE_R1_N       J55              B70      SCONN140_G64V3431BHR-SCONN140_A
IRQ_LVC3_WAKE_R1_N       R2171            1        Q_RES_0402LF-33.2,1%,1/16W,CHIA
IRQ_LVC3_WAKE_R2_N       J89              B30      SCONN280_ME1028040102011-SCONNA
IRQ_LVC3_WAKE_R2_N       R1481            2        Q_RES_0402LF-33.2,1%,1/16W,CHIA
IRQ_LVC3_WAKE_R3_N       J57              B70      SCONN140_G64V3431BHR-SCONN140_A
IRQ_LVC3_WAKE_R3_N       R1482            1        Q_RES_0402LF-33.2,1%,1/16W,CHIA
IRQ_P12V_HSC_FAULT_N     J44              13       CONN24_52SH90245BRD-CONN24_52SA
IRQ_P12V_HSC_FAULT_N     R1836            2        Q_RES_0402LF-0,5%,1/16W,CHIP,CA
IRQ_PCH_CPU_NMI_EVENT_N  R1310            2        Q_RES_0402LF-33.2,1%,1/16W,CHIA
IRQ_PCH_CPU_NMI_EVENT_N  U122             G3       10M04SAU324I7G-10M04SAU324I7G,A
IRQ_PCH_CPU_NMI_EVENT_R_N R1310            1        Q_RES_0402LF-33.2,1%,1/16W,CHIA
IRQ_PCH_CPU_NMI_EVENT_R_N R1459            2        Q_RES_0402LF-10K,1%,1/16W,CHIPA
IRQ_PCH_CPU_NMI_EVENT_R_N U4               AP15     EMMITSBURG_REV0P9-GFNOCPU04302A
IRQ_PCH_SCI_WHEA_N       R1256            2        Q_RES_0402LF-10K,1%,1/16W,CHIPA
IRQ_PCH_SCI_WHEA_N       R1944            2        Q_RES_0402LF-0,5%,1/16W,CHIP,CA
IRQ_PCH_SCI_WHEA_N       U4               AB2      EMMITSBURG_REV0P9-GFNOCPU04302A
IRQ_PCH_SCI_WHEA_R_N     R1944            1        Q_RES_0402LF-0,5%,1/16W,CHIP,CA
IRQ_PCH_SCI_WHEA_R_N     U122             P17      10M04SAU324I7G-10M04SAU324I7G,A
IRQ_PDB_R_N              R948             1        Q_RES_0402LF-0,5%,1/16W,CHIP,CA
IRQ_PDB_R_N              R952             2        Q_RES_0402LF-4.7K,1%,1/16W,EMPA
IRQ_PDB_R_N              U122             D12      10M04SAU324I7G-10M04SAU324I7G,A
IRQ_PSU_ALERT_N          L11              1        Q_INDUCTOR_SMLF-BLM15AG121SN1DA
IRQ_PSU_ALERT_N          R473             1        Q_RES_0402LF-0,5%,1/16W,CHIP,CA
IRQ_PSU_ALERT_N          R1608            2        Q_RES_0402LF-4.7K,1%,1/16W,EMPA
IRQ_PSU_ALERT_N          R1836            1        Q_RES_0402LF-0,5%,1/16W,CHIP,CA
IRQ_PSYS_CRIT_N          R541             1        Q_RES_0402LF-0,5%,1/16W,CHIP,CA
IRQ_PSYS_CRIT_N          U122             P18      10M04SAU324I7G-10M04SAU324I7G,A
IRQ_PVCCD_CPU0_VRHOT_LVC3_N PR378            2        Q_RES_0402LF-1K,1%,1/16W,CHIP,A
IRQ_PVCCD_CPU0_VRHOT_LVC3_N PU35             14       ISL69260IRAZT-ISL69260IRAZ-T,SA
IRQ_PVCCD_CPU0_VRHOT_LVC3_N U122             B11      10M04SAU324I7G-10M04SAU324I7G,A
IRQ_PVCCD_CPU1_VRHOT_LVC3_N PR223            2        Q_RES_0402LF-1K,1%,1/16W,CHIP,A
IRQ_PVCCD_CPU1_VRHOT_LVC3_N PU18             14       ISL69260IRAZT-ISL69260IRAZ-T,SA
IRQ_PVCCD_CPU1_VRHOT_LVC3_N U122             B12      10M04SAU324I7G-10M04SAU324I7G,A
IRQ_SGPIO_INTR_N         J41              B40      SCONN168_623403212-SCONN168_6-A
IRQ_SGPIO_INTR_N         R1812            1        Q_RES_0402LF-33.2,1%,1/16W,CHIA
IRQ_SGPIO_INTR_N_R       R1812            2        Q_RES_0402LF-33.2,1%,1/16W,CHIA
IRQ_SGPIO_INTR_N_R       U122             P14      10M04SAU324I7G-10M04SAU324I7G,A
IRQ_SMI_ACTIVE_BMC_N     R506             1        Q_RES_0402LF-0,5%,1/16W,CHIP,CA
IRQ_SMI_ACTIVE_BMC_N     R1309            2        Q_RES_0402LF-33.2,1%,1/16W,CHIA
IRQ_SMI_ACTIVE_N         R1309            1        Q_RES_0402LF-33.2,1%,1/16W,CHIA
IRQ_SMI_ACTIVE_N         R1458            2        Q_RES_0402LF-10K,1%,1/16W,CHIPA
IRQ_SMI_ACTIVE_N         U4               AV18     EMMITSBURG_REV0P9-GFNOCPU04302A
IRQ_SML0_ALERT_N         R1600            1        Q_RES_0402LF-33,5%,1/16W,CHIP,A
IRQ_SML0_ALERT_N         R1601            1        Q_RES_0402LF-10K,1%,1/16W,CHIPA
IRQ_SML0_ALERT_N         U4               AU2      EMMITSBURG_REV0P9-GFNOCPU04302A
IRQ_SML0_ALERT_R_N       R1600            2        Q_RES_0402LF-33,5%,1/16W,CHIP,A
IRQ_SML0_ALERT_R_N       U122             T1       10M04SAU324I7G-10M04SAU324I7G,A
IRQ_SML1_PMBUS_ALERT_N   R951             1        Q_RES_0402LF-0,5%,1/16W,CHIP,CA
IRQ_SML1_PMBUS_ALERT_N   R1656            1        Q_RES_0402LF-33,5%,1/16W,CHIP,A
IRQ_SML1_PMBUS_ALERT_N   R1657            1        Q_RES_0402LF-33,5%,1/16W,CHIP,A
IRQ_SML1_PMBUS_ALERT_N   R1658            1        Q_RES_0402LF-10K,1%,1/16W,CHIPA
IRQ_SML1_PMBUS_ALERT_N   U4               AR4      EMMITSBURG_REV0P9-GFNOCPU04302A
IRQ_SML1_PMBUS_ALERT_R_N J44              15       CONN24_52SH90245BRD-CONN24_52SA
IRQ_SML1_PMBUS_ALERT_R_N R951             2        Q_RES_0402LF-0,5%,1/16W,CHIP,CA
IRQ_SML1_PMBUS_BMC_ALERT_N R1657            2        Q_RES_0402LF-33,5%,1/16W,CHIP,A
IRQ_SML1_PMBUS_BMC_ALERT_N U122             M7       10M04SAU324I7G-10M04SAU324I7G,A
IRQ_SML1_PMBUS_PLD_ALERT_N R1656            2        Q_RES_0402LF-33,5%,1/16W,CHIP,A
IRQ_SML1_PMBUS_PLD_ALERT_N U122             T2       10M04SAU324I7G-10M04SAU324I7G,A
IRQ_TPM_SPI_N            R401             2        Q_RES_0402LF-10K,1%,1/16W,EMPTA
IRQ_TPM_SPI_N            U4               N4       EMMITSBURG_REV0P9-GFNOCPU04302A
IRQ_TPM_SPI_N            U122             P16      10M04SAU324I7G-10M04SAU324I7G,A
JTAG_BMC_CPU_TCK         R1373            1        Q_RES_0402LF-1K,1%,1/16W,CHIP,A
JTAG_BMC_CPU_TCK         U85              3        NC7SB3157_SMLF-NC7SB3157P6X,NCA
JTAG_BMC_CPU_TCK         U86              4        74CBTLV3126PW-74CBTLV3126PW,SMA
JTAG_BMC_DBP_PREQ_N      J41              A49      SCONN168_623403212-SCONN168_6-A
JTAG_BMC_DBP_PREQ_N      R1379            2        Q_RES_0402LF-33.2,1%,1/16W,CHIA
JTAG_BMC_DBP_PREQ_N      R1383            2        Q_RES_0402LF-1K,1%,1/16W,CHIP,A
JTAG_BMC_DBP_PREQ_N      R1832            1        Q_RES_0402LF-0,5%,1/16W,EMPTY,A
JTAG_BMC_DBP_TCK         U85              4        NC7SB3157_SMLF-NC7SB3157P6X,NCA
JTAG_BMC_DBP_TCK         U97              4        TS3A24157RSER-TS3A24157RSER,SMA
JTAG_BMC_DBP_TDI         R1345            2        Q_RES_0402LF-0,5%,1/16W,CHIP,CA
JTAG_BMC_DBP_TDI         U96              2        TS3A24157RSER-TS3A24157RSER,SMA
JTAG_BMC_DBP_TDI_R       R1345            1        Q_RES_0402LF-0,5%,1/16W,CHIP,CA
JTAG_BMC_DBP_TDI_R       U84              10       GTL2014PW-GTL2014PW,SMLF,IC,ALA
JTAG_BMC_DBP_TDO         R483             2        Q_RES_0402LF-0,5%,1/16W,CHIP,CA
JTAG_BMC_DBP_TDO         R1380            2        Q_RES_0402LF-1K,1%,1/16W,CHIP,A
JTAG_BMC_DBP_TDO         U96              4        TS3A24157RSER-TS3A24157RSER,SMA
JTAG_BMC_DBP_TDO_R       R483             1        Q_RES_0402LF-0,5%,1/16W,CHIP,CA
JTAG_BMC_DBP_TDO_R       U83              9        GTL2014PW-GTL2014PW,SMLF,IC,ALA
JTAG_BMC_DBP_TMS         R1184            2        Q_RES_0402LF-0,5%,1/16W,CHIP,CA
JTAG_BMC_DBP_TMS         U97              2        TS3A24157RSER-TS3A24157RSER,SMA
JTAG_BMC_DBP_TMS_R       R1184            1        Q_RES_0402LF-0,5%,1/16W,CHIP,CA
JTAG_BMC_DBP_TMS_R       U84              9        GTL2014PW-GTL2014PW,SMLF,IC,ALA
JTAG_BMC_PCH_TCK         R1371            1        Q_RES_0402LF-1K,1%,1/16W,CHIP,A
JTAG_BMC_PCH_TCK         U85              1        NC7SB3157_SMLF-NC7SB3157P6X,NCA
JTAG_BMC_PCH_TCK         U86              10       74CBTLV3126PW-74CBTLV3126PW,SMA
JTAG_BMC_PLD_TCK         J43              1        CONN10_G2100HT0038071-CONN10_GA
JTAG_BMC_PLD_TCK         R806             2        Q_RES_0402LF-33,5%,1/16W,CHIP,A
JTAG_BMC_PLD_TCK         R930             1        Q_RES_0402LF-4.7K,1%,1/16W,CHIA
JTAG_BMC_PLD_TCK         U97              3        TS3A24157RSER-TS3A24157RSER,SMA
JTAG_BMC_PLD_TDI         J43              9        CONN10_G2100HT0038071-CONN10_GA
JTAG_BMC_PLD_TDI         R803             2        Q_RES_0402LF-33,5%,1/16W,CHIP,A
JTAG_BMC_PLD_TDI         R927             2        Q_RES_0402LF-10K,1%,1/16W,CHIPA
JTAG_BMC_PLD_TDI         U96              1        TS3A24157RSER-TS3A24157RSER,SMA
JTAG_BMC_PLD_TDO         J43              3        CONN10_G2100HT0038071-CONN10_GA
JTAG_BMC_PLD_TDO         R804             2        Q_RES_0402LF-33,5%,1/16W,CHIP,A
JTAG_BMC_PLD_TDO         R928             2        Q_RES_0402LF-10K,1%,1/16W,CHIPA
JTAG_BMC_PLD_TDO         U96              3        TS3A24157RSER-TS3A24157RSER,SMA
JTAG_BMC_PLD_TMS         J43              5        CONN10_G2100HT0038071-CONN10_GA
JTAG_BMC_PLD_TMS         R805             2        Q_RES_0402LF-33,5%,1/16W,CHIP,A
JTAG_BMC_PLD_TMS         R929             2        Q_RES_0402LF-10K,1%,1/16W,CHIPA
JTAG_BMC_PLD_TMS         U97              1        TS3A24157RSER-TS3A24157RSER,SMA
JTAG_BMC_TCK             J41              A34      SCONN168_623403212-SCONN168_6-A
JTAG_BMC_TCK             U97              6        TS3A24157RSER-TS3A24157RSER,SMA
JTAG_BMC_TDI             J41              A36      SCONN168_623403212-SCONN168_6-A
JTAG_BMC_TDI             U96              9        TS3A24157RSER-TS3A24157RSER,SMA
JTAG_BMC_TDO             J41              A37      SCONN168_623403212-SCONN168_6-A
JTAG_BMC_TDO             U96              6        TS3A24157RSER-TS3A24157RSER,SMA
JTAG_BMC_TMS             J41              A35      SCONN168_623403212-SCONN168_6-A
JTAG_BMC_TMS             U97              9        TS3A24157RSER-TS3A24157RSER,SMA
JTAG_CPU0_MUX_GTL_TDO    R744             2        Q_RES_0402LF-75,1%,1/16W,CHIP,A
JTAG_CPU0_MUX_GTL_TDO    U2               BW25     SOCKET4677_AZIFS054P001C01-SOCA
JTAG_CPU0_MUX_GTL_TDO    U16              1        NC7SZ66M5X_SMLF-NC7SZ66M5X,NC7A
JTAG_CPU0_MUX_GTL_TDO    U22              1        NC7SB3157_SMLF-NC7SB3157P6X,NCA
JTAG_CPU0_PLD_TCK        R1226            1        Q_RES_0402LF-1K,1%,1/16W,CHIP,A
JTAG_CPU0_PLD_TCK        U2               CY22     SOCKET4677_AZIFS054P001C01-SOCA
JTAG_CPU0_PLD_TDI        R1223            1        Q_RES_0402LF-10K,1%,1/16W,EMPTA
JTAG_CPU0_PLD_TDI        U2               CT22     SOCKET4677_AZIFS054P001C01-SOCA
JTAG_CPU0_PLD_TDO        R1225            1        Q_RES_0402LF-10K,1%,1/16W,CHIPA
JTAG_CPU0_PLD_TDO        U2               CP22     SOCKET4677_AZIFS054P001C01-SOCA
JTAG_CPU0_PLD_TMS        R1224            1        Q_RES_0402LF-10K,1%,1/16W,CHIPA
JTAG_CPU0_PLD_TMS        U2               CV22     SOCKET4677_AZIFS054P001C01-SOCA
JTAG_CPU1_MUX_GTL_TDO    R742             2        Q_RES_0402LF-75,1%,1/16W,CHIP,A
JTAG_CPU1_MUX_GTL_TDO    U1               BW25     SOCKET4677_AZIFS054P001C01-SOCA
JTAG_CPU1_MUX_GTL_TDO    U22              3        NC7SB3157_SMLF-NC7SB3157P6X,NCA
JTAG_DBP_BMC_PRDY_N      J41              A50      SCONN168_623403212-SCONN168_6-A
JTAG_DBP_BMC_PRDY_N      R1378            2        Q_RES_0402LF-33.2,1%,1/16W,CHIA
JTAG_DBP_BMC_PRDY_N      R1382            2        Q_RES_0402LF-1K,1%,1/16W,CHIP,A
JTAG_DBP_BMC_PRDY_N      R1831            1        Q_RES_0402LF-0,5%,1/16W,EMPTY,A
JTAG_DBP_BMC_PRDY_R1_N   R1378            1        Q_RES_0402LF-33.2,1%,1/16W,CHIA
JTAG_DBP_BMC_PRDY_R1_N   U83              12       GTL2014PW-GTL2014PW,SMLF,IC,ALA
JTAG_DBP_BMC_PRDY_R_N    R1831            2        Q_RES_0402LF-0,5%,1/16W,EMPTY,A
JTAG_DBP_BMC_PRDY_R_N    U122             D7       10M04SAU324I7G-10M04SAU324I7G,A
JTAG_DBP_BMC_PREQ_R1_N   R1379            1        Q_RES_0402LF-33.2,1%,1/16W,CHIA
JTAG_DBP_BMC_PREQ_R1_N   U84              13       GTL2014PW-GTL2014PW,SMLF,IC,ALA
JTAG_DBP_BMC_PREQ_R_N    R1832            2        Q_RES_0402LF-0,5%,1/16W,EMPTY,A
JTAG_DBP_BMC_PREQ_R_N    U122             D8       10M04SAU324I7G-10M04SAU324I7G,A
JTAG_DBP_BOOT_HALT_N     J42              36       SCONN60_QSH03001LDAKTR-SCONN60A
JTAG_DBP_BOOT_HALT_N     R773             1        Q_RES_0402LF-1K,1%,1/16W,CHIP,A
JTAG_DBP_BOOT_HALT_N     R778             2        Q_RES_0402LF-1K,1%,1/16W,CHIP,A
JTAG_DBP_CPU0_GTL_R_TCK  R5               2        Q_RES_0402LF-100,1%,1/16W,CHIPA
JTAG_DBP_CPU0_GTL_R_TCK  U2               BT24     SOCKET4677_AZIFS054P001C01-SOCA
JTAG_DBP_CPU0_GTL_R_TDI  R4               2        Q_RES_0402LF-200,1%,1/16W,CHIPA
JTAG_DBP_CPU0_GTL_R_TDI  U2               BV24     SOCKET4677_AZIFS054P001C01-SOCA
JTAG_DBP_CPU0_QS_GTL_R_TMS R6               2        Q_RES_0402LF-100,1%,1/16W,CHIPA
JTAG_DBP_CPU0_QS_GTL_R_TMS U2               BR25     SOCKET4677_AZIFS054P001C01-SOCA
JTAG_DBP_CPU1_GTL_R_TCK  R65              2        Q_RES_0402LF-100,1%,1/16W,CHIPA
JTAG_DBP_CPU1_GTL_R_TCK  U1               BT24     SOCKET4677_AZIFS054P001C01-SOCA
JTAG_DBP_CPU1_GTL_R_TDI  R64              2        Q_RES_0402LF-200,1%,1/16W,CHIPA
JTAG_DBP_CPU1_GTL_R_TDI  U1               BV24     SOCKET4677_AZIFS054P001C01-SOCA
JTAG_DBP_CPU1_QS_GTL_R_TMS R66              2        Q_RES_0402LF-100,1%,1/16W,CHIPA
JTAG_DBP_CPU1_QS_GTL_R_TMS U1               BR25     SOCKET4677_AZIFS054P001C01-SOCA
JTAG_DBP_CPU_GTL_TCK     R5               1        Q_RES_0402LF-100,1%,1/16W,CHIPA
JTAG_DBP_CPU_GTL_TCK     R65              1        Q_RES_0402LF-100,1%,1/16W,CHIPA
JTAG_DBP_CPU_GTL_TCK     R762             1        Q_RES_0402LF-0,5%,1/16W,CHIP,CA
JTAG_DBP_CPU_GTL_TCK     R774             1        Q_RES_0402LF-75,1%,1/16W,CHIP,A
JTAG_DBP_CPU_GTL_TCK     R1025            1        Q_RES_0402LF-75,1%,1/16W,EMPTYA
JTAG_DBP_CPU_GTL_TCK     R1348            2        Q_RES_0402LF-0,5%,1/16W,CHIP,CA
JTAG_DBP_CPU_GTL_TCK     U4               BD35     EMMITSBURG_REV0P9-GFNOCPU04302A
JTAG_DBP_CPU_GTL_TCK_R   J42              3        SCONN60_QSH03001LDAKTR-SCONN60A
JTAG_DBP_CPU_GTL_TCK_R   R762             2        Q_RES_0402LF-0,5%,1/16W,CHIP,CA
JTAG_DBP_CPU_GTL_TCK_R1  R1348            1        Q_RES_0402LF-0,5%,1/16W,CHIP,CA
JTAG_DBP_CPU_GTL_TCK_R1  U86              6        74CBTLV3126PW-74CBTLV3126PW,SMA
JTAG_DBP_CPU_HOOK8_MBP2_GTL_N J42              55       SCONN60_QSH03001LDAKTR-SCONN60A
JTAG_DBP_CPU_HOOK8_MBP2_GTL_N U18              5        74CBTLV3126PW-74CBTLV3126PW,SMA
JTAG_DBP_CPU_HOOK9_MBP3_GTL_N J42              53       SCONN60_QSH03001LDAKTR-SCONN60A
JTAG_DBP_CPU_HOOK9_MBP3_GTL_N U18              2        74CBTLV3126PW-74CBTLV3126PW,SMA
JTAG_DBP_CPU_QS_GTL_TMS  R6               1        Q_RES_0402LF-100,1%,1/16W,CHIPA
JTAG_DBP_CPU_QS_GTL_TMS  R66              1        Q_RES_0402LF-100,1%,1/16W,CHIPA
JTAG_DBP_CPU_QS_GTL_TMS  R757             2        Q_RES_0402LF-120,1%,1/16W,CHIPA
JTAG_DBP_CPU_QS_GTL_TMS  U17              3        74CBTLV3126PW-74CBTLV3126PW,SMA
JTAG_DBP_FB_TDI          R481             2        Q_RES_0402LF-0,5%,1/16W,CHIP,CA
JTAG_DBP_FB_TDI          U84              5        GTL2014PW-GTL2014PW,SMLF,IC,ALA
JTAG_DBP_FB_TDO          R1366            2        Q_RES_0402LF-100,1%,1/16W,CHIPB
JTAG_DBP_FB_TDO          U83              6        GTL2014PW-GTL2014PW,SMLF,IC,ALA
JTAG_DBP_FB_TMS          R480             2        Q_RES_0402LF-0,5%,1/16W,CHIP,CA
JTAG_DBP_FB_TMS          U84              6        GTL2014PW-GTL2014PW,SMLF,IC,ALA
JTAG_DBP_PCH_DEBUG_CONSENT_N J42              15       SCONN60_QSH03001LDAKTR-SCONN60A
JTAG_DBP_PCH_DEBUG_CONSENT_N R771             1        Q_RES_0402LF-1K,1%,1/16W,CHIP,A
JTAG_DBP_PMODE           J42              7        SCONN60_QSH03001LDAKTR-SCONN60A
JTAG_DBP_PMODE           R1026            1        Q_RES_0402LF-1K,1%,1/16W,CHIP,A
JTAG_DBP_PMODE           U4               BE40     EMMITSBURG_REV0P9-GFNOCPU04302A
JTAG_DBP_POWER_BTN_N     C548             1        Q_CAP_0402-0.1UF,25V,10%,X7R,CA
JTAG_DBP_POWER_BTN_N     J42              40       SCONN60_QSH03001LDAKTR-SCONN60A
JTAG_DBP_POWER_BTN_N     R766             2        Q_RES_0402LF-1K,1%,1/16W,EMPTYA
JTAG_DBP_PRDY_N          R756             1        Q_RES_0402LF-10,1%,1/16W,CHIP,A
JTAG_DBP_PRDY_N          R764             1        Q_RES_0402LF-0,5%,1/16W,CHIP,CA
JTAG_DBP_PRDY_N          R1367            1        Q_RES_0402LF-100,1%,1/16W,CHIPB
JTAG_DBP_PRDY_N          U18              9        74CBTLV3126PW-74CBTLV3126PW,SMA
JTAG_DBP_PRDY_R1_N       J42              11       SCONN60_QSH03001LDAKTR-SCONN60A
JTAG_DBP_PRDY_R1_N       R764             2        Q_RES_0402LF-0,5%,1/16W,CHIP,CA
JTAG_DBP_PRDY_R_N        R1367            2        Q_RES_0402LF-100,1%,1/16W,CHIPB
JTAG_DBP_PRDY_R_N        U83              3        GTL2014PW-GTL2014PW,SMLF,IC,ALA
JTAG_DBP_PREQ_N          R482             1        Q_RES_0402LF-0,5%,1/16W,CHIP,CA
JTAG_DBP_PREQ_N          R755             1        Q_RES_0402LF-10,1%,1/16W,CHIP,A
JTAG_DBP_PREQ_N          R777             2        Q_RES_0402LF-10,1%,1/16W,CHIP,A
JTAG_DBP_PREQ_N          U18              12       74CBTLV3126PW-74CBTLV3126PW,SMA
JTAG_DBP_PREQ_N_R        J42              10       SCONN60_QSH03001LDAKTR-SCONN60A
JTAG_DBP_PREQ_N_R        R777             1        Q_RES_0402LF-10,1%,1/16W,CHIP,A
JTAG_DBP_PREQ_R_N        R482             2        Q_RES_0402LF-0,5%,1/16W,CHIP,CA
JTAG_DBP_PREQ_R_N        U84              2        GTL2014PW-GTL2014PW,SMLF,IC,ALA
JTAG_DBP_PRESENT_R_N     J42              17       SCONN60_QSH03001LDAKTR-SCONN60A
JTAG_DBP_PRESENT_R_N     R768             2        Q_RES_0402LF-1K,1%,1/16W,CHIP,A
JTAG_DBP_PRESENT_R_N     R1472            1        Q_RES_0402LF-33.2,1%,1/16W,CHIA
JTAG_DBP_TCK_PCH         R765             1        Q_RES_0402LF-0,5%,1/16W,CHIP,CA
JTAG_DBP_TCK_PCH         R1024            1        Q_RES_0402LF-100,1%,1/16W,CHIPA
JTAG_DBP_TCK_PCH         R1349            2        Q_RES_0402LF-0,5%,1/16W,CHIP,CA
JTAG_DBP_TCK_PCH         U4               BF35     EMMITSBURG_REV0P9-GFNOCPU04302A
JTAG_DBP_TCK_PCH_R       R1349            1        Q_RES_0402LF-0,5%,1/16W,CHIP,CA
JTAG_DBP_TCK_PCH_R       U86              8        74CBTLV3126PW-74CBTLV3126PW,SMA
JTAG_DBP_TCK_R_TCK       J42              51       SCONN60_QSH03001LDAKTR-SCONN60A
JTAG_DBP_TCK_R_TCK       R765             2        Q_RES_0402LF-0,5%,1/16W,CHIP,CA
JTAG_DBP_TDI             R481             1        Q_RES_0402LF-0,5%,1/16W,CHIP,CA
JTAG_DBP_TDI             R753             1        Q_RES_0402LF-10,1%,1/16W,CHIP,A
JTAG_DBP_TDI             R763             1        Q_RES_0402LF-10,1%,1/16W,CHIP,A
JTAG_DBP_TDI             U17              5        74CBTLV3126PW-74CBTLV3126PW,SMA
JTAG_DBP_TDI_PCH         R748             2        Q_RES_0402LF-75,1%,1/16W,CHIP,A
JTAG_DBP_TDI_PCH         R753             2        Q_RES_0402LF-10,1%,1/16W,CHIP,A
JTAG_DBP_TDI_PCH         U4               BE38     EMMITSBURG_REV0P9-GFNOCPU04302A
JTAG_DBP_TDI_R           J42              5        SCONN60_QSH03001LDAKTR-SCONN60A
JTAG_DBP_TDI_R           R763             2        Q_RES_0402LF-10,1%,1/16W,CHIP,A
JTAG_DBP_TDO             R752             1        Q_RES_0402LF-10,1%,1/16W,CHIP,A
JTAG_DBP_TDO             R776             2        Q_RES_0402LF-100,1%,1/16W,CHIPA
JTAG_DBP_TDO             R1366            1        Q_RES_0402LF-100,1%,1/16W,CHIPB
JTAG_DBP_TDO             U17              12       74CBTLV3126PW-74CBTLV3126PW,SMA
JTAG_DBP_TDO_PCH         R747             2        Q_RES_0402LF-150,1%,1/16W,CHIPA
JTAG_DBP_TDO_PCH         R752             2        Q_RES_0402LF-10,1%,1/16W,CHIP,A
JTAG_DBP_TDO_PCH         U4               BE36     EMMITSBURG_REV0P9-GFNOCPU04302A
JTAG_DBP_TDO_R           J42              4        SCONN60_QSH03001LDAKTR-SCONN60A
JTAG_DBP_TDO_R           R776             1        Q_RES_0402LF-100,1%,1/16W,CHIPA
JTAG_DBP_TMS             R480             1        Q_RES_0402LF-0,5%,1/16W,CHIP,CA
JTAG_DBP_TMS             R754             1        Q_RES_0402LF-10,1%,1/16W,CHIP,A
JTAG_DBP_TMS             R775             2        Q_RES_0402LF-10,1%,1/16W,CHIP,A
JTAG_DBP_TMS             U17              2        74CBTLV3126PW-74CBTLV3126PW,SMA
JTAG_DBP_TMS_PCH         R749             2        Q_RES_0402LF-75,1%,1/16W,CHIP,A
JTAG_DBP_TMS_PCH         R754             2        Q_RES_0402LF-10,1%,1/16W,CHIP,A
JTAG_DBP_TMS_PCH         U4               BD37     EMMITSBURG_REV0P9-GFNOCPU04302A
JTAG_DBP_TMS_R           J42              2        SCONN60_QSH03001LDAKTR-SCONN60A
JTAG_DBP_TMS_R           R775             1        Q_RES_0402LF-10,1%,1/16W,CHIP,A
JTAG_EDSFF4_TCK          J61              A14      SCONN84_123318136-SCONN84_1-23A
JTAG_EDSFF4_TCK          R2082            1        Q_RES_0402LF-4.7K,5%,1/16W,EMPA
JTAG_EDSFF4_TDI          J61              B9       SCONN84_123318136-SCONN84_1-23A
JTAG_EDSFF4_TDI          R2079            1        Q_RES_0402LF-4.7K,5%,1/16W,EMPA
JTAG_EDSFF4_TDO          J61              B8       SCONN84_123318136-SCONN84_1-23A
JTAG_EDSFF4_TDO          R2080            1        Q_RES_0402LF-4.7K,5%,1/16W,EMPA
JTAG_EDSFF4_TMS          J61              A15      SCONN84_123318136-SCONN84_1-23A
JTAG_EDSFF4_TMS          R2081            1        Q_RES_0402LF-4.7K,5%,1/16W,EMPA
JTAG_EDSFF4_TRST_N       J61              A42      SCONN84_123318136-SCONN84_1-23A
JTAG_EDSFF4_TRST_N       R2083            1        Q_RES_0402LF-4.7K,5%,1/16W,EMPA
JTAG_MUX_CPU0_GTL_TDI    R4               1        Q_RES_0402LF-200,1%,1/16W,CHIPA
JTAG_MUX_CPU0_GTL_TDI    R741             2        Q_RES_0402LF-150,1%,1/16W,CHIPA
JTAG_MUX_CPU0_GTL_TDI    U21              3        NC7SB3157_SMLF-NC7SB3157P6X,NCA
JTAG_MUX_CPU1_GTL_TDI    R64              1        Q_RES_0402LF-200,1%,1/16W,CHIPA
JTAG_MUX_CPU1_GTL_TDI    R743             2        Q_RES_0402LF-150,1%,1/16W,CHIPA
JTAG_MUX_CPU1_GTL_TDI    U16              2        NC7SZ66M5X_SMLF-NC7SZ66M5X,NC7A
JTAG_MUX_CPU1_GTL_TDI    U21              1        NC7SB3157_SMLF-NC7SB3157P6X,NCA
JTAG_MUX_QS_GTL_TDO      U17              11       74CBTLV3126PW-74CBTLV3126PW,SMA
JTAG_MUX_QS_GTL_TDO      U22              4        NC7SB3157_SMLF-NC7SB3157P6X,NCA
JTAG_PLD_JTAGEN          R919             2        Q_RES_0402LF-10K,1%,1/16W,CHIPA
JTAG_PLD_JTAGEN          R920             1        Q_RES_0402LF-1K,5%,1/16W,EMPTYA
JTAG_PLD_JTAGEN          R931             1        Q_RES_0402LF-0,5%,1/16W,CHIP,CA
JTAG_PLD_JTAGEN          U122             H7       10M04SAU324I7G-10M04SAU324I7G,A
JTAG_PLD_JTAGEN_R        J43              8        CONN10_G2100HT0038071-CONN10_GA
JTAG_PLD_JTAGEN_R        R931             2        Q_RES_0402LF-0,5%,1/16W,CHIP,CA
JTAG_PLD_TCK_R           R806             1        Q_RES_0402LF-33,5%,1/16W,CHIP,A
JTAG_PLD_TCK_R           R1441            1        Q_RES_0402LF-1K,1%,1/16W,CHIP,A
JTAG_PLD_TCK_R           U122             J8       10M04SAU324I7G-10M04SAU324I7G,A
JTAG_PLD_TDI_R           R803             1        Q_RES_0402LF-33,5%,1/16W,CHIP,A
JTAG_PLD_TDI_R           R1438            1        Q_RES_0402LF-10K,1%,1/16W,CHIPA
JTAG_PLD_TDI_R           U122             H3       10M04SAU324I7G-10M04SAU324I7G,A
JTAG_PLD_TDO_R           R804             1        Q_RES_0402LF-33,5%,1/16W,CHIP,A
JTAG_PLD_TDO_R           R1440            1        Q_RES_0402LF-10K,1%,1/16W,EMPTA
JTAG_PLD_TDO_R           U122             H4       10M04SAU324I7G-10M04SAU324I7G,A
JTAG_PLD_TMS_R           R805             1        Q_RES_0402LF-33,5%,1/16W,CHIP,A
JTAG_PLD_TMS_R           R1439            1        Q_RES_0402LF-10K,1%,1/16W,CHIPA
JTAG_PLD_TMS_R           U122             J7       10M04SAU324I7G-10M04SAU324I7G,A
JTAG_QS_MUX_GTL_TDI      U17              6        74CBTLV3126PW-74CBTLV3126PW,SMA
JTAG_QS_MUX_GTL_TDI      U21              4        NC7SB3157_SMLF-NC7SB3157P6X,NCA
JTAG_RISER1_TCK          J55              B2       SCONN140_G64V3431BHR-SCONN140_A
JTAG_RISER1_TCK          R2178            1        Q_RES_0402LF-4.7K,5%,1/16W,EMPA
JTAG_RISER1_TDI          J55              B3       SCONN140_G64V3431BHR-SCONN140_A
JTAG_RISER1_TDI          R2175            1        Q_RES_0402LF-4.7K,5%,1/16W,EMPA
JTAG_RISER1_TDO          J55              B4       SCONN140_G64V3431BHR-SCONN140_A
JTAG_RISER1_TDO          R2176            1        Q_RES_0402LF-4.7K,5%,1/16W,EMPA
JTAG_RISER1_TMS          J55              B42      SCONN140_G64V3431BHR-SCONN140_A
JTAG_RISER1_TMS          R2177            1        Q_RES_0402LF-4.7K,5%,1/16W,EMPA
JTAG_RISER1_TRST_N       J55              B68      SCONN140_G64V3431BHR-SCONN140_A
JTAG_RISER1_TRST_N       R2179            1        Q_RES_0402LF-4.7K,5%,1/16W,EMPA
JTAG_RISER2_TCK          J89              A23      SCONN280_ME1028040102011-SCONNA
JTAG_RISER2_TCK          R1530            1        Q_RES_0402LF-4.7K,5%,1/16W,EMPA
JTAG_RISER2_TDI          J89              A24      SCONN280_ME1028040102011-SCONNA
JTAG_RISER2_TDI          R640             1        Q_RES_0402LF-4.7K,5%,1/16W,EMPA
JTAG_RISER2_TDO          J89              A25      SCONN280_ME1028040102011-SCONNA
JTAG_RISER2_TDO          R1528            1        Q_RES_0402LF-4.7K,5%,1/16W,EMPA
JTAG_RISER2_TMS          J89              A26      SCONN280_ME1028040102011-SCONNA
JTAG_RISER2_TMS          R1529            1        Q_RES_0402LF-4.7K,5%,1/16W,EMPA
JTAG_RISER2_TRST_N       J89              A27      SCONN280_ME1028040102011-SCONNA
JTAG_RISER2_TRST_N       R1531            1        Q_RES_0402LF-4.7K,5%,1/16W,EMPA
JTAG_RISER3_TCK          J57              B2       SCONN140_G64V3431BHR-SCONN140_A
JTAG_RISER3_TCK          R1535            1        Q_RES_0402LF-4.7K,5%,1/16W,EMPA
JTAG_RISER3_TDI          J57              B3       SCONN140_G64V3431BHR-SCONN140_A
JTAG_RISER3_TDI          R1532            1        Q_RES_0402LF-4.7K,5%,1/16W,EMPA
JTAG_RISER3_TDO          J57              B4       SCONN140_G64V3431BHR-SCONN140_A
JTAG_RISER3_TDO          R1533            1        Q_RES_0402LF-4.7K,5%,1/16W,EMPA
JTAG_RISER3_TMS          J57              B42      SCONN140_G64V3431BHR-SCONN140_A
JTAG_RISER3_TMS          R1534            1        Q_RES_0402LF-4.7K,5%,1/16W,EMPA
JTAG_RISER3_TRST_N       J57              B68      SCONN140_G64V3431BHR-SCONN140_A
JTAG_RISER3_TRST_N       R1536            1        Q_RES_0402LF-4.7K,5%,1/16W,EMPA
JTAG_RST_DBP_RSMRST_N    J42              42       SCONN60_QSH03001LDAKTR-SCONN60A
JTAG_RST_DBP_RSMRST_N    R772             1        Q_RES_0402LF-1K,1%,1/16W,CHIP,A
JTAG_RST_DBP_RST_CO_N    C549             1        Q_CAP_0402-0.1UF,25V,10%,X7R,CA
JTAG_RST_DBP_RST_CO_N    J42              6        SCONN60_QSH03001LDAKTR-SCONN60A
JTAG_RST_DBP_RST_CO_N    R767             2        Q_RES_0402LF-1K,1%,1/16W,CHIP,A
JTAG_TRC_PCH_PTI0_CLK    J42              13       SCONN60_QSH03001LDAKTR-SCONN60A
JTAG_TRC_PCH_PTI0_CLK    U4               BD33     EMMITSBURG_REV0P9-GFNOCPU04302A
JTAG_TRC_PCH_PTI1_CLK    J42              59       SCONN60_QSH03001LDAKTR-SCONN60A
JTAG_TRC_PCH_PTI1_CLK    U4               BD23     EMMITSBURG_REV0P9-GFNOCPU04302A
JTAG_TRC_PCH_PTI<0>      J42              19       SCONN60_QSH03001LDAKTR-SCONN60A
JTAG_TRC_PCH_PTI<0>      U4               BE32     EMMITSBURG_REV0P9-GFNOCPU04302A
JTAG_TRC_PCH_PTI<1>      J42              21       SCONN60_QSH03001LDAKTR-SCONN60A
JTAG_TRC_PCH_PTI<1>      U4               BF33     EMMITSBURG_REV0P9-GFNOCPU04302A
JTAG_TRC_PCH_PTI<2>      J42              23       SCONN60_QSH03001LDAKTR-SCONN60A
JTAG_TRC_PCH_PTI<2>      U4               BD31     EMMITSBURG_REV0P9-GFNOCPU04302A
JTAG_TRC_PCH_PTI<3>      J42              25       SCONN60_QSH03001LDAKTR-SCONN60A
JTAG_TRC_PCH_PTI<3>      U4               BE30     EMMITSBURG_REV0P9-GFNOCPU04302A
JTAG_TRC_PCH_PTI<4>      J42              27       SCONN60_QSH03001LDAKTR-SCONN60A
JTAG_TRC_PCH_PTI<4>      U4               BF31     EMMITSBURG_REV0P9-GFNOCPU04302A
JTAG_TRC_PCH_PTI<5>      J42              29       SCONN60_QSH03001LDAKTR-SCONN60A
JTAG_TRC_PCH_PTI<5>      U4               BD29     EMMITSBURG_REV0P9-GFNOCPU04302A
JTAG_TRC_PCH_PTI<6>      J42              31       SCONN60_QSH03001LDAKTR-SCONN60A
JTAG_TRC_PCH_PTI<6>      R2132            1        Q_RES_0402LF-0,5%,1/16W,EMPTY,A
JTAG_TRC_PCH_PTI<6>      R2134            1        Q_RES_0402LF-10K,1%,1/16W,CHIPA
JTAG_TRC_PCH_PTI<6>      S1               8        SW8S_DHNF04FTVTR-SW8S_DHNF04FTA
JTAG_TRC_PCH_PTI<6>      U4               BE28     EMMITSBURG_REV0P9-GFNOCPU04302A
JTAG_TRC_PCH_PTI<7>      J42              33       SCONN60_QSH03001LDAKTR-SCONN60A
JTAG_TRC_PCH_PTI<7>      U4               BF29     EMMITSBURG_REV0P9-GFNOCPU04302A
JTAG_TRC_PCH_PTI<8>      J42              35       SCONN60_QSH03001LDAKTR-SCONN60A
JTAG_TRC_PCH_PTI<8>      U4               BD27     EMMITSBURG_REV0P9-GFNOCPU04302A
JTAG_TRC_PCH_PTI<9>      J42              37       SCONN60_QSH03001LDAKTR-SCONN60A
JTAG_TRC_PCH_PTI<9>      U4               BE26     EMMITSBURG_REV0P9-GFNOCPU04302A
JTAG_TRC_PCH_PTI<10>     J42              39       SCONN60_QSH03001LDAKTR-SCONN60A
JTAG_TRC_PCH_PTI<10>     U4               BF27     EMMITSBURG_REV0P9-GFNOCPU04302A
JTAG_TRC_PCH_PTI<11>     J42              41       SCONN60_QSH03001LDAKTR-SCONN60A
JTAG_TRC_PCH_PTI<11>     U4               BD25     EMMITSBURG_REV0P9-GFNOCPU04302A
JTAG_TRC_PCH_PTI<12>     J42              43       SCONN60_QSH03001LDAKTR-SCONN60A
JTAG_TRC_PCH_PTI<12>     U4               BF25     EMMITSBURG_REV0P9-GFNOCPU04302A
JTAG_TRC_PCH_PTI<13>     J42              45       SCONN60_QSH03001LDAKTR-SCONN60A
JTAG_TRC_PCH_PTI<13>     U4               BE24     EMMITSBURG_REV0P9-GFNOCPU04302A
JTAG_TRC_PCH_PTI<14>     J42              47       SCONN60_QSH03001LDAKTR-SCONN60A
JTAG_TRC_PCH_PTI<14>     U4               BF23     EMMITSBURG_REV0P9-GFNOCPU04302A
JTAG_TRC_PCH_PTI<15>     J42              49       SCONN60_QSH03001LDAKTR-SCONN60A
JTAG_TRC_PCH_PTI<15>     U4               BE22     EMMITSBURG_REV0P9-GFNOCPU04302A
LED_CPU_RMCA_CATERR      D6               A        Q_LED_SMLF-LED_RED,19-217/R6C-A
LED_CPU_RMCA_CATERR      R366             1        Q_RES_0402LF-332,1%,1/16W,CHIPA
LED_CPU_RMCA_CATERR_R    Q33              S        MOSFET_PCH_GDS_ESD_PROTECTED-PA
LED_CPU_RMCA_CATERR_R    R366             2        Q_RES_0402LF-332,1%,1/16W,CHIPA
M2_SSD0_CLKREQ_EN_N      R486             1        Q_RES_0402LF-0,5%,1/16W,CHIP,CA
M2_SSD0_CLKREQ_EN_N      R491             1        Q_RES_0402LF-4.7K,1%,1/16W,EMPA
M2_SSD0_CLKREQ_EN_N      R1778            1        Q_RES_0402LF-0,5%,1/16W,EMPTY,A
M2_SSD0_CLKREQ_EN_N      U54              2        74LVC1G07GV-74LVC1G07GV,SMLF,IA
M2_SSD0_CLKREQ_EN_N_BUF  J59              52       SCONN75K_APCI0155P004A-SCONN75A
M2_SSD0_CLKREQ_EN_N_BUF  R486             2        Q_RES_0402LF-0,5%,1/16W,CHIP,CA
M2_SSD0_CLKREQ_EN_N_BUF  R487             2        Q_RES_0402LF-1K,1%,1/16W,EMPTYA
M2_SSD0_CLKREQ_LV_EN_N   R1697            2        Q_RES_0402LF-10K,1%,1/16W,CHIPA
M2_SSD0_CLKREQ_LV_EN_N   R1778            2        Q_RES_0402LF-0,5%,1/16W,EMPTY,A
M2_SSD0_CLKREQ_LV_EN_N   U4               BG16     EMMITSBURG_REV0P9-GFNOCPU04302A
M2_SSD0_CLKREQ_LV_EN_N   U54              4        74LVC1G07GV-74LVC1G07GV,SMLF,IA
MB_FRU_ADDR0             R721             2        Q_RES_0402LF-10K,1%,1/16W,CHIPA
MB_FRU_ADDR0             R722             1        Q_RES_0402LF-1K,1%,1/16W,EMPTYA
MB_FRU_ADDR0             U64              1        M24128BWDW6TP-M24128-BWDW6TP,SA
MB_FRU_ADDR1             R717             2        Q_RES_0402LF-10K,1%,1/16W,EMPTA
MB_FRU_ADDR1             R718             1        Q_RES_0402LF-1K,1%,1/16W,CHIP,A
MB_FRU_ADDR1             U64              2        M24128BWDW6TP-M24128-BWDW6TP,SA
MB_FRU_ADDR2             R713             2        Q_RES_0402LF-10K,1%,1/16W,EMPTA
MB_FRU_ADDR2             R714             1        Q_RES_0402LF-1K,1%,1/16W,CHIP,A
MB_FRU_ADDR2             U64              3        M24128BWDW6TP-M24128-BWDW6TP,SA
MP5981_0_CLREF           C1580            1        Q_CAP_0402-1NF,50V,10%,X7R,CH2A
MP5981_0_CLREF           R2075            1        Q_RES_0402LF-120K,1%,1/16W,CHIA
MP5981_0_CLREF           U107             24       MP5981GLUZ-MP5981GLU-Z,SMLF,ICA
MP5981_0_CS              R2076            1        Q_RES_0402LF-2.4K,1%,1/16W,CHIA
MP5981_0_CS              U107             23       MP5981GLUZ-MP5981GLU-Z,SMLF,ICA
MP5981_0_ON_PD           C1582            1        Q_CAP_C0402-100NF,50V,10%,X7R,A
MP5981_0_ON_PD           U107             4        MP5981GLUZ-MP5981GLU-Z,SMLF,ICA
MP5981_1_CLREF           C1585            1        Q_CAP_0402-1NF,50V,10%,X7R,CH2A
MP5981_1_CLREF           R2087            1        Q_RES_0402LF-120K,1%,1/16W,CHIA
MP5981_1_CLREF           U81              24       MP5981GLUZ-MP5981GLU-Z,SMLF,ICA
MP5981_1_CS              R2088            1        Q_RES_0402LF-2.4K,1%,1/16W,CHIA
MP5981_1_CS              U81              23       MP5981GLUZ-MP5981GLU-Z,SMLF,ICA
MP5981_1_ON_PD           C1584            1        Q_CAP_C0402-100NF,50V,10%,X7R,A
MP5981_1_ON_PD           U81              4        MP5981GLUZ-MP5981GLU-Z,SMLF,ICA
MPS5981_1_SS             C1586            1        Q_CAP_C0402-100NF,50V,10%,X7R,A
MPS5981_1_SS             U81              19       MP5981GLUZ-MP5981GLU-Z,SMLF,ICA
MPS5981_SS               C1583            1        Q_CAP_C0402-100NF,50V,10%,X7R,A
MPS5981_SS               U107             19       MP5981GLUZ-MP5981GLU-Z,SMLF,ICA
M_A_CPU0_ALERT_N         J1               62       SCONN288_ADR50001P013C01-SCONNA
M_A_CPU0_ALERT_N         J2               62       SCONN288_ADR50001P003C01-SCONNA
M_A_CPU0_ALERT_N         U2               AT49     SOCKET4677_AZIFS054P001C01-SOCA
M_A_CPU0_CLK_DN<0>       J1               218      SCONN288_ADR50001P013C01-SCONNA
M_A_CPU0_CLK_DN<0>       U2               B44      SOCKET4677_AZIFS054P001C01-SOCA
M_A_CPU0_CLK_DN<1>       J2               218      SCONN288_ADR50001P003C01-SCONNA
M_A_CPU0_CLK_DN<1>       U2               G45      SOCKET4677_AZIFS054P001C01-SOCA
M_A_CPU0_CLK_DP<0>       J1               217      SCONN288_ADR50001P013C01-SCONNA
M_A_CPU0_CLK_DP<0>       U2               C43      SOCKET4677_AZIFS054P001C01-SOCA
M_A_CPU0_CLK_DP<1>       J2               217      SCONN288_ADR50001P003C01-SCONNA
M_A_CPU0_CLK_DP<1>       U2               E45      SOCKET4677_AZIFS054P001C01-SOCA
M_A_CPU0_SA_CA<0>        J1               66       SCONN288_ADR50001P013C01-SCONNA
M_A_CPU0_SA_CA<0>        J2               66       SCONN288_ADR50001P003C01-SCONNA
M_A_CPU0_SA_CA<0>        U2               A52      SOCKET4677_AZIFS054P001C01-SOCA
M_A_CPU0_SA_CA<1>        J1               211      SCONN288_ADR50001P013C01-SCONNA
M_A_CPU0_SA_CA<1>        J2               211      SCONN288_ADR50001P003C01-SCONNA
M_A_CPU0_SA_CA<1>        U2               G52      SOCKET4677_AZIFS054P001C01-SOCA
M_A_CPU0_SA_CA<2>        J1               68       SCONN288_ADR50001P013C01-SCONNA
M_A_CPU0_SA_CA<2>        J2               68       SCONN288_ADR50001P003C01-SCONNA
M_A_CPU0_SA_CA<2>        U2               B51      SOCKET4677_AZIFS054P001C01-SOCA
M_A_CPU0_SA_CA<3>        J1               213      SCONN288_ADR50001P013C01-SCONNA
M_A_CPU0_SA_CA<3>        J2               213      SCONN288_ADR50001P003C01-SCONNA
M_A_CPU0_SA_CA<3>        U2               F51      SOCKET4677_AZIFS054P001C01-SOCA
M_A_CPU0_SA_CA<4>        J1               70       SCONN288_ADR50001P013C01-SCONNA
M_A_CPU0_SA_CA<4>        J2               70       SCONN288_ADR50001P003C01-SCONNA
M_A_CPU0_SA_CA<4>        U2               C50      SOCKET4677_AZIFS054P001C01-SOCA
M_A_CPU0_SA_CA<5>        J1               215      SCONN288_ADR50001P013C01-SCONNA
M_A_CPU0_SA_CA<5>        J2               215      SCONN288_ADR50001P003C01-SCONNA
M_A_CPU0_SA_CA<5>        U2               E50      SOCKET4677_AZIFS054P001C01-SOCA
M_A_CPU0_SA_CA<6>        J1               72       SCONN288_ADR50001P013C01-SCONNA
M_A_CPU0_SA_CA<6>        J2               72       SCONN288_ADR50001P003C01-SCONNA
M_A_CPU0_SA_CA<6>        U2               C48      SOCKET4677_AZIFS054P001C01-SOCA
M_A_CPU0_SA_CB<0>        J1               51       SCONN288_ADR50001P013C01-SCONNA
M_A_CPU0_SA_CB<0>        J2               51       SCONN288_ADR50001P003C01-SCONNA
M_A_CPU0_SA_CB<0>        U2               C60      SOCKET4677_AZIFS054P001C01-SOCA
M_A_CPU0_SA_CB<1>        J1               53       SCONN288_ADR50001P013C01-SCONNA
M_A_CPU0_SA_CB<1>        J2               53       SCONN288_ADR50001P003C01-SCONNA
M_A_CPU0_SA_CB<1>        U2               B59      SOCKET4677_AZIFS054P001C01-SOCA
M_A_CPU0_SA_CB<2>        J1               196      SCONN288_ADR50001P013C01-SCONNA
M_A_CPU0_SA_CB<2>        J2               196      SCONN288_ADR50001P003C01-SCONNA
M_A_CPU0_SA_CB<2>        U2               E60      SOCKET4677_AZIFS054P001C01-SOCA
M_A_CPU0_SA_CB<3>        J1               198      SCONN288_ADR50001P013C01-SCONNA
M_A_CPU0_SA_CB<3>        J2               198      SCONN288_ADR50001P003C01-SCONNA
M_A_CPU0_SA_CB<3>        U2               F59      SOCKET4677_AZIFS054P001C01-SOCA
M_A_CPU0_SA_CB<4>        J1               58       SCONN288_ADR50001P013C01-SCONNA
M_A_CPU0_SA_CB<4>        J2               58       SCONN288_ADR50001P003C01-SCONNA
M_A_CPU0_SA_CB<4>        U2               B57      SOCKET4677_AZIFS054P001C01-SOCA
M_A_CPU0_SA_CB<5>        J1               60       SCONN288_ADR50001P013C01-SCONNA
M_A_CPU0_SA_CB<5>        J2               60       SCONN288_ADR50001P003C01-SCONNA
M_A_CPU0_SA_CB<5>        U2               C56      SOCKET4677_AZIFS054P001C01-SOCA
M_A_CPU0_SA_CB<6>        J1               203      SCONN288_ADR50001P013C01-SCONNA
M_A_CPU0_SA_CB<6>        J2               203      SCONN288_ADR50001P003C01-SCONNA
M_A_CPU0_SA_CB<6>        U2               F57      SOCKET4677_AZIFS054P001C01-SOCA
M_A_CPU0_SA_CB<7>        J1               205      SCONN288_ADR50001P013C01-SCONNA
M_A_CPU0_SA_CB<7>        J2               205      SCONN288_ADR50001P003C01-SCONNA
M_A_CPU0_SA_CB<7>        U2               E56      SOCKET4677_AZIFS054P001C01-SOCA
M_A_CPU0_SA_CS_N<0>      J1               64       SCONN288_ADR50001P013C01-SCONNA
M_A_CPU0_SA_CS_N<0>      U2               C54      SOCKET4677_AZIFS054P001C01-SOCA
M_A_CPU0_SA_CS_N<1>      J1               209      SCONN288_ADR50001P013C01-SCONNA
M_A_CPU0_SA_CS_N<1>      U2               B53      SOCKET4677_AZIFS054P001C01-SOCA
M_A_CPU0_SA_CS_N<2>      J2               64       SCONN288_ADR50001P003C01-SCONNA
M_A_CPU0_SA_CS_N<2>      U2               E54      SOCKET4677_AZIFS054P001C01-SOCA
M_A_CPU0_SA_CS_N<3>      J2               209      SCONN288_ADR50001P003C01-SCONNA
M_A_CPU0_SA_CS_N<3>      U2               F53      SOCKET4677_AZIFS054P001C01-SOCA
M_A_CPU0_SA_DQ<0>        J1               7        SCONN288_ADR50001P013C01-SCONNA
M_A_CPU0_SA_DQ<0>        J2               7        SCONN288_ADR50001P003C01-SCONNA
M_A_CPU0_SA_DQ<0>        U2               B81      SOCKET4677_AZIFS054P001C01-SOCA
M_A_CPU0_SA_DQ<1>        J1               9        SCONN288_ADR50001P013C01-SCONNA
M_A_CPU0_SA_DQ<1>        J2               9        SCONN288_ADR50001P003C01-SCONNA
M_A_CPU0_SA_DQ<1>        U2               B79      SOCKET4677_AZIFS054P001C01-SOCA
M_A_CPU0_SA_DQ<2>        J1               152      SCONN288_ADR50001P013C01-SCONNA
M_A_CPU0_SA_DQ<2>        J2               152      SCONN288_ADR50001P003C01-SCONNA
M_A_CPU0_SA_DQ<2>        U2               M77      SOCKET4677_AZIFS054P001C01-SOCA
M_A_CPU0_SA_DQ<3>        J1               154      SCONN288_ADR50001P013C01-SCONNA
M_A_CPU0_SA_DQ<3>        J2               154      SCONN288_ADR50001P003C01-SCONNA
M_A_CPU0_SA_DQ<3>        U2               G78      SOCKET4677_AZIFS054P001C01-SOCA
M_A_CPU0_SA_DQ<4>        J1               14       SCONN288_ADR50001P013C01-SCONNA
M_A_CPU0_SA_DQ<4>        J2               14       SCONN288_ADR50001P003C01-SCONNA
M_A_CPU0_SA_DQ<4>        U2               C76      SOCKET4677_AZIFS054P001C01-SOCA
M_A_CPU0_SA_DQ<5>        J1               16       SCONN288_ADR50001P013C01-SCONNA
M_A_CPU0_SA_DQ<5>        J2               16       SCONN288_ADR50001P003C01-SCONNA
M_A_CPU0_SA_DQ<5>        U2               D75      SOCKET4677_AZIFS054P001C01-SOCA
M_A_CPU0_SA_DQ<6>        J1               159      SCONN288_ADR50001P013C01-SCONNA
M_A_CPU0_SA_DQ<6>        J2               159      SCONN288_ADR50001P003C01-SCONNA
M_A_CPU0_SA_DQ<6>        U2               G76      SOCKET4677_AZIFS054P001C01-SOCA
M_A_CPU0_SA_DQ<7>        J1               161      SCONN288_ADR50001P013C01-SCONNA
M_A_CPU0_SA_DQ<7>        J2               161      SCONN288_ADR50001P003C01-SCONNA
M_A_CPU0_SA_DQ<7>        U2               F75      SOCKET4677_AZIFS054P001C01-SOCA
M_A_CPU0_SA_DQ<8>        J1               18       SCONN288_ADR50001P013C01-SCONNA
M_A_CPU0_SA_DQ<8>        J2               18       SCONN288_ADR50001P003C01-SCONNA
M_A_CPU0_SA_DQ<8>        U2               K69      SOCKET4677_AZIFS054P001C01-SOCA
M_A_CPU0_SA_DQ<9>        J1               20       SCONN288_ADR50001P013C01-SCONNA
M_A_CPU0_SA_DQ<9>        J2               20       SCONN288_ADR50001P003C01-SCONNA
M_A_CPU0_SA_DQ<9>        U2               J68      SOCKET4677_AZIFS054P001C01-SOCA
M_A_CPU0_SA_DQ<10>       J1               163      SCONN288_ADR50001P013C01-SCONNA
M_A_CPU0_SA_DQ<10>       J2               163      SCONN288_ADR50001P003C01-SCONNA
M_A_CPU0_SA_DQ<10>       U2               M69      SOCKET4677_AZIFS054P001C01-SOCA
M_A_CPU0_SA_DQ<11>       J1               165      SCONN288_ADR50001P013C01-SCONNA
M_A_CPU0_SA_DQ<11>       J2               165      SCONN288_ADR50001P003C01-SCONNA
M_A_CPU0_SA_DQ<11>       U2               N68      SOCKET4677_AZIFS054P001C01-SOCA
M_A_CPU0_SA_DQ<12>       J1               25       SCONN288_ADR50001P013C01-SCONNA
M_A_CPU0_SA_DQ<12>       J2               25       SCONN288_ADR50001P003C01-SCONNA
M_A_CPU0_SA_DQ<12>       U2               J66      SOCKET4677_AZIFS054P001C01-SOCA
M_A_CPU0_SA_DQ<13>       J1               27       SCONN288_ADR50001P013C01-SCONNA
M_A_CPU0_SA_DQ<13>       J2               27       SCONN288_ADR50001P003C01-SCONNA
M_A_CPU0_SA_DQ<13>       U2               K65      SOCKET4677_AZIFS054P001C01-SOCA
M_A_CPU0_SA_DQ<14>       J1               170      SCONN288_ADR50001P013C01-SCONNA
M_A_CPU0_SA_DQ<14>       J2               170      SCONN288_ADR50001P003C01-SCONNA
M_A_CPU0_SA_DQ<14>       U2               N66      SOCKET4677_AZIFS054P001C01-SOCA
M_A_CPU0_SA_DQ<15>       J1               172      SCONN288_ADR50001P013C01-SCONNA
M_A_CPU0_SA_DQ<15>       J2               172      SCONN288_ADR50001P003C01-SCONNA
M_A_CPU0_SA_DQ<15>       U2               M65      SOCKET4677_AZIFS054P001C01-SOCA
M_A_CPU0_SA_DQ<16>       J1               29       SCONN288_ADR50001P013C01-SCONNA
M_A_CPU0_SA_DQ<16>       J2               29       SCONN288_ADR50001P003C01-SCONNA
M_A_CPU0_SA_DQ<16>       U2               B73      SOCKET4677_AZIFS054P001C01-SOCA
M_A_CPU0_SA_DQ<17>       J1               31       SCONN288_ADR50001P013C01-SCONNA
M_A_CPU0_SA_DQ<17>       J2               31       SCONN288_ADR50001P003C01-SCONNA
M_A_CPU0_SA_DQ<17>       U2               E72      SOCKET4677_AZIFS054P001C01-SOCA
M_A_CPU0_SA_DQ<18>       J1               174      SCONN288_ADR50001P013C01-SCONNA
M_A_CPU0_SA_DQ<18>       J2               174      SCONN288_ADR50001P003C01-SCONNA
M_A_CPU0_SA_DQ<18>       U2               D73      SOCKET4677_AZIFS054P001C01-SOCA
M_A_CPU0_SA_DQ<19>       J1               176      SCONN288_ADR50001P013C01-SCONNA
M_A_CPU0_SA_DQ<19>       J2               176      SCONN288_ADR50001P003C01-SCONNA
M_A_CPU0_SA_DQ<19>       U2               F71      SOCKET4677_AZIFS054P001C01-SOCA
M_A_CPU0_SA_DQ<20>       J1               36       SCONN288_ADR50001P013C01-SCONNA
M_A_CPU0_SA_DQ<20>       J2               36       SCONN288_ADR50001P003C01-SCONNA
M_A_CPU0_SA_DQ<20>       U2               B69      SOCKET4677_AZIFS054P001C01-SOCA
M_A_CPU0_SA_DQ<21>       J1               38       SCONN288_ADR50001P013C01-SCONNA
M_A_CPU0_SA_DQ<21>       J2               38       SCONN288_ADR50001P003C01-SCONNA
M_A_CPU0_SA_DQ<21>       U2               C68      SOCKET4677_AZIFS054P001C01-SOCA
M_A_CPU0_SA_DQ<22>       J1               181      SCONN288_ADR50001P013C01-SCONNA
M_A_CPU0_SA_DQ<22>       J2               181      SCONN288_ADR50001P003C01-SCONNA
M_A_CPU0_SA_DQ<22>       U2               F69      SOCKET4677_AZIFS054P001C01-SOCA
M_A_CPU0_SA_DQ<23>       J1               183      SCONN288_ADR50001P013C01-SCONNA
M_A_CPU0_SA_DQ<23>       J2               183      SCONN288_ADR50001P003C01-SCONNA
M_A_CPU0_SA_DQ<23>       U2               E68      SOCKET4677_AZIFS054P001C01-SOCA
M_A_CPU0_SA_DQ<24>       J1               40       SCONN288_ADR50001P013C01-SCONNA
M_A_CPU0_SA_DQ<24>       J2               40       SCONN288_ADR50001P003C01-SCONNA
M_A_CPU0_SA_DQ<24>       U2               C66      SOCKET4677_AZIFS054P001C01-SOCA
M_A_CPU0_SA_DQ<25>       J1               42       SCONN288_ADR50001P013C01-SCONNA
M_A_CPU0_SA_DQ<25>       J2               42       SCONN288_ADR50001P003C01-SCONNA
M_A_CPU0_SA_DQ<25>       U2               B65      SOCKET4677_AZIFS054P001C01-SOCA
M_A_CPU0_SA_DQ<26>       J1               185      SCONN288_ADR50001P013C01-SCONNA
M_A_CPU0_SA_DQ<26>       J2               185      SCONN288_ADR50001P003C01-SCONNA
M_A_CPU0_SA_DQ<26>       U2               E66      SOCKET4677_AZIFS054P001C01-SOCA
M_A_CPU0_SA_DQ<27>       J1               187      SCONN288_ADR50001P013C01-SCONNA
M_A_CPU0_SA_DQ<27>       J2               187      SCONN288_ADR50001P003C01-SCONNA
M_A_CPU0_SA_DQ<27>       U2               F65      SOCKET4677_AZIFS054P001C01-SOCA
M_A_CPU0_SA_DQ<28>       J1               47       SCONN288_ADR50001P013C01-SCONNA
M_A_CPU0_SA_DQ<28>       J2               47       SCONN288_ADR50001P003C01-SCONNA
M_A_CPU0_SA_DQ<28>       U2               B63      SOCKET4677_AZIFS054P001C01-SOCA
M_A_CPU0_SA_DQ<29>       J1               49       SCONN288_ADR50001P013C01-SCONNA
M_A_CPU0_SA_DQ<29>       J2               49       SCONN288_ADR50001P003C01-SCONNA
M_A_CPU0_SA_DQ<29>       U2               C62      SOCKET4677_AZIFS054P001C01-SOCA
M_A_CPU0_SA_DQ<30>       J1               192      SCONN288_ADR50001P013C01-SCONNA
M_A_CPU0_SA_DQ<30>       J2               192      SCONN288_ADR50001P003C01-SCONNA
M_A_CPU0_SA_DQ<30>       U2               F63      SOCKET4677_AZIFS054P001C01-SOCA
M_A_CPU0_SA_DQ<31>       J1               194      SCONN288_ADR50001P013C01-SCONNA
M_A_CPU0_SA_DQ<31>       J2               194      SCONN288_ADR50001P003C01-SCONNA
M_A_CPU0_SA_DQ<31>       U2               E62      SOCKET4677_AZIFS054P001C01-SOCA
M_A_CPU0_SA_DQS_DN<0>    J1               12       SCONN288_ADR50001P013C01-SCONNA
M_A_CPU0_SA_DQS_DN<0>    J2               12       SCONN288_ADR50001P003C01-SCONNA
M_A_CPU0_SA_DQS_DN<0>    U2               B77      SOCKET4677_AZIFS054P001C01-SOCA
M_A_CPU0_SA_DQS_DN<1>    J1               23       SCONN288_ADR50001P013C01-SCONNA
M_A_CPU0_SA_DQS_DN<1>    J2               23       SCONN288_ADR50001P003C01-SCONNA
M_A_CPU0_SA_DQS_DN<1>    U2               H67      SOCKET4677_AZIFS054P001C01-SOCA
M_A_CPU0_SA_DQS_DN<2>    J1               34       SCONN288_ADR50001P013C01-SCONNA
M_A_CPU0_SA_DQS_DN<2>    J2               34       SCONN288_ADR50001P003C01-SCONNA
M_A_CPU0_SA_DQS_DN<2>    U2               B71      SOCKET4677_AZIFS054P001C01-SOCA
M_A_CPU0_SA_DQS_DN<3>    J1               45       SCONN288_ADR50001P013C01-SCONNA
M_A_CPU0_SA_DQS_DN<3>    J2               45       SCONN288_ADR50001P003C01-SCONNA
M_A_CPU0_SA_DQS_DN<3>    U2               A64      SOCKET4677_AZIFS054P001C01-SOCA
M_A_CPU0_SA_DQS_DN<4>    J1               56       SCONN288_ADR50001P013C01-SCONNA
M_A_CPU0_SA_DQS_DN<4>    J2               56       SCONN288_ADR50001P003C01-SCONNA
M_A_CPU0_SA_DQS_DN<4>    U2               A58      SOCKET4677_AZIFS054P001C01-SOCA
M_A_CPU0_SA_DQS_DN<5>    J1               156      SCONN288_ADR50001P013C01-SCONNA
M_A_CPU0_SA_DQS_DN<5>    J2               156      SCONN288_ADR50001P003C01-SCONNA
M_A_CPU0_SA_DQS_DN<5>    U2               H77      SOCKET4677_AZIFS054P001C01-SOCA
M_A_CPU0_SA_DQS_DN<6>    J1               167      SCONN288_ADR50001P013C01-SCONNA
M_A_CPU0_SA_DQS_DN<6>    J2               167      SCONN288_ADR50001P003C01-SCONNA
M_A_CPU0_SA_DQS_DN<6>    U2               P67      SOCKET4677_AZIFS054P001C01-SOCA
M_A_CPU0_SA_DQS_DN<7>    J1               178      SCONN288_ADR50001P013C01-SCONNA
M_A_CPU0_SA_DQS_DN<7>    J2               178      SCONN288_ADR50001P003C01-SCONNA
M_A_CPU0_SA_DQS_DN<7>    U2               G70      SOCKET4677_AZIFS054P001C01-SOCA
M_A_CPU0_SA_DQS_DN<8>    J1               189      SCONN288_ADR50001P013C01-SCONNA
M_A_CPU0_SA_DQS_DN<8>    J2               189      SCONN288_ADR50001P003C01-SCONNA
M_A_CPU0_SA_DQS_DN<8>    U2               G64      SOCKET4677_AZIFS054P001C01-SOCA
M_A_CPU0_SA_DQS_DN<9>    J1               200      SCONN288_ADR50001P013C01-SCONNA
M_A_CPU0_SA_DQS_DN<9>    J2               200      SCONN288_ADR50001P003C01-SCONNA
M_A_CPU0_SA_DQS_DN<9>    U2               G58      SOCKET4677_AZIFS054P001C01-SOCA
M_A_CPU0_SA_DQS_DP<0>    J1               11       SCONN288_ADR50001P013C01-SCONNA
M_A_CPU0_SA_DQS_DP<0>    J2               11       SCONN288_ADR50001P003C01-SCONNA
M_A_CPU0_SA_DQS_DP<0>    U2               D77      SOCKET4677_AZIFS054P001C01-SOCA
M_A_CPU0_SA_DQS_DP<1>    J1               22       SCONN288_ADR50001P013C01-SCONNA
M_A_CPU0_SA_DQS_DP<1>    J2               22       SCONN288_ADR50001P003C01-SCONNA
M_A_CPU0_SA_DQS_DP<1>    U2               K67      SOCKET4677_AZIFS054P001C01-SOCA
M_A_CPU0_SA_DQS_DP<2>    J1               33       SCONN288_ADR50001P013C01-SCONNA
M_A_CPU0_SA_DQS_DP<2>    J2               33       SCONN288_ADR50001P003C01-SCONNA
M_A_CPU0_SA_DQS_DP<2>    U2               C70      SOCKET4677_AZIFS054P001C01-SOCA
M_A_CPU0_SA_DQS_DP<3>    J1               44       SCONN288_ADR50001P013C01-SCONNA
M_A_CPU0_SA_DQS_DP<3>    J2               44       SCONN288_ADR50001P003C01-SCONNA
M_A_CPU0_SA_DQS_DP<3>    U2               C64      SOCKET4677_AZIFS054P001C01-SOCA
M_A_CPU0_SA_DQS_DP<4>    J1               55       SCONN288_ADR50001P013C01-SCONNA
M_A_CPU0_SA_DQS_DP<4>    J2               55       SCONN288_ADR50001P003C01-SCONNA
M_A_CPU0_SA_DQS_DP<4>    U2               C58      SOCKET4677_AZIFS054P001C01-SOCA
M_A_CPU0_SA_DQS_DP<5>    J1               157      SCONN288_ADR50001P013C01-SCONNA
M_A_CPU0_SA_DQS_DP<5>    J2               157      SCONN288_ADR50001P003C01-SCONNA
M_A_CPU0_SA_DQS_DP<5>    U2               F77      SOCKET4677_AZIFS054P001C01-SOCA
M_A_CPU0_SA_DQS_DP<6>    J1               168      SCONN288_ADR50001P013C01-SCONNA
M_A_CPU0_SA_DQS_DP<6>    J2               168      SCONN288_ADR50001P003C01-SCONNA
M_A_CPU0_SA_DQS_DP<6>    U2               M67      SOCKET4677_AZIFS054P001C01-SOCA
M_A_CPU0_SA_DQS_DP<7>    J1               179      SCONN288_ADR50001P013C01-SCONNA
M_A_CPU0_SA_DQS_DP<7>    J2               179      SCONN288_ADR50001P003C01-SCONNA
M_A_CPU0_SA_DQS_DP<7>    U2               E70      SOCKET4677_AZIFS054P001C01-SOCA
M_A_CPU0_SA_DQS_DP<8>    J1               190      SCONN288_ADR50001P013C01-SCONNA
M_A_CPU0_SA_DQS_DP<8>    J2               190      SCONN288_ADR50001P003C01-SCONNA
M_A_CPU0_SA_DQS_DP<8>    U2               E64      SOCKET4677_AZIFS054P001C01-SOCA
M_A_CPU0_SA_DQS_DP<9>    J1               201      SCONN288_ADR50001P013C01-SCONNA
M_A_CPU0_SA_DQS_DP<9>    J2               201      SCONN288_ADR50001P003C01-SCONNA
M_A_CPU0_SA_DQS_DP<9>    U2               E58      SOCKET4677_AZIFS054P001C01-SOCA
M_A_CPU0_SA_PAR          J1               74       SCONN288_ADR50001P013C01-SCONNA
M_A_CPU0_SA_PAR          J2               74       SCONN288_ADR50001P003C01-SCONNA
M_A_CPU0_SA_PAR          U2               E48      SOCKET4677_AZIFS054P001C01-SOCA
M_A_CPU0_SA_RSP<0>       J1               86       SCONN288_ADR50001P013C01-SCONNA
M_A_CPU0_SA_RSP<0>       U2               AT42     SOCKET4677_AZIFS054P001C01-SOCA
M_A_CPU0_SA_RSP<1>       J2               86       SCONN288_ADR50001P003C01-SCONNA
M_A_CPU0_SA_RSP<1>       U2               AU43     SOCKET4677_AZIFS054P001C01-SOCA
M_A_CPU0_SB_CA<0>        J1               76       SCONN288_ADR50001P013C01-SCONNA
M_A_CPU0_SB_CA<0>        J2               76       SCONN288_ADR50001P003C01-SCONNA
M_A_CPU0_SB_CA<0>        U2               E43      SOCKET4677_AZIFS054P001C01-SOCA
M_A_CPU0_SB_CA<1>        J1               221      SCONN288_ADR50001P013C01-SCONNA
M_A_CPU0_SB_CA<1>        J2               221      SCONN288_ADR50001P003C01-SCONNA
M_A_CPU0_SB_CA<1>        U2               F44      SOCKET4677_AZIFS054P001C01-SOCA
M_A_CPU0_SB_CA<2>        J1               78       SCONN288_ADR50001P013C01-SCONNA
M_A_CPU0_SB_CA<2>        J2               78       SCONN288_ADR50001P003C01-SCONNA
M_A_CPU0_SB_CA<2>        U2               C41      SOCKET4677_AZIFS054P001C01-SOCA
M_A_CPU0_SB_CA<3>        J1               223      SCONN288_ADR50001P013C01-SCONNA
M_A_CPU0_SB_CA<3>        J2               223      SCONN288_ADR50001P003C01-SCONNA
M_A_CPU0_SB_CA<3>        U2               E41      SOCKET4677_AZIFS054P001C01-SOCA
M_A_CPU0_SB_CA<4>        J1               80       SCONN288_ADR50001P013C01-SCONNA
M_A_CPU0_SB_CA<4>        J2               80       SCONN288_ADR50001P003C01-SCONNA
M_A_CPU0_SB_CA<4>        U2               B40      SOCKET4677_AZIFS054P001C01-SOCA
M_A_CPU0_SB_CA<5>        J1               225      SCONN288_ADR50001P013C01-SCONNA
M_A_CPU0_SB_CA<5>        J2               225      SCONN288_ADR50001P003C01-SCONNA
M_A_CPU0_SB_CA<5>        U2               F40      SOCKET4677_AZIFS054P001C01-SOCA
M_A_CPU0_SB_CA<6>        J1               82       SCONN288_ADR50001P013C01-SCONNA
M_A_CPU0_SB_CA<6>        J2               82       SCONN288_ADR50001P003C01-SCONNA
M_A_CPU0_SB_CA<6>        U2               A39      SOCKET4677_AZIFS054P001C01-SOCA
M_A_CPU0_SB_CB<0>        J1               96       SCONN288_ADR50001P013C01-SCONNA
M_A_CPU0_SB_CB<0>        J2               96       SCONN288_ADR50001P003C01-SCONNA
M_A_CPU0_SB_CB<0>        U2               B32      SOCKET4677_AZIFS054P001C01-SOCA
M_A_CPU0_SB_CB<1>        J1               98       SCONN288_ADR50001P013C01-SCONNA
M_A_CPU0_SB_CB<1>        J2               98       SCONN288_ADR50001P003C01-SCONNA
M_A_CPU0_SB_CB<1>        U2               C31      SOCKET4677_AZIFS054P001C01-SOCA
M_A_CPU0_SB_CB<2>        J1               241      SCONN288_ADR50001P013C01-SCONNA
M_A_CPU0_SB_CB<2>        J2               241      SCONN288_ADR50001P003C01-SCONNA
M_A_CPU0_SB_CB<2>        U2               F32      SOCKET4677_AZIFS054P001C01-SOCA
M_A_CPU0_SB_CB<3>        J1               243      SCONN288_ADR50001P013C01-SCONNA
M_A_CPU0_SB_CB<3>        J2               243      SCONN288_ADR50001P003C01-SCONNA
M_A_CPU0_SB_CB<3>        U2               E31      SOCKET4677_AZIFS054P001C01-SOCA
M_A_CPU0_SB_CB<4>        J1               89       SCONN288_ADR50001P013C01-SCONNA
M_A_CPU0_SB_CB<4>        J2               89       SCONN288_ADR50001P003C01-SCONNA
M_A_CPU0_SB_CB<4>        U2               C35      SOCKET4677_AZIFS054P001C01-SOCA
M_A_CPU0_SB_CB<5>        J1               91       SCONN288_ADR50001P013C01-SCONNA
M_A_CPU0_SB_CB<5>        J2               91       SCONN288_ADR50001P003C01-SCONNA
M_A_CPU0_SB_CB<5>        U2               B34      SOCKET4677_AZIFS054P001C01-SOCA
M_A_CPU0_SB_CB<6>        J1               234      SCONN288_ADR50001P013C01-SCONNA
M_A_CPU0_SB_CB<6>        J2               234      SCONN288_ADR50001P003C01-SCONNA
M_A_CPU0_SB_CB<6>        U2               E35      SOCKET4677_AZIFS054P001C01-SOCA
M_A_CPU0_SB_CB<7>        J1               236      SCONN288_ADR50001P013C01-SCONNA
M_A_CPU0_SB_CB<7>        J2               236      SCONN288_ADR50001P003C01-SCONNA
M_A_CPU0_SB_CB<7>        U2               F34      SOCKET4677_AZIFS054P001C01-SOCA
M_A_CPU0_SB_CS_N<0>      J1               84       SCONN288_ADR50001P013C01-SCONNA
M_A_CPU0_SB_CS_N<0>      U2               B38      SOCKET4677_AZIFS054P001C01-SOCA
M_A_CPU0_SB_CS_N<1>      J1               229      SCONN288_ADR50001P013C01-SCONNA
M_A_CPU0_SB_CS_N<1>      U2               C37      SOCKET4677_AZIFS054P001C01-SOCA
M_A_CPU0_SB_CS_N<2>      J2               84       SCONN288_ADR50001P003C01-SCONNA
M_A_CPU0_SB_CS_N<2>      U2               F38      SOCKET4677_AZIFS054P001C01-SOCA
M_A_CPU0_SB_CS_N<3>      J2               229      SCONN288_ADR50001P003C01-SCONNA
M_A_CPU0_SB_CS_N<3>      U2               E37      SOCKET4677_AZIFS054P001C01-SOCA
M_A_CPU0_SB_DQ<0>        J1               100      SCONN288_ADR50001P013C01-SCONNA
M_A_CPU0_SB_DQ<0>        J2               100      SCONN288_ADR50001P003C01-SCONNA
M_A_CPU0_SB_DQ<0>        U2               K32      SOCKET4677_AZIFS054P001C01-SOCA
M_A_CPU0_SB_DQ<1>        J1               102      SCONN288_ADR50001P013C01-SCONNA
M_A_CPU0_SB_DQ<1>        J2               102      SCONN288_ADR50001P003C01-SCONNA
M_A_CPU0_SB_DQ<1>        U2               J31      SOCKET4677_AZIFS054P001C01-SOCA
M_A_CPU0_SB_DQ<2>        J1               245      SCONN288_ADR50001P013C01-SCONNA
M_A_CPU0_SB_DQ<2>        J2               245      SCONN288_ADR50001P003C01-SCONNA
M_A_CPU0_SB_DQ<2>        U2               M32      SOCKET4677_AZIFS054P001C01-SOCA
M_A_CPU0_SB_DQ<3>        J1               247      SCONN288_ADR50001P013C01-SCONNA
M_A_CPU0_SB_DQ<3>        J2               247      SCONN288_ADR50001P003C01-SCONNA
M_A_CPU0_SB_DQ<3>        U2               N31      SOCKET4677_AZIFS054P001C01-SOCA
M_A_CPU0_SB_DQ<4>        J1               107      SCONN288_ADR50001P013C01-SCONNA
M_A_CPU0_SB_DQ<4>        J2               107      SCONN288_ADR50001P003C01-SCONNA
M_A_CPU0_SB_DQ<4>        U2               J29      SOCKET4677_AZIFS054P001C01-SOCA
M_A_CPU0_SB_DQ<5>        J1               109      SCONN288_ADR50001P013C01-SCONNA
M_A_CPU0_SB_DQ<5>        J2               109      SCONN288_ADR50001P003C01-SCONNA
M_A_CPU0_SB_DQ<5>        U2               K28      SOCKET4677_AZIFS054P001C01-SOCA
M_A_CPU0_SB_DQ<6>        J1               252      SCONN288_ADR50001P013C01-SCONNA
M_A_CPU0_SB_DQ<6>        J2               252      SCONN288_ADR50001P003C01-SCONNA
M_A_CPU0_SB_DQ<6>        U2               N29      SOCKET4677_AZIFS054P001C01-SOCA
M_A_CPU0_SB_DQ<7>        J1               254      SCONN288_ADR50001P013C01-SCONNA
M_A_CPU0_SB_DQ<7>        J2               254      SCONN288_ADR50001P003C01-SCONNA
M_A_CPU0_SB_DQ<7>        U2               M28      SOCKET4677_AZIFS054P001C01-SOCA
M_A_CPU0_SB_DQ<8>        J1               111      SCONN288_ADR50001P013C01-SCONNA
M_A_CPU0_SB_DQ<8>        J2               111      SCONN288_ADR50001P003C01-SCONNA
M_A_CPU0_SB_DQ<8>        U2               C29      SOCKET4677_AZIFS054P001C01-SOCA
M_A_CPU0_SB_DQ<9>        J1               113      SCONN288_ADR50001P013C01-SCONNA
M_A_CPU0_SB_DQ<9>        J2               113      SCONN288_ADR50001P003C01-SCONNA
M_A_CPU0_SB_DQ<9>        U2               B28      SOCKET4677_AZIFS054P001C01-SOCA
M_A_CPU0_SB_DQ<10>       J1               256      SCONN288_ADR50001P013C01-SCONNA
M_A_CPU0_SB_DQ<10>       J2               256      SCONN288_ADR50001P003C01-SCONNA
M_A_CPU0_SB_DQ<10>       U2               E29      SOCKET4677_AZIFS054P001C01-SOCA
M_A_CPU0_SB_DQ<11>       J1               258      SCONN288_ADR50001P013C01-SCONNA
M_A_CPU0_SB_DQ<11>       J2               258      SCONN288_ADR50001P003C01-SCONNA
M_A_CPU0_SB_DQ<11>       U2               F28      SOCKET4677_AZIFS054P001C01-SOCA
M_A_CPU0_SB_DQ<12>       J1               118      SCONN288_ADR50001P013C01-SCONNA
M_A_CPU0_SB_DQ<12>       J2               118      SCONN288_ADR50001P003C01-SCONNA
M_A_CPU0_SB_DQ<12>       U2               B26      SOCKET4677_AZIFS054P001C01-SOCA
M_A_CPU0_SB_DQ<13>       J1               120      SCONN288_ADR50001P013C01-SCONNA
M_A_CPU0_SB_DQ<13>       J2               120      SCONN288_ADR50001P003C01-SCONNA
M_A_CPU0_SB_DQ<13>       U2               C25      SOCKET4677_AZIFS054P001C01-SOCA
M_A_CPU0_SB_DQ<14>       J1               263      SCONN288_ADR50001P013C01-SCONNA
M_A_CPU0_SB_DQ<14>       J2               263      SCONN288_ADR50001P003C01-SCONNA
M_A_CPU0_SB_DQ<14>       U2               F26      SOCKET4677_AZIFS054P001C01-SOCA
M_A_CPU0_SB_DQ<15>       J1               265      SCONN288_ADR50001P013C01-SCONNA
M_A_CPU0_SB_DQ<15>       J2               265      SCONN288_ADR50001P003C01-SCONNA
M_A_CPU0_SB_DQ<15>       U2               E25      SOCKET4677_AZIFS054P001C01-SOCA
M_A_CPU0_SB_DQ<16>       J1               122      SCONN288_ADR50001P013C01-SCONNA
M_A_CPU0_SB_DQ<16>       J2               122      SCONN288_ADR50001P003C01-SCONNA
M_A_CPU0_SB_DQ<16>       U2               C23      SOCKET4677_AZIFS054P001C01-SOCA
M_A_CPU0_SB_DQ<17>       J1               124      SCONN288_ADR50001P013C01-SCONNA
M_A_CPU0_SB_DQ<17>       J2               124      SCONN288_ADR50001P003C01-SCONNA
M_A_CPU0_SB_DQ<17>       U2               B22      SOCKET4677_AZIFS054P001C01-SOCA
M_A_CPU0_SB_DQ<18>       J1               267      SCONN288_ADR50001P013C01-SCONNA
M_A_CPU0_SB_DQ<18>       J2               267      SCONN288_ADR50001P003C01-SCONNA
M_A_CPU0_SB_DQ<18>       U2               E23      SOCKET4677_AZIFS054P001C01-SOCA
M_A_CPU0_SB_DQ<19>       J1               269      SCONN288_ADR50001P013C01-SCONNA
M_A_CPU0_SB_DQ<19>       J2               269      SCONN288_ADR50001P003C01-SCONNA
M_A_CPU0_SB_DQ<19>       U2               F22      SOCKET4677_AZIFS054P001C01-SOCA
M_A_CPU0_SB_DQ<20>       J1               129      SCONN288_ADR50001P013C01-SCONNA
M_A_CPU0_SB_DQ<20>       J2               129      SCONN288_ADR50001P003C01-SCONNA
M_A_CPU0_SB_DQ<20>       U2               B20      SOCKET4677_AZIFS054P001C01-SOCA
M_A_CPU0_SB_DQ<21>       J1               131      SCONN288_ADR50001P013C01-SCONNA
M_A_CPU0_SB_DQ<21>       J2               131      SCONN288_ADR50001P003C01-SCONNA
M_A_CPU0_SB_DQ<21>       U2               C19      SOCKET4677_AZIFS054P001C01-SOCA
M_A_CPU0_SB_DQ<22>       J1               274      SCONN288_ADR50001P013C01-SCONNA
M_A_CPU0_SB_DQ<22>       J2               274      SCONN288_ADR50001P003C01-SCONNA
M_A_CPU0_SB_DQ<22>       U2               F20      SOCKET4677_AZIFS054P001C01-SOCA
M_A_CPU0_SB_DQ<23>       J1               276      SCONN288_ADR50001P013C01-SCONNA
M_A_CPU0_SB_DQ<23>       J2               276      SCONN288_ADR50001P003C01-SCONNA
M_A_CPU0_SB_DQ<23>       U2               E19      SOCKET4677_AZIFS054P001C01-SOCA
M_A_CPU0_SB_DQ<24>       J1               133      SCONN288_ADR50001P013C01-SCONNA
M_A_CPU0_SB_DQ<24>       J2               133      SCONN288_ADR50001P003C01-SCONNA
M_A_CPU0_SB_DQ<24>       U2               C11      SOCKET4677_AZIFS054P001C01-SOCA
M_A_CPU0_SB_DQ<25>       J1               135      SCONN288_ADR50001P013C01-SCONNA
M_A_CPU0_SB_DQ<25>       J2               135      SCONN288_ADR50001P003C01-SCONNA
M_A_CPU0_SB_DQ<25>       U2               B10      SOCKET4677_AZIFS054P001C01-SOCA
M_A_CPU0_SB_DQ<26>       J1               278      SCONN288_ADR50001P013C01-SCONNA
M_A_CPU0_SB_DQ<26>       J2               278      SCONN288_ADR50001P003C01-SCONNA
M_A_CPU0_SB_DQ<26>       U2               E11      SOCKET4677_AZIFS054P001C01-SOCA
M_A_CPU0_SB_DQ<27>       J1               280      SCONN288_ADR50001P013C01-SCONNA
M_A_CPU0_SB_DQ<27>       J2               280      SCONN288_ADR50001P003C01-SCONNA
M_A_CPU0_SB_DQ<27>       U2               F10      SOCKET4677_AZIFS054P001C01-SOCA
M_A_CPU0_SB_DQ<28>       J1               140      SCONN288_ADR50001P013C01-SCONNA
M_A_CPU0_SB_DQ<28>       J2               140      SCONN288_ADR50001P003C01-SCONNA
M_A_CPU0_SB_DQ<28>       U2               B8       SOCKET4677_AZIFS054P001C01-SOCA
M_A_CPU0_SB_DQ<29>       J1               142      SCONN288_ADR50001P013C01-SCONNA
M_A_CPU0_SB_DQ<29>       J2               142      SCONN288_ADR50001P003C01-SCONNA
M_A_CPU0_SB_DQ<29>       U2               C7       SOCKET4677_AZIFS054P001C01-SOCA
M_A_CPU0_SB_DQ<30>       J1               285      SCONN288_ADR50001P013C01-SCONNA
M_A_CPU0_SB_DQ<30>       J2               285      SCONN288_ADR50001P003C01-SCONNA
M_A_CPU0_SB_DQ<30>       U2               F8       SOCKET4677_AZIFS054P001C01-SOCA
M_A_CPU0_SB_DQ<31>       J1               287      SCONN288_ADR50001P013C01-SCONNA
M_A_CPU0_SB_DQ<31>       J2               287      SCONN288_ADR50001P003C01-SCONNA
M_A_CPU0_SB_DQ<31>       U2               E7       SOCKET4677_AZIFS054P001C01-SOCA
M_A_CPU0_SB_DQS_DN<0>    J1               105      SCONN288_ADR50001P013C01-SCONNA
M_A_CPU0_SB_DQS_DN<0>    J2               105      SCONN288_ADR50001P003C01-SCONNA
M_A_CPU0_SB_DQS_DN<0>    U2               H30      SOCKET4677_AZIFS054P001C01-SOCA
M_A_CPU0_SB_DQS_DN<1>    J1               116      SCONN288_ADR50001P013C01-SCONNA
M_A_CPU0_SB_DQS_DN<1>    J2               116      SCONN288_ADR50001P003C01-SCONNA
M_A_CPU0_SB_DQS_DN<1>    U2               A27      SOCKET4677_AZIFS054P001C01-SOCA
M_A_CPU0_SB_DQS_DN<2>    J1               127      SCONN288_ADR50001P013C01-SCONNA
M_A_CPU0_SB_DQS_DN<2>    J2               127      SCONN288_ADR50001P003C01-SCONNA
M_A_CPU0_SB_DQS_DN<2>    U2               A21      SOCKET4677_AZIFS054P001C01-SOCA
M_A_CPU0_SB_DQS_DN<3>    J1               138      SCONN288_ADR50001P013C01-SCONNA
M_A_CPU0_SB_DQS_DN<3>    J2               138      SCONN288_ADR50001P003C01-SCONNA
M_A_CPU0_SB_DQS_DN<3>    U2               A9       SOCKET4677_AZIFS054P001C01-SOCA
M_A_CPU0_SB_DQS_DN<4>    J1               238      SCONN288_ADR50001P013C01-SCONNA
M_A_CPU0_SB_DQS_DN<4>    J2               238      SCONN288_ADR50001P003C01-SCONNA
M_A_CPU0_SB_DQS_DN<4>    U2               G33      SOCKET4677_AZIFS054P001C01-SOCA
M_A_CPU0_SB_DQS_DN<5>    J1               249      SCONN288_ADR50001P013C01-SCONNA
M_A_CPU0_SB_DQS_DN<5>    J2               249      SCONN288_ADR50001P003C01-SCONNA
M_A_CPU0_SB_DQS_DN<5>    U2               M30      SOCKET4677_AZIFS054P001C01-SOCA
M_A_CPU0_SB_DQS_DN<6>    J1               260      SCONN288_ADR50001P013C01-SCONNA
M_A_CPU0_SB_DQS_DN<6>    J2               260      SCONN288_ADR50001P003C01-SCONNA
M_A_CPU0_SB_DQS_DN<6>    U2               G27      SOCKET4677_AZIFS054P001C01-SOCA
M_A_CPU0_SB_DQS_DN<7>    J1               271      SCONN288_ADR50001P013C01-SCONNA
M_A_CPU0_SB_DQS_DN<7>    J2               271      SCONN288_ADR50001P003C01-SCONNA
M_A_CPU0_SB_DQS_DN<7>    U2               G21      SOCKET4677_AZIFS054P001C01-SOCA
M_A_CPU0_SB_DQS_DN<8>    J1               282      SCONN288_ADR50001P013C01-SCONNA
M_A_CPU0_SB_DQS_DN<8>    J2               282      SCONN288_ADR50001P003C01-SCONNA
M_A_CPU0_SB_DQS_DN<8>    U2               G9       SOCKET4677_AZIFS054P001C01-SOCA
M_A_CPU0_SB_DQS_DN<9>    J1               94       SCONN288_ADR50001P013C01-SCONNA
M_A_CPU0_SB_DQS_DN<9>    J2               94       SCONN288_ADR50001P003C01-SCONNA
M_A_CPU0_SB_DQS_DN<9>    U2               A33      SOCKET4677_AZIFS054P001C01-SOCA
M_A_CPU0_SB_DQS_DP<0>    J1               104      SCONN288_ADR50001P013C01-SCONNA
M_A_CPU0_SB_DQS_DP<0>    J2               104      SCONN288_ADR50001P003C01-SCONNA
M_A_CPU0_SB_DQS_DP<0>    U2               K30      SOCKET4677_AZIFS054P001C01-SOCA
M_A_CPU0_SB_DQS_DP<1>    J1               115      SCONN288_ADR50001P013C01-SCONNA
M_A_CPU0_SB_DQS_DP<1>    J2               115      SCONN288_ADR50001P003C01-SCONNA
M_A_CPU0_SB_DQS_DP<1>    U2               C27      SOCKET4677_AZIFS054P001C01-SOCA
M_A_CPU0_SB_DQS_DP<2>    J1               126      SCONN288_ADR50001P013C01-SCONNA
M_A_CPU0_SB_DQS_DP<2>    J2               126      SCONN288_ADR50001P003C01-SCONNA
M_A_CPU0_SB_DQS_DP<2>    U2               C21      SOCKET4677_AZIFS054P001C01-SOCA
M_A_CPU0_SB_DQS_DP<3>    J1               137      SCONN288_ADR50001P013C01-SCONNA
M_A_CPU0_SB_DQS_DP<3>    J2               137      SCONN288_ADR50001P003C01-SCONNA
M_A_CPU0_SB_DQS_DP<3>    U2               C9       SOCKET4677_AZIFS054P001C01-SOCA
M_A_CPU0_SB_DQS_DP<4>    J1               239      SCONN288_ADR50001P013C01-SCONNA
M_A_CPU0_SB_DQS_DP<4>    J2               239      SCONN288_ADR50001P003C01-SCONNA
M_A_CPU0_SB_DQS_DP<4>    U2               E33      SOCKET4677_AZIFS054P001C01-SOCA
M_A_CPU0_SB_DQS_DP<5>    J1               250      SCONN288_ADR50001P013C01-SCONNA
M_A_CPU0_SB_DQS_DP<5>    J2               250      SCONN288_ADR50001P003C01-SCONNA
M_A_CPU0_SB_DQS_DP<5>    U2               P30      SOCKET4677_AZIFS054P001C01-SOCA
M_A_CPU0_SB_DQS_DP<6>    J1               261      SCONN288_ADR50001P013C01-SCONNA
M_A_CPU0_SB_DQS_DP<6>    J2               261      SCONN288_ADR50001P003C01-SCONNA
M_A_CPU0_SB_DQS_DP<6>    U2               E27      SOCKET4677_AZIFS054P001C01-SOCA
M_A_CPU0_SB_DQS_DP<7>    J1               272      SCONN288_ADR50001P013C01-SCONNA
M_A_CPU0_SB_DQS_DP<7>    J2               272      SCONN288_ADR50001P003C01-SCONNA
M_A_CPU0_SB_DQS_DP<7>    U2               E21      SOCKET4677_AZIFS054P001C01-SOCA
M_A_CPU0_SB_DQS_DP<8>    J1               283      SCONN288_ADR50001P013C01-SCONNA
M_A_CPU0_SB_DQS_DP<8>    J2               283      SCONN288_ADR50001P003C01-SCONNA
M_A_CPU0_SB_DQS_DP<8>    U2               E9       SOCKET4677_AZIFS054P001C01-SOCA
M_A_CPU0_SB_DQS_DP<9>    J1               93       SCONN288_ADR50001P013C01-SCONNA
M_A_CPU0_SB_DQS_DP<9>    J2               93       SCONN288_ADR50001P003C01-SCONNA
M_A_CPU0_SB_DQS_DP<9>    U2               C33      SOCKET4677_AZIFS054P001C01-SOCA
M_A_CPU0_SB_PAR          J1               227      SCONN288_ADR50001P013C01-SCONNA
M_A_CPU0_SB_PAR          J2               227      SCONN288_ADR50001P003C01-SCONNA
M_A_CPU0_SB_PAR          U2               G39      SOCKET4677_AZIFS054P001C01-SOCA
M_A_CPU0_SB_RSP<0>       J1               87       SCONN288_ADR50001P013C01-SCONNA
M_A_CPU0_SB_RSP<0>       U2               AV44     SOCKET4677_AZIFS054P001C01-SOCA
M_A_CPU0_SB_RSP<1>       J2               87       SCONN288_ADR50001P003C01-SCONNA
M_A_CPU0_SB_RSP<1>       U2               AV42     SOCKET4677_AZIFS054P001C01-SOCA
M_A_CPU1_ALERT_N         J17              62       SCONN288_ADR50001P013C01-SCONNA
M_A_CPU1_ALERT_N         J18              62       SCONN288_ADR50001P003C01-SCONNA
M_A_CPU1_ALERT_N         U1               AT49     SOCKET4677_AZIFS054P001C01-SOCA
M_A_CPU1_CLK_DN<0>       J17              218      SCONN288_ADR50001P013C01-SCONNA
M_A_CPU1_CLK_DN<0>       U1               B44      SOCKET4677_AZIFS054P001C01-SOCA
M_A_CPU1_CLK_DN<1>       J18              218      SCONN288_ADR50001P003C01-SCONNA
M_A_CPU1_CLK_DN<1>       U1               G45      SOCKET4677_AZIFS054P001C01-SOCA
M_A_CPU1_CLK_DP<0>       J17              217      SCONN288_ADR50001P013C01-SCONNA
M_A_CPU1_CLK_DP<0>       U1               C43      SOCKET4677_AZIFS054P001C01-SOCA
M_A_CPU1_CLK_DP<1>       J18              217      SCONN288_ADR50001P003C01-SCONNA
M_A_CPU1_CLK_DP<1>       U1               E45      SOCKET4677_AZIFS054P001C01-SOCA
M_A_CPU1_SA_CA<0>        J17              66       SCONN288_ADR50001P013C01-SCONNA
M_A_CPU1_SA_CA<0>        J18              66       SCONN288_ADR50001P003C01-SCONNA
M_A_CPU1_SA_CA<0>        U1               A52      SOCKET4677_AZIFS054P001C01-SOCA
M_A_CPU1_SA_CA<1>        J17              211      SCONN288_ADR50001P013C01-SCONNA
M_A_CPU1_SA_CA<1>        J18              211      SCONN288_ADR50001P003C01-SCONNA
M_A_CPU1_SA_CA<1>        U1               G52      SOCKET4677_AZIFS054P001C01-SOCA
M_A_CPU1_SA_CA<2>        J17              68       SCONN288_ADR50001P013C01-SCONNA
M_A_CPU1_SA_CA<2>        J18              68       SCONN288_ADR50001P003C01-SCONNA
M_A_CPU1_SA_CA<2>        U1               B51      SOCKET4677_AZIFS054P001C01-SOCA
M_A_CPU1_SA_CA<3>        J17              213      SCONN288_ADR50001P013C01-SCONNA
M_A_CPU1_SA_CA<3>        J18              213      SCONN288_ADR50001P003C01-SCONNA
M_A_CPU1_SA_CA<3>        U1               F51      SOCKET4677_AZIFS054P001C01-SOCA
M_A_CPU1_SA_CA<4>        J17              70       SCONN288_ADR50001P013C01-SCONNA
M_A_CPU1_SA_CA<4>        J18              70       SCONN288_ADR50001P003C01-SCONNA
M_A_CPU1_SA_CA<4>        U1               C50      SOCKET4677_AZIFS054P001C01-SOCA
M_A_CPU1_SA_CA<5>        J17              215      SCONN288_ADR50001P013C01-SCONNA
M_A_CPU1_SA_CA<5>        J18              215      SCONN288_ADR50001P003C01-SCONNA
M_A_CPU1_SA_CA<5>        U1               E50      SOCKET4677_AZIFS054P001C01-SOCA
M_A_CPU1_SA_CA<6>        J17              72       SCONN288_ADR50001P013C01-SCONNA
M_A_CPU1_SA_CA<6>        J18              72       SCONN288_ADR50001P003C01-SCONNA
M_A_CPU1_SA_CA<6>        U1               C48      SOCKET4677_AZIFS054P001C01-SOCA
M_A_CPU1_SA_CB<0>        J17              51       SCONN288_ADR50001P013C01-SCONNA
M_A_CPU1_SA_CB<0>        J18              51       SCONN288_ADR50001P003C01-SCONNA
M_A_CPU1_SA_CB<0>        U1               C60      SOCKET4677_AZIFS054P001C01-SOCA
M_A_CPU1_SA_CB<1>        J17              53       SCONN288_ADR50001P013C01-SCONNA
M_A_CPU1_SA_CB<1>        J18              53       SCONN288_ADR50001P003C01-SCONNA
M_A_CPU1_SA_CB<1>        U1               B59      SOCKET4677_AZIFS054P001C01-SOCA
M_A_CPU1_SA_CB<2>        J17              196      SCONN288_ADR50001P013C01-SCONNA
M_A_CPU1_SA_CB<2>        J18              196      SCONN288_ADR50001P003C01-SCONNA
M_A_CPU1_SA_CB<2>        U1               E60      SOCKET4677_AZIFS054P001C01-SOCA
M_A_CPU1_SA_CB<3>        J17              198      SCONN288_ADR50001P013C01-SCONNA
M_A_CPU1_SA_CB<3>        J18              198      SCONN288_ADR50001P003C01-SCONNA
M_A_CPU1_SA_CB<3>        U1               F59      SOCKET4677_AZIFS054P001C01-SOCA
M_A_CPU1_SA_CB<4>        J17              58       SCONN288_ADR50001P013C01-SCONNA
M_A_CPU1_SA_CB<4>        J18              58       SCONN288_ADR50001P003C01-SCONNA
M_A_CPU1_SA_CB<4>        U1               B57      SOCKET4677_AZIFS054P001C01-SOCA
M_A_CPU1_SA_CB<5>        J17              60       SCONN288_ADR50001P013C01-SCONNA
M_A_CPU1_SA_CB<5>        J18              60       SCONN288_ADR50001P003C01-SCONNA
M_A_CPU1_SA_CB<5>        U1               C56      SOCKET4677_AZIFS054P001C01-SOCA
M_A_CPU1_SA_CB<6>        J17              203      SCONN288_ADR50001P013C01-SCONNA
M_A_CPU1_SA_CB<6>        J18              203      SCONN288_ADR50001P003C01-SCONNA
M_A_CPU1_SA_CB<6>        U1               F57      SOCKET4677_AZIFS054P001C01-SOCA
M_A_CPU1_SA_CB<7>        J17              205      SCONN288_ADR50001P013C01-SCONNA
M_A_CPU1_SA_CB<7>        J18              205      SCONN288_ADR50001P003C01-SCONNA
M_A_CPU1_SA_CB<7>        U1               E56      SOCKET4677_AZIFS054P001C01-SOCA
M_A_CPU1_SA_CS_N<0>      J17              64       SCONN288_ADR50001P013C01-SCONNA
M_A_CPU1_SA_CS_N<0>      U1               C54      SOCKET4677_AZIFS054P001C01-SOCA
M_A_CPU1_SA_CS_N<1>      J17              209      SCONN288_ADR50001P013C01-SCONNA
M_A_CPU1_SA_CS_N<1>      U1               B53      SOCKET4677_AZIFS054P001C01-SOCA
M_A_CPU1_SA_CS_N<2>      J18              64       SCONN288_ADR50001P003C01-SCONNA
M_A_CPU1_SA_CS_N<2>      U1               E54      SOCKET4677_AZIFS054P001C01-SOCA
M_A_CPU1_SA_CS_N<3>      J18              209      SCONN288_ADR50001P003C01-SCONNA
M_A_CPU1_SA_CS_N<3>      U1               F53      SOCKET4677_AZIFS054P001C01-SOCA
M_A_CPU1_SA_DQ<0>        J17              7        SCONN288_ADR50001P013C01-SCONNA
M_A_CPU1_SA_DQ<0>        J18              7        SCONN288_ADR50001P003C01-SCONNA
M_A_CPU1_SA_DQ<0>        U1               B81      SOCKET4677_AZIFS054P001C01-SOCA
M_A_CPU1_SA_DQ<1>        J17              9        SCONN288_ADR50001P013C01-SCONNA
M_A_CPU1_SA_DQ<1>        J18              9        SCONN288_ADR50001P003C01-SCONNA
M_A_CPU1_SA_DQ<1>        U1               B79      SOCKET4677_AZIFS054P001C01-SOCA
M_A_CPU1_SA_DQ<2>        J17              152      SCONN288_ADR50001P013C01-SCONNA
M_A_CPU1_SA_DQ<2>        J18              152      SCONN288_ADR50001P003C01-SCONNA
M_A_CPU1_SA_DQ<2>        U1               M77      SOCKET4677_AZIFS054P001C01-SOCA
M_A_CPU1_SA_DQ<3>        J17              154      SCONN288_ADR50001P013C01-SCONNA
M_A_CPU1_SA_DQ<3>        J18              154      SCONN288_ADR50001P003C01-SCONNA
M_A_CPU1_SA_DQ<3>        U1               G78      SOCKET4677_AZIFS054P001C01-SOCA
M_A_CPU1_SA_DQ<4>        J17              14       SCONN288_ADR50001P013C01-SCONNA
M_A_CPU1_SA_DQ<4>        J18              14       SCONN288_ADR50001P003C01-SCONNA
M_A_CPU1_SA_DQ<4>        U1               C76      SOCKET4677_AZIFS054P001C01-SOCA
M_A_CPU1_SA_DQ<5>        J17              16       SCONN288_ADR50001P013C01-SCONNA
M_A_CPU1_SA_DQ<5>        J18              16       SCONN288_ADR50001P003C01-SCONNA
M_A_CPU1_SA_DQ<5>        U1               D75      SOCKET4677_AZIFS054P001C01-SOCA
M_A_CPU1_SA_DQ<6>        J17              159      SCONN288_ADR50001P013C01-SCONNA
M_A_CPU1_SA_DQ<6>        J18              159      SCONN288_ADR50001P003C01-SCONNA
M_A_CPU1_SA_DQ<6>        U1               G76      SOCKET4677_AZIFS054P001C01-SOCA
M_A_CPU1_SA_DQ<7>        J17              161      SCONN288_ADR50001P013C01-SCONNA
M_A_CPU1_SA_DQ<7>        J18              161      SCONN288_ADR50001P003C01-SCONNA
M_A_CPU1_SA_DQ<7>        U1               F75      SOCKET4677_AZIFS054P001C01-SOCA
M_A_CPU1_SA_DQ<8>        J17              18       SCONN288_ADR50001P013C01-SCONNA
M_A_CPU1_SA_DQ<8>        J18              18       SCONN288_ADR50001P003C01-SCONNA
M_A_CPU1_SA_DQ<8>        U1               K69      SOCKET4677_AZIFS054P001C01-SOCA
M_A_CPU1_SA_DQ<9>        J17              20       SCONN288_ADR50001P013C01-SCONNA
M_A_CPU1_SA_DQ<9>        J18              20       SCONN288_ADR50001P003C01-SCONNA
M_A_CPU1_SA_DQ<9>        U1               J68      SOCKET4677_AZIFS054P001C01-SOCA
M_A_CPU1_SA_DQ<10>       J17              163      SCONN288_ADR50001P013C01-SCONNA
M_A_CPU1_SA_DQ<10>       J18              163      SCONN288_ADR50001P003C01-SCONNA
M_A_CPU1_SA_DQ<10>       U1               M69      SOCKET4677_AZIFS054P001C01-SOCA
M_A_CPU1_SA_DQ<11>       J17              165      SCONN288_ADR50001P013C01-SCONNA
M_A_CPU1_SA_DQ<11>       J18              165      SCONN288_ADR50001P003C01-SCONNA
M_A_CPU1_SA_DQ<11>       U1               N68      SOCKET4677_AZIFS054P001C01-SOCA
M_A_CPU1_SA_DQ<12>       J17              25       SCONN288_ADR50001P013C01-SCONNA
M_A_CPU1_SA_DQ<12>       J18              25       SCONN288_ADR50001P003C01-SCONNA
M_A_CPU1_SA_DQ<12>       U1               J66      SOCKET4677_AZIFS054P001C01-SOCA
M_A_CPU1_SA_DQ<13>       J17              27       SCONN288_ADR50001P013C01-SCONNA
M_A_CPU1_SA_DQ<13>       J18              27       SCONN288_ADR50001P003C01-SCONNA
M_A_CPU1_SA_DQ<13>       U1               K65      SOCKET4677_AZIFS054P001C01-SOCA
M_A_CPU1_SA_DQ<14>       J17              170      SCONN288_ADR50001P013C01-SCONNA
M_A_CPU1_SA_DQ<14>       J18              170      SCONN288_ADR50001P003C01-SCONNA
M_A_CPU1_SA_DQ<14>       U1               N66      SOCKET4677_AZIFS054P001C01-SOCA
M_A_CPU1_SA_DQ<15>       J17              172      SCONN288_ADR50001P013C01-SCONNA
M_A_CPU1_SA_DQ<15>       J18              172      SCONN288_ADR50001P003C01-SCONNA
M_A_CPU1_SA_DQ<15>       U1               M65      SOCKET4677_AZIFS054P001C01-SOCA
M_A_CPU1_SA_DQ<16>       J17              29       SCONN288_ADR50001P013C01-SCONNA
M_A_CPU1_SA_DQ<16>       J18              29       SCONN288_ADR50001P003C01-SCONNA
M_A_CPU1_SA_DQ<16>       U1               B73      SOCKET4677_AZIFS054P001C01-SOCA
M_A_CPU1_SA_DQ<17>       J17              31       SCONN288_ADR50001P013C01-SCONNA
M_A_CPU1_SA_DQ<17>       J18              31       SCONN288_ADR50001P003C01-SCONNA
M_A_CPU1_SA_DQ<17>       U1               E72      SOCKET4677_AZIFS054P001C01-SOCA
M_A_CPU1_SA_DQ<18>       J17              174      SCONN288_ADR50001P013C01-SCONNA
M_A_CPU1_SA_DQ<18>       J18              174      SCONN288_ADR50001P003C01-SCONNA
M_A_CPU1_SA_DQ<18>       U1               D73      SOCKET4677_AZIFS054P001C01-SOCA
M_A_CPU1_SA_DQ<19>       J17              176      SCONN288_ADR50001P013C01-SCONNA
M_A_CPU1_SA_DQ<19>       J18              176      SCONN288_ADR50001P003C01-SCONNA
M_A_CPU1_SA_DQ<19>       U1               F71      SOCKET4677_AZIFS054P001C01-SOCA
M_A_CPU1_SA_DQ<20>       J17              36       SCONN288_ADR50001P013C01-SCONNA
M_A_CPU1_SA_DQ<20>       J18              36       SCONN288_ADR50001P003C01-SCONNA
M_A_CPU1_SA_DQ<20>       U1               B69      SOCKET4677_AZIFS054P001C01-SOCA
M_A_CPU1_SA_DQ<21>       J17              38       SCONN288_ADR50001P013C01-SCONNA
M_A_CPU1_SA_DQ<21>       J18              38       SCONN288_ADR50001P003C01-SCONNA
M_A_CPU1_SA_DQ<21>       U1               C68      SOCKET4677_AZIFS054P001C01-SOCA
M_A_CPU1_SA_DQ<22>       J17              181      SCONN288_ADR50001P013C01-SCONNA
M_A_CPU1_SA_DQ<22>       J18              181      SCONN288_ADR50001P003C01-SCONNA
M_A_CPU1_SA_DQ<22>       U1               F69      SOCKET4677_AZIFS054P001C01-SOCA
M_A_CPU1_SA_DQ<23>       J17              183      SCONN288_ADR50001P013C01-SCONNA
M_A_CPU1_SA_DQ<23>       J18              183      SCONN288_ADR50001P003C01-SCONNA
M_A_CPU1_SA_DQ<23>       U1               E68      SOCKET4677_AZIFS054P001C01-SOCA
M_A_CPU1_SA_DQ<24>       J17              40       SCONN288_ADR50001P013C01-SCONNA
M_A_CPU1_SA_DQ<24>       J18              40       SCONN288_ADR50001P003C01-SCONNA
M_A_CPU1_SA_DQ<24>       U1               C66      SOCKET4677_AZIFS054P001C01-SOCA
M_A_CPU1_SA_DQ<25>       J17              42       SCONN288_ADR50001P013C01-SCONNA
M_A_CPU1_SA_DQ<25>       J18              42       SCONN288_ADR50001P003C01-SCONNA
M_A_CPU1_SA_DQ<25>       U1               B65      SOCKET4677_AZIFS054P001C01-SOCA
M_A_CPU1_SA_DQ<26>       J17              185      SCONN288_ADR50001P013C01-SCONNA
M_A_CPU1_SA_DQ<26>       J18              185      SCONN288_ADR50001P003C01-SCONNA
M_A_CPU1_SA_DQ<26>       U1               E66      SOCKET4677_AZIFS054P001C01-SOCA
M_A_CPU1_SA_DQ<27>       J17              187      SCONN288_ADR50001P013C01-SCONNA
M_A_CPU1_SA_DQ<27>       J18              187      SCONN288_ADR50001P003C01-SCONNA
M_A_CPU1_SA_DQ<27>       U1               F65      SOCKET4677_AZIFS054P001C01-SOCA
M_A_CPU1_SA_DQ<28>       J17              47       SCONN288_ADR50001P013C01-SCONNA
M_A_CPU1_SA_DQ<28>       J18              47       SCONN288_ADR50001P003C01-SCONNA
M_A_CPU1_SA_DQ<28>       U1               B63      SOCKET4677_AZIFS054P001C01-SOCA
M_A_CPU1_SA_DQ<29>       J17              49       SCONN288_ADR50001P013C01-SCONNA
M_A_CPU1_SA_DQ<29>       J18              49       SCONN288_ADR50001P003C01-SCONNA
M_A_CPU1_SA_DQ<29>       U1               C62      SOCKET4677_AZIFS054P001C01-SOCA
M_A_CPU1_SA_DQ<30>       J17              192      SCONN288_ADR50001P013C01-SCONNA
M_A_CPU1_SA_DQ<30>       J18              192      SCONN288_ADR50001P003C01-SCONNA
M_A_CPU1_SA_DQ<30>       U1               F63      SOCKET4677_AZIFS054P001C01-SOCA
M_A_CPU1_SA_DQ<31>       J17              194      SCONN288_ADR50001P013C01-SCONNA
M_A_CPU1_SA_DQ<31>       J18              194      SCONN288_ADR50001P003C01-SCONNA
M_A_CPU1_SA_DQ<31>       U1               E62      SOCKET4677_AZIFS054P001C01-SOCA
M_A_CPU1_SA_DQS_DN<0>    J17              12       SCONN288_ADR50001P013C01-SCONNA
M_A_CPU1_SA_DQS_DN<0>    J18              12       SCONN288_ADR50001P003C01-SCONNA
M_A_CPU1_SA_DQS_DN<0>    U1               B77      SOCKET4677_AZIFS054P001C01-SOCA
M_A_CPU1_SA_DQS_DN<1>    J17              23       SCONN288_ADR50001P013C01-SCONNA
M_A_CPU1_SA_DQS_DN<1>    J18              23       SCONN288_ADR50001P003C01-SCONNA
M_A_CPU1_SA_DQS_DN<1>    U1               H67      SOCKET4677_AZIFS054P001C01-SOCA
M_A_CPU1_SA_DQS_DN<2>    J17              34       SCONN288_ADR50001P013C01-SCONNA
M_A_CPU1_SA_DQS_DN<2>    J18              34       SCONN288_ADR50001P003C01-SCONNA
M_A_CPU1_SA_DQS_DN<2>    U1               B71      SOCKET4677_AZIFS054P001C01-SOCA
M_A_CPU1_SA_DQS_DN<3>    J17              45       SCONN288_ADR50001P013C01-SCONNA
M_A_CPU1_SA_DQS_DN<3>    J18              45       SCONN288_ADR50001P003C01-SCONNA
M_A_CPU1_SA_DQS_DN<3>    U1               A64      SOCKET4677_AZIFS054P001C01-SOCA
M_A_CPU1_SA_DQS_DN<4>    J17              56       SCONN288_ADR50001P013C01-SCONNA
M_A_CPU1_SA_DQS_DN<4>    J18              56       SCONN288_ADR50001P003C01-SCONNA
M_A_CPU1_SA_DQS_DN<4>    U1               A58      SOCKET4677_AZIFS054P001C01-SOCA
M_A_CPU1_SA_DQS_DN<5>    J17              156      SCONN288_ADR50001P013C01-SCONNA
M_A_CPU1_SA_DQS_DN<5>    J18              156      SCONN288_ADR50001P003C01-SCONNA
M_A_CPU1_SA_DQS_DN<5>    U1               H77      SOCKET4677_AZIFS054P001C01-SOCA
M_A_CPU1_SA_DQS_DN<6>    J17              167      SCONN288_ADR50001P013C01-SCONNA
M_A_CPU1_SA_DQS_DN<6>    J18              167      SCONN288_ADR50001P003C01-SCONNA
M_A_CPU1_SA_DQS_DN<6>    U1               P67      SOCKET4677_AZIFS054P001C01-SOCA
M_A_CPU1_SA_DQS_DN<7>    J17              178      SCONN288_ADR50001P013C01-SCONNA
M_A_CPU1_SA_DQS_DN<7>    J18              178      SCONN288_ADR50001P003C01-SCONNA
M_A_CPU1_SA_DQS_DN<7>    U1               G70      SOCKET4677_AZIFS054P001C01-SOCA
M_A_CPU1_SA_DQS_DN<8>    J17              189      SCONN288_ADR50001P013C01-SCONNA
M_A_CPU1_SA_DQS_DN<8>    J18              189      SCONN288_ADR50001P003C01-SCONNA
M_A_CPU1_SA_DQS_DN<8>    U1               G64      SOCKET4677_AZIFS054P001C01-SOCA
M_A_CPU1_SA_DQS_DN<9>    J17              200      SCONN288_ADR50001P013C01-SCONNA
M_A_CPU1_SA_DQS_DN<9>    J18              200      SCONN288_ADR50001P003C01-SCONNA
M_A_CPU1_SA_DQS_DN<9>    U1               G58      SOCKET4677_AZIFS054P001C01-SOCA
M_A_CPU1_SA_DQS_DP<0>    J17              11       SCONN288_ADR50001P013C01-SCONNA
M_A_CPU1_SA_DQS_DP<0>    J18              11       SCONN288_ADR50001P003C01-SCONNA
M_A_CPU1_SA_DQS_DP<0>    U1               D77      SOCKET4677_AZIFS054P001C01-SOCA
M_A_CPU1_SA_DQS_DP<1>    J17              22       SCONN288_ADR50001P013C01-SCONNA
M_A_CPU1_SA_DQS_DP<1>    J18              22       SCONN288_ADR50001P003C01-SCONNA
M_A_CPU1_SA_DQS_DP<1>    U1               K67      SOCKET4677_AZIFS054P001C01-SOCA
M_A_CPU1_SA_DQS_DP<2>    J17              33       SCONN288_ADR50001P013C01-SCONNA
M_A_CPU1_SA_DQS_DP<2>    J18              33       SCONN288_ADR50001P003C01-SCONNA
M_A_CPU1_SA_DQS_DP<2>    U1               C70      SOCKET4677_AZIFS054P001C01-SOCA
M_A_CPU1_SA_DQS_DP<3>    J17              44       SCONN288_ADR50001P013C01-SCONNA
M_A_CPU1_SA_DQS_DP<3>    J18              44       SCONN288_ADR50001P003C01-SCONNA
M_A_CPU1_SA_DQS_DP<3>    U1               C64      SOCKET4677_AZIFS054P001C01-SOCA
M_A_CPU1_SA_DQS_DP<4>    J17              55       SCONN288_ADR50001P013C01-SCONNA
M_A_CPU1_SA_DQS_DP<4>    J18              55       SCONN288_ADR50001P003C01-SCONNA
M_A_CPU1_SA_DQS_DP<4>    U1               C58      SOCKET4677_AZIFS054P001C01-SOCA
M_A_CPU1_SA_DQS_DP<5>    J17              157      SCONN288_ADR50001P013C01-SCONNA
M_A_CPU1_SA_DQS_DP<5>    J18              157      SCONN288_ADR50001P003C01-SCONNA
M_A_CPU1_SA_DQS_DP<5>    U1               F77      SOCKET4677_AZIFS054P001C01-SOCA
M_A_CPU1_SA_DQS_DP<6>    J17              168      SCONN288_ADR50001P013C01-SCONNA
M_A_CPU1_SA_DQS_DP<6>    J18              168      SCONN288_ADR50001P003C01-SCONNA
M_A_CPU1_SA_DQS_DP<6>    U1               M67      SOCKET4677_AZIFS054P001C01-SOCA
M_A_CPU1_SA_DQS_DP<7>    J17              179      SCONN288_ADR50001P013C01-SCONNA
M_A_CPU1_SA_DQS_DP<7>    J18              179      SCONN288_ADR50001P003C01-SCONNA
M_A_CPU1_SA_DQS_DP<7>    U1               E70      SOCKET4677_AZIFS054P001C01-SOCA
M_A_CPU1_SA_DQS_DP<8>    J17              190      SCONN288_ADR50001P013C01-SCONNA
M_A_CPU1_SA_DQS_DP<8>    J18              190      SCONN288_ADR50001P003C01-SCONNA
M_A_CPU1_SA_DQS_DP<8>    U1               E64      SOCKET4677_AZIFS054P001C01-SOCA
M_A_CPU1_SA_DQS_DP<9>    J17              201      SCONN288_ADR50001P013C01-SCONNA
M_A_CPU1_SA_DQS_DP<9>    J18              201      SCONN288_ADR50001P003C01-SCONNA
M_A_CPU1_SA_DQS_DP<9>    U1               E58      SOCKET4677_AZIFS054P001C01-SOCA
M_A_CPU1_SA_PAR          J17              74       SCONN288_ADR50001P013C01-SCONNA
M_A_CPU1_SA_PAR          J18              74       SCONN288_ADR50001P003C01-SCONNA
M_A_CPU1_SA_PAR          U1               E48      SOCKET4677_AZIFS054P001C01-SOCA
M_A_CPU1_SA_RSP<0>       J17              86       SCONN288_ADR50001P013C01-SCONNA
M_A_CPU1_SA_RSP<0>       U1               AT42     SOCKET4677_AZIFS054P001C01-SOCA
M_A_CPU1_SA_RSP<1>       J18              86       SCONN288_ADR50001P003C01-SCONNA
M_A_CPU1_SA_RSP<1>       U1               AU43     SOCKET4677_AZIFS054P001C01-SOCA
M_A_CPU1_SB_CA<0>        J17              76       SCONN288_ADR50001P013C01-SCONNA
M_A_CPU1_SB_CA<0>        J18              76       SCONN288_ADR50001P003C01-SCONNA
M_A_CPU1_SB_CA<0>        U1               E43      SOCKET4677_AZIFS054P001C01-SOCA
M_A_CPU1_SB_CA<1>        J17              221      SCONN288_ADR50001P013C01-SCONNA
M_A_CPU1_SB_CA<1>        J18              221      SCONN288_ADR50001P003C01-SCONNA
M_A_CPU1_SB_CA<1>        U1               F44      SOCKET4677_AZIFS054P001C01-SOCA
M_A_CPU1_SB_CA<2>        J17              78       SCONN288_ADR50001P013C01-SCONNA
M_A_CPU1_SB_CA<2>        J18              78       SCONN288_ADR50001P003C01-SCONNA
M_A_CPU1_SB_CA<2>        U1               C41      SOCKET4677_AZIFS054P001C01-SOCA
M_A_CPU1_SB_CA<3>        J17              223      SCONN288_ADR50001P013C01-SCONNA
M_A_CPU1_SB_CA<3>        J18              223      SCONN288_ADR50001P003C01-SCONNA
M_A_CPU1_SB_CA<3>        U1               E41      SOCKET4677_AZIFS054P001C01-SOCA
M_A_CPU1_SB_CA<4>        J17              80       SCONN288_ADR50001P013C01-SCONNA
M_A_CPU1_SB_CA<4>        J18              80       SCONN288_ADR50001P003C01-SCONNA
M_A_CPU1_SB_CA<4>        U1               B40      SOCKET4677_AZIFS054P001C01-SOCA
M_A_CPU1_SB_CA<5>        J17              225      SCONN288_ADR50001P013C01-SCONNA
M_A_CPU1_SB_CA<5>        J18              225      SCONN288_ADR50001P003C01-SCONNA
M_A_CPU1_SB_CA<5>        U1               F40      SOCKET4677_AZIFS054P001C01-SOCA
M_A_CPU1_SB_CA<6>        J17              82       SCONN288_ADR50001P013C01-SCONNA
M_A_CPU1_SB_CA<6>        J18              82       SCONN288_ADR50001P003C01-SCONNA
M_A_CPU1_SB_CA<6>        U1               A39      SOCKET4677_AZIFS054P001C01-SOCA
M_A_CPU1_SB_CB<0>        J17              96       SCONN288_ADR50001P013C01-SCONNA
M_A_CPU1_SB_CB<0>        J18              96       SCONN288_ADR50001P003C01-SCONNA
M_A_CPU1_SB_CB<0>        U1               B32      SOCKET4677_AZIFS054P001C01-SOCA
M_A_CPU1_SB_CB<1>        J17              98       SCONN288_ADR50001P013C01-SCONNA
M_A_CPU1_SB_CB<1>        J18              98       SCONN288_ADR50001P003C01-SCONNA
M_A_CPU1_SB_CB<1>        U1               C31      SOCKET4677_AZIFS054P001C01-SOCA
M_A_CPU1_SB_CB<2>        J17              241      SCONN288_ADR50001P013C01-SCONNA
M_A_CPU1_SB_CB<2>        J18              241      SCONN288_ADR50001P003C01-SCONNA
M_A_CPU1_SB_CB<2>        U1               F32      SOCKET4677_AZIFS054P001C01-SOCA
M_A_CPU1_SB_CB<3>        J17              243      SCONN288_ADR50001P013C01-SCONNA
M_A_CPU1_SB_CB<3>        J18              243      SCONN288_ADR50001P003C01-SCONNA
M_A_CPU1_SB_CB<3>        U1               E31      SOCKET4677_AZIFS054P001C01-SOCA
M_A_CPU1_SB_CB<4>        J17              89       SCONN288_ADR50001P013C01-SCONNA
M_A_CPU1_SB_CB<4>        J18              89       SCONN288_ADR50001P003C01-SCONNA
M_A_CPU1_SB_CB<4>        U1               C35      SOCKET4677_AZIFS054P001C01-SOCA
M_A_CPU1_SB_CB<5>        J17              91       SCONN288_ADR50001P013C01-SCONNA
M_A_CPU1_SB_CB<5>        J18              91       SCONN288_ADR50001P003C01-SCONNA
M_A_CPU1_SB_CB<5>        U1               B34      SOCKET4677_AZIFS054P001C01-SOCA
M_A_CPU1_SB_CB<6>        J17              234      SCONN288_ADR50001P013C01-SCONNA
M_A_CPU1_SB_CB<6>        J18              234      SCONN288_ADR50001P003C01-SCONNA
M_A_CPU1_SB_CB<6>        U1               E35      SOCKET4677_AZIFS054P001C01-SOCA
M_A_CPU1_SB_CB<7>        J17              236      SCONN288_ADR50001P013C01-SCONNA
M_A_CPU1_SB_CB<7>        J18              236      SCONN288_ADR50001P003C01-SCONNA
M_A_CPU1_SB_CB<7>        U1               F34      SOCKET4677_AZIFS054P001C01-SOCA
M_A_CPU1_SB_CS_N<0>      J17              84       SCONN288_ADR50001P013C01-SCONNA
M_A_CPU1_SB_CS_N<0>      U1               B38      SOCKET4677_AZIFS054P001C01-SOCA
M_A_CPU1_SB_CS_N<1>      J17              229      SCONN288_ADR50001P013C01-SCONNA
M_A_CPU1_SB_CS_N<1>      U1               C37      SOCKET4677_AZIFS054P001C01-SOCA
M_A_CPU1_SB_CS_N<2>      J18              84       SCONN288_ADR50001P003C01-SCONNA
M_A_CPU1_SB_CS_N<2>      U1               F38      SOCKET4677_AZIFS054P001C01-SOCA
M_A_CPU1_SB_CS_N<3>      J18              229      SCONN288_ADR50001P003C01-SCONNA
M_A_CPU1_SB_CS_N<3>      U1               E37      SOCKET4677_AZIFS054P001C01-SOCA
M_A_CPU1_SB_DQ<0>        J17              100      SCONN288_ADR50001P013C01-SCONNA
M_A_CPU1_SB_DQ<0>        J18              100      SCONN288_ADR50001P003C01-SCONNA
M_A_CPU1_SB_DQ<0>        U1               K32      SOCKET4677_AZIFS054P001C01-SOCA
M_A_CPU1_SB_DQ<1>        J17              102      SCONN288_ADR50001P013C01-SCONNA
M_A_CPU1_SB_DQ<1>        J18              102      SCONN288_ADR50001P003C01-SCONNA
M_A_CPU1_SB_DQ<1>        U1               J31      SOCKET4677_AZIFS054P001C01-SOCA
M_A_CPU1_SB_DQ<2>        J17              245      SCONN288_ADR50001P013C01-SCONNA
M_A_CPU1_SB_DQ<2>        J18              245      SCONN288_ADR50001P003C01-SCONNA
M_A_CPU1_SB_DQ<2>        U1               M32      SOCKET4677_AZIFS054P001C01-SOCA
M_A_CPU1_SB_DQ<3>        J17              247      SCONN288_ADR50001P013C01-SCONNA
M_A_CPU1_SB_DQ<3>        J18              247      SCONN288_ADR50001P003C01-SCONNA
M_A_CPU1_SB_DQ<3>        U1               N31      SOCKET4677_AZIFS054P001C01-SOCA
M_A_CPU1_SB_DQ<4>        J17              107      SCONN288_ADR50001P013C01-SCONNA
M_A_CPU1_SB_DQ<4>        J18              107      SCONN288_ADR50001P003C01-SCONNA
M_A_CPU1_SB_DQ<4>        U1               J29      SOCKET4677_AZIFS054P001C01-SOCA
M_A_CPU1_SB_DQ<5>        J17              109      SCONN288_ADR50001P013C01-SCONNA
M_A_CPU1_SB_DQ<5>        J18              109      SCONN288_ADR50001P003C01-SCONNA
M_A_CPU1_SB_DQ<5>        U1               K28      SOCKET4677_AZIFS054P001C01-SOCA
M_A_CPU1_SB_DQ<6>        J17              252      SCONN288_ADR50001P013C01-SCONNA
M_A_CPU1_SB_DQ<6>        J18              252      SCONN288_ADR50001P003C01-SCONNA
M_A_CPU1_SB_DQ<6>        U1               N29      SOCKET4677_AZIFS054P001C01-SOCA
M_A_CPU1_SB_DQ<7>        J17              254      SCONN288_ADR50001P013C01-SCONNA
M_A_CPU1_SB_DQ<7>        J18              254      SCONN288_ADR50001P003C01-SCONNA
M_A_CPU1_SB_DQ<7>        U1               M28      SOCKET4677_AZIFS054P001C01-SOCA
M_A_CPU1_SB_DQ<8>        J17              111      SCONN288_ADR50001P013C01-SCONNA
M_A_CPU1_SB_DQ<8>        J18              111      SCONN288_ADR50001P003C01-SCONNA
M_A_CPU1_SB_DQ<8>        U1               C29      SOCKET4677_AZIFS054P001C01-SOCA
M_A_CPU1_SB_DQ<9>        J17              113      SCONN288_ADR50001P013C01-SCONNA
M_A_CPU1_SB_DQ<9>        J18              113      SCONN288_ADR50001P003C01-SCONNA
M_A_CPU1_SB_DQ<9>        U1               B28      SOCKET4677_AZIFS054P001C01-SOCA
M_A_CPU1_SB_DQ<10>       J17              256      SCONN288_ADR50001P013C01-SCONNA
M_A_CPU1_SB_DQ<10>       J18              256      SCONN288_ADR50001P003C01-SCONNA
M_A_CPU1_SB_DQ<10>       U1               E29      SOCKET4677_AZIFS054P001C01-SOCA
M_A_CPU1_SB_DQ<11>       J17              258      SCONN288_ADR50001P013C01-SCONNA
M_A_CPU1_SB_DQ<11>       J18              258      SCONN288_ADR50001P003C01-SCONNA
M_A_CPU1_SB_DQ<11>       U1               F28      SOCKET4677_AZIFS054P001C01-SOCA
M_A_CPU1_SB_DQ<12>       J17              118      SCONN288_ADR50001P013C01-SCONNA
M_A_CPU1_SB_DQ<12>       J18              118      SCONN288_ADR50001P003C01-SCONNA
M_A_CPU1_SB_DQ<12>       U1               B26      SOCKET4677_AZIFS054P001C01-SOCA
M_A_CPU1_SB_DQ<13>       J17              120      SCONN288_ADR50001P013C01-SCONNA
M_A_CPU1_SB_DQ<13>       J18              120      SCONN288_ADR50001P003C01-SCONNA
M_A_CPU1_SB_DQ<13>       U1               C25      SOCKET4677_AZIFS054P001C01-SOCA
M_A_CPU1_SB_DQ<14>       J17              263      SCONN288_ADR50001P013C01-SCONNA
M_A_CPU1_SB_DQ<14>       J18              263      SCONN288_ADR50001P003C01-SCONNA
M_A_CPU1_SB_DQ<14>       U1               F26      SOCKET4677_AZIFS054P001C01-SOCA
M_A_CPU1_SB_DQ<15>       J17              265      SCONN288_ADR50001P013C01-SCONNA
M_A_CPU1_SB_DQ<15>       J18              265      SCONN288_ADR50001P003C01-SCONNA
M_A_CPU1_SB_DQ<15>       U1               E25      SOCKET4677_AZIFS054P001C01-SOCA
M_A_CPU1_SB_DQ<16>       J17              122      SCONN288_ADR50001P013C01-SCONNA
M_A_CPU1_SB_DQ<16>       J18              122      SCONN288_ADR50001P003C01-SCONNA
M_A_CPU1_SB_DQ<16>       U1               C23      SOCKET4677_AZIFS054P001C01-SOCA
M_A_CPU1_SB_DQ<17>       J17              124      SCONN288_ADR50001P013C01-SCONNA
M_A_CPU1_SB_DQ<17>       J18              124      SCONN288_ADR50001P003C01-SCONNA
M_A_CPU1_SB_DQ<17>       U1               B22      SOCKET4677_AZIFS054P001C01-SOCA
M_A_CPU1_SB_DQ<18>       J17              267      SCONN288_ADR50001P013C01-SCONNA
M_A_CPU1_SB_DQ<18>       J18              267      SCONN288_ADR50001P003C01-SCONNA
M_A_CPU1_SB_DQ<18>       U1               E23      SOCKET4677_AZIFS054P001C01-SOCA
M_A_CPU1_SB_DQ<19>       J17              269      SCONN288_ADR50001P013C01-SCONNA
M_A_CPU1_SB_DQ<19>       J18              269      SCONN288_ADR50001P003C01-SCONNA
M_A_CPU1_SB_DQ<19>       U1               F22      SOCKET4677_AZIFS054P001C01-SOCA
M_A_CPU1_SB_DQ<20>       J17              129      SCONN288_ADR50001P013C01-SCONNA
M_A_CPU1_SB_DQ<20>       J18              129      SCONN288_ADR50001P003C01-SCONNA
M_A_CPU1_SB_DQ<20>       U1               B20      SOCKET4677_AZIFS054P001C01-SOCA
M_A_CPU1_SB_DQ<21>       J17              131      SCONN288_ADR50001P013C01-SCONNA
M_A_CPU1_SB_DQ<21>       J18              131      SCONN288_ADR50001P003C01-SCONNA
M_A_CPU1_SB_DQ<21>       U1               C19      SOCKET4677_AZIFS054P001C01-SOCA
M_A_CPU1_SB_DQ<22>       J17              274      SCONN288_ADR50001P013C01-SCONNA
M_A_CPU1_SB_DQ<22>       J18              274      SCONN288_ADR50001P003C01-SCONNA
M_A_CPU1_SB_DQ<22>       U1               F20      SOCKET4677_AZIFS054P001C01-SOCA
M_A_CPU1_SB_DQ<23>       J17              276      SCONN288_ADR50001P013C01-SCONNA
M_A_CPU1_SB_DQ<23>       J18              276      SCONN288_ADR50001P003C01-SCONNA
M_A_CPU1_SB_DQ<23>       U1               E19      SOCKET4677_AZIFS054P001C01-SOCA
M_A_CPU1_SB_DQ<24>       J17              133      SCONN288_ADR50001P013C01-SCONNA
M_A_CPU1_SB_DQ<24>       J18              133      SCONN288_ADR50001P003C01-SCONNA
M_A_CPU1_SB_DQ<24>       U1               C11      SOCKET4677_AZIFS054P001C01-SOCA
M_A_CPU1_SB_DQ<25>       J17              135      SCONN288_ADR50001P013C01-SCONNA
M_A_CPU1_SB_DQ<25>       J18              135      SCONN288_ADR50001P003C01-SCONNA
M_A_CPU1_SB_DQ<25>       U1               B10      SOCKET4677_AZIFS054P001C01-SOCA
M_A_CPU1_SB_DQ<26>       J17              278      SCONN288_ADR50001P013C01-SCONNA
M_A_CPU1_SB_DQ<26>       J18              278      SCONN288_ADR50001P003C01-SCONNA
M_A_CPU1_SB_DQ<26>       U1               E11      SOCKET4677_AZIFS054P001C01-SOCA
M_A_CPU1_SB_DQ<27>       J17              280      SCONN288_ADR50001P013C01-SCONNA
M_A_CPU1_SB_DQ<27>       J18              280      SCONN288_ADR50001P003C01-SCONNA
M_A_CPU1_SB_DQ<27>       U1               F10      SOCKET4677_AZIFS054P001C01-SOCA
M_A_CPU1_SB_DQ<28>       J17              140      SCONN288_ADR50001P013C01-SCONNA
M_A_CPU1_SB_DQ<28>       J18              140      SCONN288_ADR50001P003C01-SCONNA
M_A_CPU1_SB_DQ<28>       U1               B8       SOCKET4677_AZIFS054P001C01-SOCA
M_A_CPU1_SB_DQ<29>       J17              142      SCONN288_ADR50001P013C01-SCONNA
M_A_CPU1_SB_DQ<29>       J18              142      SCONN288_ADR50001P003C01-SCONNA
M_A_CPU1_SB_DQ<29>       U1               C7       SOCKET4677_AZIFS054P001C01-SOCA
M_A_CPU1_SB_DQ<30>       J17              285      SCONN288_ADR50001P013C01-SCONNA
M_A_CPU1_SB_DQ<30>       J18              285      SCONN288_ADR50001P003C01-SCONNA
M_A_CPU1_SB_DQ<30>       U1               F8       SOCKET4677_AZIFS054P001C01-SOCA
M_A_CPU1_SB_DQ<31>       J17              287      SCONN288_ADR50001P013C01-SCONNA
M_A_CPU1_SB_DQ<31>       J18              287      SCONN288_ADR50001P003C01-SCONNA
M_A_CPU1_SB_DQ<31>       U1               E7       SOCKET4677_AZIFS054P001C01-SOCA
M_A_CPU1_SB_DQS_DN<0>    J17              105      SCONN288_ADR50001P013C01-SCONNA
M_A_CPU1_SB_DQS_DN<0>    J18              105      SCONN288_ADR50001P003C01-SCONNA
M_A_CPU1_SB_DQS_DN<0>    U1               H30      SOCKET4677_AZIFS054P001C01-SOCA
M_A_CPU1_SB_DQS_DN<1>    J17              116      SCONN288_ADR50001P013C01-SCONNA
M_A_CPU1_SB_DQS_DN<1>    J18              116      SCONN288_ADR50001P003C01-SCONNA
M_A_CPU1_SB_DQS_DN<1>    U1               A27      SOCKET4677_AZIFS054P001C01-SOCA
M_A_CPU1_SB_DQS_DN<2>    J17              127      SCONN288_ADR50001P013C01-SCONNA
M_A_CPU1_SB_DQS_DN<2>    J18              127      SCONN288_ADR50001P003C01-SCONNA
M_A_CPU1_SB_DQS_DN<2>    U1               A21      SOCKET4677_AZIFS054P001C01-SOCA
M_A_CPU1_SB_DQS_DN<3>    J17              138      SCONN288_ADR50001P013C01-SCONNA
M_A_CPU1_SB_DQS_DN<3>    J18              138      SCONN288_ADR50001P003C01-SCONNA
M_A_CPU1_SB_DQS_DN<3>    U1               A9       SOCKET4677_AZIFS054P001C01-SOCA
M_A_CPU1_SB_DQS_DN<4>    J17              238      SCONN288_ADR50001P013C01-SCONNA
M_A_CPU1_SB_DQS_DN<4>    J18              238      SCONN288_ADR50001P003C01-SCONNA
M_A_CPU1_SB_DQS_DN<4>    U1               G33      SOCKET4677_AZIFS054P001C01-SOCA
M_A_CPU1_SB_DQS_DN<5>    J17              249      SCONN288_ADR50001P013C01-SCONNA
M_A_CPU1_SB_DQS_DN<5>    J18              249      SCONN288_ADR50001P003C01-SCONNA
M_A_CPU1_SB_DQS_DN<5>    U1               M30      SOCKET4677_AZIFS054P001C01-SOCA
M_A_CPU1_SB_DQS_DN<6>    J17              260      SCONN288_ADR50001P013C01-SCONNA
M_A_CPU1_SB_DQS_DN<6>    J18              260      SCONN288_ADR50001P003C01-SCONNA
M_A_CPU1_SB_DQS_DN<6>    U1               G27      SOCKET4677_AZIFS054P001C01-SOCA
M_A_CPU1_SB_DQS_DN<7>    J17              271      SCONN288_ADR50001P013C01-SCONNA
M_A_CPU1_SB_DQS_DN<7>    J18              271      SCONN288_ADR50001P003C01-SCONNA
M_A_CPU1_SB_DQS_DN<7>    U1               G21      SOCKET4677_AZIFS054P001C01-SOCA
M_A_CPU1_SB_DQS_DN<8>    J17              282      SCONN288_ADR50001P013C01-SCONNA
M_A_CPU1_SB_DQS_DN<8>    J18              282      SCONN288_ADR50001P003C01-SCONNA
M_A_CPU1_SB_DQS_DN<8>    U1               G9       SOCKET4677_AZIFS054P001C01-SOCA
M_A_CPU1_SB_DQS_DN<9>    J17              94       SCONN288_ADR50001P013C01-SCONNA
M_A_CPU1_SB_DQS_DN<9>    J18              94       SCONN288_ADR50001P003C01-SCONNA
M_A_CPU1_SB_DQS_DN<9>    U1               A33      SOCKET4677_AZIFS054P001C01-SOCA
M_A_CPU1_SB_DQS_DP<0>    J17              104      SCONN288_ADR50001P013C01-SCONNA
M_A_CPU1_SB_DQS_DP<0>    J18              104      SCONN288_ADR50001P003C01-SCONNA
M_A_CPU1_SB_DQS_DP<0>    U1               K30      SOCKET4677_AZIFS054P001C01-SOCA
M_A_CPU1_SB_DQS_DP<1>    J17              115      SCONN288_ADR50001P013C01-SCONNA
M_A_CPU1_SB_DQS_DP<1>    J18              115      SCONN288_ADR50001P003C01-SCONNA
M_A_CPU1_SB_DQS_DP<1>    U1               C27      SOCKET4677_AZIFS054P001C01-SOCA
M_A_CPU1_SB_DQS_DP<2>    J17              126      SCONN288_ADR50001P013C01-SCONNA
M_A_CPU1_SB_DQS_DP<2>    J18              126      SCONN288_ADR50001P003C01-SCONNA
M_A_CPU1_SB_DQS_DP<2>    U1               C21      SOCKET4677_AZIFS054P001C01-SOCA
M_A_CPU1_SB_DQS_DP<3>    J17              137      SCONN288_ADR50001P013C01-SCONNA
M_A_CPU1_SB_DQS_DP<3>    J18              137      SCONN288_ADR50001P003C01-SCONNA
M_A_CPU1_SB_DQS_DP<3>    U1               C9       SOCKET4677_AZIFS054P001C01-SOCA
M_A_CPU1_SB_DQS_DP<4>    J17              239      SCONN288_ADR50001P013C01-SCONNA
M_A_CPU1_SB_DQS_DP<4>    J18              239      SCONN288_ADR50001P003C01-SCONNA
M_A_CPU1_SB_DQS_DP<4>    U1               E33      SOCKET4677_AZIFS054P001C01-SOCA
M_A_CPU1_SB_DQS_DP<5>    J17              250      SCONN288_ADR50001P013C01-SCONNA
M_A_CPU1_SB_DQS_DP<5>    J18              250      SCONN288_ADR50001P003C01-SCONNA
M_A_CPU1_SB_DQS_DP<5>    U1               P30      SOCKET4677_AZIFS054P001C01-SOCA
M_A_CPU1_SB_DQS_DP<6>    J17              261      SCONN288_ADR50001P013C01-SCONNA
M_A_CPU1_SB_DQS_DP<6>    J18              261      SCONN288_ADR50001P003C01-SCONNA
M_A_CPU1_SB_DQS_DP<6>    U1               E27      SOCKET4677_AZIFS054P001C01-SOCA
M_A_CPU1_SB_DQS_DP<7>    J17              272      SCONN288_ADR50001P013C01-SCONNA
M_A_CPU1_SB_DQS_DP<7>    J18              272      SCONN288_ADR50001P003C01-SCONNA
M_A_CPU1_SB_DQS_DP<7>    U1               E21      SOCKET4677_AZIFS054P001C01-SOCA
M_A_CPU1_SB_DQS_DP<8>    J17              283      SCONN288_ADR50001P013C01-SCONNA
M_A_CPU1_SB_DQS_DP<8>    J18              283      SCONN288_ADR50001P003C01-SCONNA
M_A_CPU1_SB_DQS_DP<8>    U1               E9       SOCKET4677_AZIFS054P001C01-SOCA
M_A_CPU1_SB_DQS_DP<9>    J17              93       SCONN288_ADR50001P013C01-SCONNA
M_A_CPU1_SB_DQS_DP<9>    J18              93       SCONN288_ADR50001P003C01-SCONNA
M_A_CPU1_SB_DQS_DP<9>    U1               C33      SOCKET4677_AZIFS054P001C01-SOCA
M_A_CPU1_SB_PAR          J17              227      SCONN288_ADR50001P013C01-SCONNA
M_A_CPU1_SB_PAR          J18              227      SCONN288_ADR50001P003C01-SCONNA
M_A_CPU1_SB_PAR          U1               G39      SOCKET4677_AZIFS054P001C01-SOCA
M_A_CPU1_SB_RSP<0>       J17              87       SCONN288_ADR50001P013C01-SCONNA
M_A_CPU1_SB_RSP<0>       U1               AV44     SOCKET4677_AZIFS054P001C01-SOCA
M_A_CPU1_SB_RSP<1>       J18              87       SCONN288_ADR50001P003C01-SCONNA
M_A_CPU1_SB_RSP<1>       U1               AV42     SOCKET4677_AZIFS054P001C01-SOCA
M_B_CPU0_ALERT_N         J3               62       SCONN288_ADR50001P013C01-SCONNA
M_B_CPU0_ALERT_N         J4               62       SCONN288_ADR50001P003C01-SCONNA
M_B_CPU0_ALERT_N         U2               AV49     SOCKET4677_AZIFS054P001C01-SOCA
M_B_CPU0_CLK_DN<0>       J3               218      SCONN288_ADR50001P013C01-SCONNA
M_B_CPU0_CLK_DN<0>       U2               R45      SOCKET4677_AZIFS054P001C01-SOCA
M_B_CPU0_CLK_DN<1>       J4               218      SCONN288_ADR50001P003C01-SCONNA
M_B_CPU0_CLK_DN<1>       U2               W45      SOCKET4677_AZIFS054P001C01-SOCA
M_B_CPU0_CLK_DP<0>       J3               217      SCONN288_ADR50001P013C01-SCONNA
M_B_CPU0_CLK_DP<0>       U2               U45      SOCKET4677_AZIFS054P001C01-SOCA
M_B_CPU0_CLK_DP<1>       J4               217      SCONN288_ADR50001P003C01-SCONNA
M_B_CPU0_CLK_DP<1>       U2               AA45     SOCKET4677_AZIFS054P001C01-SOCA
M_B_CPU0_SA_CA<0>        J3               66       SCONN288_ADR50001P013C01-SCONNA
M_B_CPU0_SA_CA<0>        J4               66       SCONN288_ADR50001P003C01-SCONNA
M_B_CPU0_SA_CA<0>        U2               H49      SOCKET4677_AZIFS054P001C01-SOCA
M_B_CPU0_SA_CA<1>        J3               211      SCONN288_ADR50001P013C01-SCONNA
M_B_CPU0_SA_CA<1>        J4               211      SCONN288_ADR50001P003C01-SCONNA
M_B_CPU0_SA_CA<1>        U2               P49      SOCKET4677_AZIFS054P001C01-SOCA
M_B_CPU0_SA_CA<2>        J3               68       SCONN288_ADR50001P013C01-SCONNA
M_B_CPU0_SA_CA<2>        J4               68       SCONN288_ADR50001P003C01-SCONNA
M_B_CPU0_SA_CA<2>        U2               J48      SOCKET4677_AZIFS054P001C01-SOCA
M_B_CPU0_SA_CA<3>        J3               213      SCONN288_ADR50001P013C01-SCONNA
M_B_CPU0_SA_CA<3>        J4               213      SCONN288_ADR50001P003C01-SCONNA
M_B_CPU0_SA_CA<3>        U2               N48      SOCKET4677_AZIFS054P001C01-SOCA
M_B_CPU0_SA_CA<4>        J3               70       SCONN288_ADR50001P013C01-SCONNA
M_B_CPU0_SA_CA<4>        J4               70       SCONN288_ADR50001P003C01-SCONNA
M_B_CPU0_SA_CA<4>        U2               K47      SOCKET4677_AZIFS054P001C01-SOCA
M_B_CPU0_SA_CA<5>        J3               215      SCONN288_ADR50001P013C01-SCONNA
M_B_CPU0_SA_CA<5>        J4               215      SCONN288_ADR50001P003C01-SCONNA
M_B_CPU0_SA_CA<5>        U2               M47      SOCKET4677_AZIFS054P001C01-SOCA
M_B_CPU0_SA_CA<6>        J3               72       SCONN288_ADR50001P013C01-SCONNA
M_B_CPU0_SA_CA<6>        J4               72       SCONN288_ADR50001P003C01-SCONNA
M_B_CPU0_SA_CA<6>        U2               Y44      SOCKET4677_AZIFS054P001C01-SOCA
M_B_CPU0_SA_CB<0>        J3               51       SCONN288_ADR50001P013C01-SCONNA
M_B_CPU0_SA_CB<0>        J4               51       SCONN288_ADR50001P003C01-SCONNA
M_B_CPU0_SA_CB<0>        U2               K57      SOCKET4677_AZIFS054P001C01-SOCA
M_B_CPU0_SA_CB<1>        J3               53       SCONN288_ADR50001P013C01-SCONNA
M_B_CPU0_SA_CB<1>        J4               53       SCONN288_ADR50001P003C01-SCONNA
M_B_CPU0_SA_CB<1>        U2               J56      SOCKET4677_AZIFS054P001C01-SOCA
M_B_CPU0_SA_CB<2>        J3               196      SCONN288_ADR50001P013C01-SCONNA
M_B_CPU0_SA_CB<2>        J4               196      SCONN288_ADR50001P003C01-SCONNA
M_B_CPU0_SA_CB<2>        U2               M57      SOCKET4677_AZIFS054P001C01-SOCA
M_B_CPU0_SA_CB<3>        J3               198      SCONN288_ADR50001P013C01-SCONNA
M_B_CPU0_SA_CB<3>        J4               198      SCONN288_ADR50001P003C01-SCONNA
M_B_CPU0_SA_CB<3>        U2               N56      SOCKET4677_AZIFS054P001C01-SOCA
M_B_CPU0_SA_CB<4>        J3               58       SCONN288_ADR50001P013C01-SCONNA
M_B_CPU0_SA_CB<4>        J4               58       SCONN288_ADR50001P003C01-SCONNA
M_B_CPU0_SA_CB<4>        U2               J54      SOCKET4677_AZIFS054P001C01-SOCA
M_B_CPU0_SA_CB<5>        J3               60       SCONN288_ADR50001P013C01-SCONNA
M_B_CPU0_SA_CB<5>        J4               60       SCONN288_ADR50001P003C01-SCONNA
M_B_CPU0_SA_CB<5>        U2               K53      SOCKET4677_AZIFS054P001C01-SOCA
M_B_CPU0_SA_CB<6>        J3               203      SCONN288_ADR50001P013C01-SCONNA
M_B_CPU0_SA_CB<6>        J4               203      SCONN288_ADR50001P003C01-SCONNA
M_B_CPU0_SA_CB<6>        U2               N54      SOCKET4677_AZIFS054P001C01-SOCA
M_B_CPU0_SA_CB<7>        J3               205      SCONN288_ADR50001P013C01-SCONNA
M_B_CPU0_SA_CB<7>        J4               205      SCONN288_ADR50001P003C01-SCONNA
M_B_CPU0_SA_CB<7>        U2               M53      SOCKET4677_AZIFS054P001C01-SOCA
M_B_CPU0_SA_CS_N<0>      J3               64       SCONN288_ADR50001P013C01-SCONNA
M_B_CPU0_SA_CS_N<0>      U2               K51      SOCKET4677_AZIFS054P001C01-SOCA
M_B_CPU0_SA_CS_N<1>      J3               209      SCONN288_ADR50001P013C01-SCONNA
M_B_CPU0_SA_CS_N<1>      U2               J50      SOCKET4677_AZIFS054P001C01-SOCA
M_B_CPU0_SA_CS_N<2>      J4               64       SCONN288_ADR50001P003C01-SCONNA
M_B_CPU0_SA_CS_N<2>      U2               M51      SOCKET4677_AZIFS054P001C01-SOCA
M_B_CPU0_SA_CS_N<3>      J4               209      SCONN288_ADR50001P003C01-SCONNA
M_B_CPU0_SA_CS_N<3>      U2               N50      SOCKET4677_AZIFS054P001C01-SOCA
M_B_CPU0_SA_DQ<0>        J3               7        SCONN288_ADR50001P013C01-SCONNA
M_B_CPU0_SA_DQ<0>        J4               7        SCONN288_ADR50001P003C01-SCONNA
M_B_CPU0_SA_DQ<0>        U2               K75      SOCKET4677_AZIFS054P001C01-SOCA
M_B_CPU0_SA_DQ<1>        J3               9        SCONN288_ADR50001P013C01-SCONNA
M_B_CPU0_SA_DQ<1>        J4               9        SCONN288_ADR50001P003C01-SCONNA
M_B_CPU0_SA_DQ<1>        U2               J74      SOCKET4677_AZIFS054P001C01-SOCA
M_B_CPU0_SA_DQ<2>        J3               152      SCONN288_ADR50001P013C01-SCONNA
M_B_CPU0_SA_DQ<2>        J4               152      SCONN288_ADR50001P003C01-SCONNA
M_B_CPU0_SA_DQ<2>        U2               M75      SOCKET4677_AZIFS054P001C01-SOCA
M_B_CPU0_SA_DQ<3>        J3               154      SCONN288_ADR50001P013C01-SCONNA
M_B_CPU0_SA_DQ<3>        J4               154      SCONN288_ADR50001P003C01-SCONNA
M_B_CPU0_SA_DQ<3>        U2               N74      SOCKET4677_AZIFS054P001C01-SOCA
M_B_CPU0_SA_DQ<4>        J3               14       SCONN288_ADR50001P013C01-SCONNA
M_B_CPU0_SA_DQ<4>        J4               14       SCONN288_ADR50001P003C01-SCONNA
M_B_CPU0_SA_DQ<4>        U2               J72      SOCKET4677_AZIFS054P001C01-SOCA
M_B_CPU0_SA_DQ<5>        J3               16       SCONN288_ADR50001P013C01-SCONNA
M_B_CPU0_SA_DQ<5>        J4               16       SCONN288_ADR50001P003C01-SCONNA
M_B_CPU0_SA_DQ<5>        U2               K71      SOCKET4677_AZIFS054P001C01-SOCA
M_B_CPU0_SA_DQ<6>        J3               159      SCONN288_ADR50001P013C01-SCONNA
M_B_CPU0_SA_DQ<6>        J4               159      SCONN288_ADR50001P003C01-SCONNA
M_B_CPU0_SA_DQ<6>        U2               N72      SOCKET4677_AZIFS054P001C01-SOCA
M_B_CPU0_SA_DQ<7>        J3               161      SCONN288_ADR50001P013C01-SCONNA
M_B_CPU0_SA_DQ<7>        J4               161      SCONN288_ADR50001P003C01-SCONNA
M_B_CPU0_SA_DQ<7>        U2               M71      SOCKET4677_AZIFS054P001C01-SOCA
M_B_CPU0_SA_DQ<8>        J3               18       SCONN288_ADR50001P013C01-SCONNA
M_B_CPU0_SA_DQ<8>        J4               18       SCONN288_ADR50001P003C01-SCONNA
M_B_CPU0_SA_DQ<8>        U2               U72      SOCKET4677_AZIFS054P001C01-SOCA
M_B_CPU0_SA_DQ<9>        J3               20       SCONN288_ADR50001P013C01-SCONNA
M_B_CPU0_SA_DQ<9>        J4               20       SCONN288_ADR50001P003C01-SCONNA
M_B_CPU0_SA_DQ<9>        U2               T71      SOCKET4677_AZIFS054P001C01-SOCA
M_B_CPU0_SA_DQ<10>       J3               163      SCONN288_ADR50001P013C01-SCONNA
M_B_CPU0_SA_DQ<10>       J4               163      SCONN288_ADR50001P003C01-SCONNA
M_B_CPU0_SA_DQ<10>       U2               W72      SOCKET4677_AZIFS054P001C01-SOCA
M_B_CPU0_SA_DQ<11>       J3               165      SCONN288_ADR50001P013C01-SCONNA
M_B_CPU0_SA_DQ<11>       J4               165      SCONN288_ADR50001P003C01-SCONNA
M_B_CPU0_SA_DQ<11>       U2               Y71      SOCKET4677_AZIFS054P001C01-SOCA
M_B_CPU0_SA_DQ<12>       J3               25       SCONN288_ADR50001P013C01-SCONNA
M_B_CPU0_SA_DQ<12>       J4               25       SCONN288_ADR50001P003C01-SCONNA
M_B_CPU0_SA_DQ<12>       U2               T69      SOCKET4677_AZIFS054P001C01-SOCA
M_B_CPU0_SA_DQ<13>       J3               27       SCONN288_ADR50001P013C01-SCONNA
M_B_CPU0_SA_DQ<13>       J4               27       SCONN288_ADR50001P003C01-SCONNA
M_B_CPU0_SA_DQ<13>       U2               U68      SOCKET4677_AZIFS054P001C01-SOCA
M_B_CPU0_SA_DQ<14>       J3               170      SCONN288_ADR50001P013C01-SCONNA
M_B_CPU0_SA_DQ<14>       J4               170      SCONN288_ADR50001P003C01-SCONNA
M_B_CPU0_SA_DQ<14>       U2               Y69      SOCKET4677_AZIFS054P001C01-SOCA
M_B_CPU0_SA_DQ<15>       J3               172      SCONN288_ADR50001P013C01-SCONNA
M_B_CPU0_SA_DQ<15>       J4               172      SCONN288_ADR50001P003C01-SCONNA
M_B_CPU0_SA_DQ<15>       U2               W68      SOCKET4677_AZIFS054P001C01-SOCA
M_B_CPU0_SA_DQ<16>       J3               29       SCONN288_ADR50001P013C01-SCONNA
M_B_CPU0_SA_DQ<16>       J4               29       SCONN288_ADR50001P003C01-SCONNA
M_B_CPU0_SA_DQ<16>       U2               K63      SOCKET4677_AZIFS054P001C01-SOCA
M_B_CPU0_SA_DQ<17>       J3               31       SCONN288_ADR50001P013C01-SCONNA
M_B_CPU0_SA_DQ<17>       J4               31       SCONN288_ADR50001P003C01-SCONNA
M_B_CPU0_SA_DQ<17>       U2               J62      SOCKET4677_AZIFS054P001C01-SOCA
M_B_CPU0_SA_DQ<18>       J3               174      SCONN288_ADR50001P013C01-SCONNA
M_B_CPU0_SA_DQ<18>       J4               174      SCONN288_ADR50001P003C01-SCONNA
M_B_CPU0_SA_DQ<18>       U2               M63      SOCKET4677_AZIFS054P001C01-SOCA
M_B_CPU0_SA_DQ<19>       J3               176      SCONN288_ADR50001P013C01-SCONNA
M_B_CPU0_SA_DQ<19>       J4               176      SCONN288_ADR50001P003C01-SCONNA
M_B_CPU0_SA_DQ<19>       U2               N62      SOCKET4677_AZIFS054P001C01-SOCA
M_B_CPU0_SA_DQ<20>       J3               36       SCONN288_ADR50001P013C01-SCONNA
M_B_CPU0_SA_DQ<20>       J4               36       SCONN288_ADR50001P003C01-SCONNA
M_B_CPU0_SA_DQ<20>       U2               J60      SOCKET4677_AZIFS054P001C01-SOCA
M_B_CPU0_SA_DQ<21>       J3               38       SCONN288_ADR50001P013C01-SCONNA
M_B_CPU0_SA_DQ<21>       J4               38       SCONN288_ADR50001P003C01-SCONNA
M_B_CPU0_SA_DQ<21>       U2               K59      SOCKET4677_AZIFS054P001C01-SOCA
M_B_CPU0_SA_DQ<22>       J3               181      SCONN288_ADR50001P013C01-SCONNA
M_B_CPU0_SA_DQ<22>       J4               181      SCONN288_ADR50001P003C01-SCONNA
M_B_CPU0_SA_DQ<22>       U2               N60      SOCKET4677_AZIFS054P001C01-SOCA
M_B_CPU0_SA_DQ<23>       J3               183      SCONN288_ADR50001P013C01-SCONNA
M_B_CPU0_SA_DQ<23>       J4               183      SCONN288_ADR50001P003C01-SCONNA
M_B_CPU0_SA_DQ<23>       U2               M59      SOCKET4677_AZIFS054P001C01-SOCA
M_B_CPU0_SA_DQ<24>       J3               40       SCONN288_ADR50001P013C01-SCONNA
M_B_CPU0_SA_DQ<24>       J4               40       SCONN288_ADR50001P003C01-SCONNA
M_B_CPU0_SA_DQ<24>       U2               U60      SOCKET4677_AZIFS054P001C01-SOCA
M_B_CPU0_SA_DQ<25>       J3               42       SCONN288_ADR50001P013C01-SCONNA
M_B_CPU0_SA_DQ<25>       J4               42       SCONN288_ADR50001P003C01-SCONNA
M_B_CPU0_SA_DQ<25>       U2               T59      SOCKET4677_AZIFS054P001C01-SOCA
M_B_CPU0_SA_DQ<26>       J3               185      SCONN288_ADR50001P013C01-SCONNA
M_B_CPU0_SA_DQ<26>       J4               185      SCONN288_ADR50001P003C01-SCONNA
M_B_CPU0_SA_DQ<26>       U2               W60      SOCKET4677_AZIFS054P001C01-SOCA
M_B_CPU0_SA_DQ<27>       J3               187      SCONN288_ADR50001P013C01-SCONNA
M_B_CPU0_SA_DQ<27>       J4               187      SCONN288_ADR50001P003C01-SCONNA
M_B_CPU0_SA_DQ<27>       U2               Y59      SOCKET4677_AZIFS054P001C01-SOCA
M_B_CPU0_SA_DQ<28>       J3               47       SCONN288_ADR50001P013C01-SCONNA
M_B_CPU0_SA_DQ<28>       J4               47       SCONN288_ADR50001P003C01-SCONNA
M_B_CPU0_SA_DQ<28>       U2               T57      SOCKET4677_AZIFS054P001C01-SOCA
M_B_CPU0_SA_DQ<29>       J3               49       SCONN288_ADR50001P013C01-SCONNA
M_B_CPU0_SA_DQ<29>       J4               49       SCONN288_ADR50001P003C01-SCONNA
M_B_CPU0_SA_DQ<29>       U2               U56      SOCKET4677_AZIFS054P001C01-SOCA
M_B_CPU0_SA_DQ<30>       J3               192      SCONN288_ADR50001P013C01-SCONNA
M_B_CPU0_SA_DQ<30>       J4               192      SCONN288_ADR50001P003C01-SCONNA
M_B_CPU0_SA_DQ<30>       U2               Y57      SOCKET4677_AZIFS054P001C01-SOCA
M_B_CPU0_SA_DQ<31>       J3               194      SCONN288_ADR50001P013C01-SCONNA
M_B_CPU0_SA_DQ<31>       J4               194      SCONN288_ADR50001P003C01-SCONNA
M_B_CPU0_SA_DQ<31>       U2               W56      SOCKET4677_AZIFS054P001C01-SOCA
M_B_CPU0_SA_DQS_DN<0>    J3               12       SCONN288_ADR50001P013C01-SCONNA
M_B_CPU0_SA_DQS_DN<0>    J4               12       SCONN288_ADR50001P003C01-SCONNA
M_B_CPU0_SA_DQS_DN<0>    U2               H73      SOCKET4677_AZIFS054P001C01-SOCA
M_B_CPU0_SA_DQS_DN<1>    J3               23       SCONN288_ADR50001P013C01-SCONNA
M_B_CPU0_SA_DQS_DN<1>    J4               23       SCONN288_ADR50001P003C01-SCONNA
M_B_CPU0_SA_DQS_DN<1>    U2               R70      SOCKET4677_AZIFS054P001C01-SOCA
M_B_CPU0_SA_DQS_DN<2>    J3               34       SCONN288_ADR50001P013C01-SCONNA
M_B_CPU0_SA_DQS_DN<2>    J4               34       SCONN288_ADR50001P003C01-SCONNA
M_B_CPU0_SA_DQS_DN<2>    U2               H61      SOCKET4677_AZIFS054P001C01-SOCA
M_B_CPU0_SA_DQS_DN<3>    J3               45       SCONN288_ADR50001P013C01-SCONNA
M_B_CPU0_SA_DQS_DN<3>    J4               45       SCONN288_ADR50001P003C01-SCONNA
M_B_CPU0_SA_DQS_DN<3>    U2               R58      SOCKET4677_AZIFS054P001C01-SOCA
M_B_CPU0_SA_DQS_DN<4>    J3               56       SCONN288_ADR50001P013C01-SCONNA
M_B_CPU0_SA_DQS_DN<4>    J4               56       SCONN288_ADR50001P003C01-SCONNA
M_B_CPU0_SA_DQS_DN<4>    U2               H55      SOCKET4677_AZIFS054P001C01-SOCA
M_B_CPU0_SA_DQS_DN<5>    J3               156      SCONN288_ADR50001P013C01-SCONNA
M_B_CPU0_SA_DQS_DN<5>    J4               156      SCONN288_ADR50001P003C01-SCONNA
M_B_CPU0_SA_DQS_DN<5>    U2               M73      SOCKET4677_AZIFS054P001C01-SOCA
M_B_CPU0_SA_DQS_DN<6>    J3               167      SCONN288_ADR50001P013C01-SCONNA
M_B_CPU0_SA_DQS_DN<6>    J4               167      SCONN288_ADR50001P003C01-SCONNA
M_B_CPU0_SA_DQS_DN<6>    U2               AA70     SOCKET4677_AZIFS054P001C01-SOCA
M_B_CPU0_SA_DQS_DN<7>    J3               178      SCONN288_ADR50001P013C01-SCONNA
M_B_CPU0_SA_DQS_DN<7>    J4               178      SCONN288_ADR50001P003C01-SCONNA
M_B_CPU0_SA_DQS_DN<7>    U2               M61      SOCKET4677_AZIFS054P001C01-SOCA
M_B_CPU0_SA_DQS_DN<8>    J3               189      SCONN288_ADR50001P013C01-SCONNA
M_B_CPU0_SA_DQS_DN<8>    J4               189      SCONN288_ADR50001P003C01-SCONNA
M_B_CPU0_SA_DQS_DN<8>    U2               AA58     SOCKET4677_AZIFS054P001C01-SOCA
M_B_CPU0_SA_DQS_DN<9>    J3               200      SCONN288_ADR50001P013C01-SCONNA
M_B_CPU0_SA_DQS_DN<9>    J4               200      SCONN288_ADR50001P003C01-SCONNA
M_B_CPU0_SA_DQS_DN<9>    U2               M55      SOCKET4677_AZIFS054P001C01-SOCA
M_B_CPU0_SA_DQS_DP<0>    J3               11       SCONN288_ADR50001P013C01-SCONNA
M_B_CPU0_SA_DQS_DP<0>    J4               11       SCONN288_ADR50001P003C01-SCONNA
M_B_CPU0_SA_DQS_DP<0>    U2               K73      SOCKET4677_AZIFS054P001C01-SOCA
M_B_CPU0_SA_DQS_DP<1>    J3               22       SCONN288_ADR50001P013C01-SCONNA
M_B_CPU0_SA_DQS_DP<1>    J4               22       SCONN288_ADR50001P003C01-SCONNA
M_B_CPU0_SA_DQS_DP<1>    U2               U70      SOCKET4677_AZIFS054P001C01-SOCA
M_B_CPU0_SA_DQS_DP<2>    J3               33       SCONN288_ADR50001P013C01-SCONNA
M_B_CPU0_SA_DQS_DP<2>    J4               33       SCONN288_ADR50001P003C01-SCONNA
M_B_CPU0_SA_DQS_DP<2>    U2               K61      SOCKET4677_AZIFS054P001C01-SOCA
M_B_CPU0_SA_DQS_DP<3>    J3               44       SCONN288_ADR50001P013C01-SCONNA
M_B_CPU0_SA_DQS_DP<3>    J4               44       SCONN288_ADR50001P003C01-SCONNA
M_B_CPU0_SA_DQS_DP<3>    U2               U58      SOCKET4677_AZIFS054P001C01-SOCA
M_B_CPU0_SA_DQS_DP<4>    J3               55       SCONN288_ADR50001P013C01-SCONNA
M_B_CPU0_SA_DQS_DP<4>    J4               55       SCONN288_ADR50001P003C01-SCONNA
M_B_CPU0_SA_DQS_DP<4>    U2               K55      SOCKET4677_AZIFS054P001C01-SOCA
M_B_CPU0_SA_DQS_DP<5>    J3               157      SCONN288_ADR50001P013C01-SCONNA
M_B_CPU0_SA_DQS_DP<5>    J4               157      SCONN288_ADR50001P003C01-SCONNA
M_B_CPU0_SA_DQS_DP<5>    U2               P73      SOCKET4677_AZIFS054P001C01-SOCA
M_B_CPU0_SA_DQS_DP<6>    J3               168      SCONN288_ADR50001P013C01-SCONNA
M_B_CPU0_SA_DQS_DP<6>    J4               168      SCONN288_ADR50001P003C01-SCONNA
M_B_CPU0_SA_DQS_DP<6>    U2               W70      SOCKET4677_AZIFS054P001C01-SOCA
M_B_CPU0_SA_DQS_DP<7>    J3               179      SCONN288_ADR50001P013C01-SCONNA
M_B_CPU0_SA_DQS_DP<7>    J4               179      SCONN288_ADR50001P003C01-SCONNA
M_B_CPU0_SA_DQS_DP<7>    U2               P61      SOCKET4677_AZIFS054P001C01-SOCA
M_B_CPU0_SA_DQS_DP<8>    J3               190      SCONN288_ADR50001P013C01-SCONNA
M_B_CPU0_SA_DQS_DP<8>    J4               190      SCONN288_ADR50001P003C01-SCONNA
M_B_CPU0_SA_DQS_DP<8>    U2               W58      SOCKET4677_AZIFS054P001C01-SOCA
M_B_CPU0_SA_DQS_DP<9>    J3               201      SCONN288_ADR50001P013C01-SCONNA
M_B_CPU0_SA_DQS_DP<9>    J4               201      SCONN288_ADR50001P003C01-SCONNA
M_B_CPU0_SA_DQS_DP<9>    U2               P55      SOCKET4677_AZIFS054P001C01-SOCA
M_B_CPU0_SA_PAR          J3               74       SCONN288_ADR50001P013C01-SCONNA
M_B_CPU0_SA_PAR          J4               74       SCONN288_ADR50001P003C01-SCONNA
M_B_CPU0_SA_PAR          U2               W43      SOCKET4677_AZIFS054P001C01-SOCA
M_B_CPU0_SA_RSP<0>       J3               86       SCONN288_ADR50001P013C01-SCONNA
M_B_CPU0_SA_RSP<0>       U2               AL48     SOCKET4677_AZIFS054P001C01-SOCA
M_B_CPU0_SA_RSP<1>       J4               86       SCONN288_ADR50001P003C01-SCONNA
M_B_CPU0_SA_RSP<1>       U2               AK47     SOCKET4677_AZIFS054P001C01-SOCA
M_B_CPU0_SB_CA<0>        J3               76       SCONN288_ADR50001P013C01-SCONNA
M_B_CPU0_SB_CA<0>        J4               76       SCONN288_ADR50001P003C01-SCONNA
M_B_CPU0_SB_CA<0>        U2               T44      SOCKET4677_AZIFS054P001C01-SOCA
M_B_CPU0_SB_CA<1>        J3               221      SCONN288_ADR50001P013C01-SCONNA
M_B_CPU0_SB_CA<1>        J4               221      SCONN288_ADR50001P003C01-SCONNA
M_B_CPU0_SB_CA<1>        U2               U43      SOCKET4677_AZIFS054P001C01-SOCA
M_B_CPU0_SB_CA<2>        J3               78       SCONN288_ADR50001P013C01-SCONNA
M_B_CPU0_SB_CA<2>        J4               78       SCONN288_ADR50001P003C01-SCONNA
M_B_CPU0_SB_CA<2>        U2               K44      SOCKET4677_AZIFS054P001C01-SOCA
M_B_CPU0_SB_CA<3>        J3               223      SCONN288_ADR50001P013C01-SCONNA
M_B_CPU0_SB_CA<3>        J4               223      SCONN288_ADR50001P003C01-SCONNA
M_B_CPU0_SB_CA<3>        U2               M44      SOCKET4677_AZIFS054P001C01-SOCA
M_B_CPU0_SB_CA<4>        J3               80       SCONN288_ADR50001P013C01-SCONNA
M_B_CPU0_SB_CA<4>        J4               80       SCONN288_ADR50001P003C01-SCONNA
M_B_CPU0_SB_CA<4>        U2               J43      SOCKET4677_AZIFS054P001C01-SOCA
M_B_CPU0_SB_CA<5>        J3               225      SCONN288_ADR50001P013C01-SCONNA
M_B_CPU0_SB_CA<5>        J4               225      SCONN288_ADR50001P003C01-SCONNA
M_B_CPU0_SB_CA<5>        U2               N43      SOCKET4677_AZIFS054P001C01-SOCA
M_B_CPU0_SB_CA<6>        J3               82       SCONN288_ADR50001P013C01-SCONNA
M_B_CPU0_SB_CA<6>        J4               82       SCONN288_ADR50001P003C01-SCONNA
M_B_CPU0_SB_CA<6>        U2               H42      SOCKET4677_AZIFS054P001C01-SOCA
M_B_CPU0_SB_CB<0>        J3               96       SCONN288_ADR50001P013C01-SCONNA
M_B_CPU0_SB_CB<0>        J4               96       SCONN288_ADR50001P003C01-SCONNA
M_B_CPU0_SB_CB<0>        U2               J35      SOCKET4677_AZIFS054P001C01-SOCA
M_B_CPU0_SB_CB<1>        J3               98       SCONN288_ADR50001P013C01-SCONNA
M_B_CPU0_SB_CB<1>        J4               98       SCONN288_ADR50001P003C01-SCONNA
M_B_CPU0_SB_CB<1>        U2               K34      SOCKET4677_AZIFS054P001C01-SOCA
M_B_CPU0_SB_CB<2>        J3               241      SCONN288_ADR50001P013C01-SCONNA
M_B_CPU0_SB_CB<2>        J4               241      SCONN288_ADR50001P003C01-SCONNA
M_B_CPU0_SB_CB<2>        U2               N35      SOCKET4677_AZIFS054P001C01-SOCA
M_B_CPU0_SB_CB<3>        J3               243      SCONN288_ADR50001P013C01-SCONNA
M_B_CPU0_SB_CB<3>        J4               243      SCONN288_ADR50001P003C01-SCONNA
M_B_CPU0_SB_CB<3>        U2               M34      SOCKET4677_AZIFS054P001C01-SOCA
M_B_CPU0_SB_CB<4>        J3               89       SCONN288_ADR50001P013C01-SCONNA
M_B_CPU0_SB_CB<4>        J4               89       SCONN288_ADR50001P003C01-SCONNA
M_B_CPU0_SB_CB<4>        U2               K38      SOCKET4677_AZIFS054P001C01-SOCA
M_B_CPU0_SB_CB<5>        J3               91       SCONN288_ADR50001P013C01-SCONNA
M_B_CPU0_SB_CB<5>        J4               91       SCONN288_ADR50001P003C01-SCONNA
M_B_CPU0_SB_CB<5>        U2               J37      SOCKET4677_AZIFS054P001C01-SOCA
M_B_CPU0_SB_CB<6>        J3               234      SCONN288_ADR50001P013C01-SCONNA
M_B_CPU0_SB_CB<6>        J4               234      SCONN288_ADR50001P003C01-SCONNA
M_B_CPU0_SB_CB<6>        U2               M38      SOCKET4677_AZIFS054P001C01-SOCA
M_B_CPU0_SB_CB<7>        J3               236      SCONN288_ADR50001P013C01-SCONNA
M_B_CPU0_SB_CB<7>        J4               236      SCONN288_ADR50001P003C01-SCONNA
M_B_CPU0_SB_CB<7>        U2               N37      SOCKET4677_AZIFS054P001C01-SOCA
M_B_CPU0_SB_CS_N<0>      J3               84       SCONN288_ADR50001P013C01-SCONNA
M_B_CPU0_SB_CS_N<0>      U2               J41      SOCKET4677_AZIFS054P001C01-SOCA
M_B_CPU0_SB_CS_N<1>      J3               229      SCONN288_ADR50001P013C01-SCONNA
M_B_CPU0_SB_CS_N<1>      U2               K40      SOCKET4677_AZIFS054P001C01-SOCA
M_B_CPU0_SB_CS_N<2>      J4               84       SCONN288_ADR50001P003C01-SCONNA
M_B_CPU0_SB_CS_N<2>      U2               N41      SOCKET4677_AZIFS054P001C01-SOCA
M_B_CPU0_SB_CS_N<3>      J4               229      SCONN288_ADR50001P003C01-SCONNA
M_B_CPU0_SB_CS_N<3>      U2               M40      SOCKET4677_AZIFS054P001C01-SOCA
M_B_CPU0_SB_DQ<0>        J3               100      SCONN288_ADR50001P013C01-SCONNA
M_B_CPU0_SB_DQ<0>        J4               100      SCONN288_ADR50001P003C01-SCONNA
M_B_CPU0_SB_DQ<0>        U2               U29      SOCKET4677_AZIFS054P001C01-SOCA
M_B_CPU0_SB_DQ<1>        J3               102      SCONN288_ADR50001P013C01-SCONNA
M_B_CPU0_SB_DQ<1>        J4               102      SCONN288_ADR50001P003C01-SCONNA
M_B_CPU0_SB_DQ<1>        U2               T28      SOCKET4677_AZIFS054P001C01-SOCA
M_B_CPU0_SB_DQ<2>        J3               245      SCONN288_ADR50001P013C01-SCONNA
M_B_CPU0_SB_DQ<2>        J4               245      SCONN288_ADR50001P003C01-SCONNA
M_B_CPU0_SB_DQ<2>        U2               W29      SOCKET4677_AZIFS054P001C01-SOCA
M_B_CPU0_SB_DQ<3>        J3               247      SCONN288_ADR50001P013C01-SCONNA
M_B_CPU0_SB_DQ<3>        J4               247      SCONN288_ADR50001P003C01-SCONNA
M_B_CPU0_SB_DQ<3>        U2               Y28      SOCKET4677_AZIFS054P001C01-SOCA
M_B_CPU0_SB_DQ<4>        J3               107      SCONN288_ADR50001P013C01-SCONNA
M_B_CPU0_SB_DQ<4>        J4               107      SCONN288_ADR50001P003C01-SCONNA
M_B_CPU0_SB_DQ<4>        U2               T26      SOCKET4677_AZIFS054P001C01-SOCA
M_B_CPU0_SB_DQ<5>        J3               109      SCONN288_ADR50001P013C01-SCONNA
M_B_CPU0_SB_DQ<5>        J4               109      SCONN288_ADR50001P003C01-SCONNA
M_B_CPU0_SB_DQ<5>        U2               U25      SOCKET4677_AZIFS054P001C01-SOCA
M_B_CPU0_SB_DQ<6>        J3               252      SCONN288_ADR50001P013C01-SCONNA
M_B_CPU0_SB_DQ<6>        J4               252      SCONN288_ADR50001P003C01-SCONNA
M_B_CPU0_SB_DQ<6>        U2               Y26      SOCKET4677_AZIFS054P001C01-SOCA
M_B_CPU0_SB_DQ<7>        J3               254      SCONN288_ADR50001P013C01-SCONNA
M_B_CPU0_SB_DQ<7>        J4               254      SCONN288_ADR50001P003C01-SCONNA
M_B_CPU0_SB_DQ<7>        U2               W25      SOCKET4677_AZIFS054P001C01-SOCA
M_B_CPU0_SB_DQ<8>        J3               111      SCONN288_ADR50001P013C01-SCONNA
M_B_CPU0_SB_DQ<8>        J4               111      SCONN288_ADR50001P003C01-SCONNA
M_B_CPU0_SB_DQ<8>        U2               K26      SOCKET4677_AZIFS054P001C01-SOCA
M_B_CPU0_SB_DQ<9>        J3               113      SCONN288_ADR50001P013C01-SCONNA
M_B_CPU0_SB_DQ<9>        J4               113      SCONN288_ADR50001P003C01-SCONNA
M_B_CPU0_SB_DQ<9>        U2               J25      SOCKET4677_AZIFS054P001C01-SOCA
M_B_CPU0_SB_DQ<10>       J3               256      SCONN288_ADR50001P013C01-SCONNA
M_B_CPU0_SB_DQ<10>       J4               256      SCONN288_ADR50001P003C01-SCONNA
M_B_CPU0_SB_DQ<10>       U2               M26      SOCKET4677_AZIFS054P001C01-SOCA
M_B_CPU0_SB_DQ<11>       J3               258      SCONN288_ADR50001P013C01-SCONNA
M_B_CPU0_SB_DQ<11>       J4               258      SCONN288_ADR50001P003C01-SCONNA
M_B_CPU0_SB_DQ<11>       U2               N25      SOCKET4677_AZIFS054P001C01-SOCA
M_B_CPU0_SB_DQ<12>       J3               118      SCONN288_ADR50001P013C01-SCONNA
M_B_CPU0_SB_DQ<12>       J4               118      SCONN288_ADR50001P003C01-SCONNA
M_B_CPU0_SB_DQ<12>       U2               J23      SOCKET4677_AZIFS054P001C01-SOCA
M_B_CPU0_SB_DQ<13>       J3               120      SCONN288_ADR50001P013C01-SCONNA
M_B_CPU0_SB_DQ<13>       J4               120      SCONN288_ADR50001P003C01-SCONNA
M_B_CPU0_SB_DQ<13>       U2               K22      SOCKET4677_AZIFS054P001C01-SOCA
M_B_CPU0_SB_DQ<14>       J3               263      SCONN288_ADR50001P013C01-SCONNA
M_B_CPU0_SB_DQ<14>       J4               263      SCONN288_ADR50001P003C01-SCONNA
M_B_CPU0_SB_DQ<14>       U2               N23      SOCKET4677_AZIFS054P001C01-SOCA
M_B_CPU0_SB_DQ<15>       J3               265      SCONN288_ADR50001P013C01-SCONNA
M_B_CPU0_SB_DQ<15>       J4               265      SCONN288_ADR50001P003C01-SCONNA
M_B_CPU0_SB_DQ<15>       U2               M22      SOCKET4677_AZIFS054P001C01-SOCA
M_B_CPU0_SB_DQ<16>       J3               122      SCONN288_ADR50001P013C01-SCONNA
M_B_CPU0_SB_DQ<16>       J4               122      SCONN288_ADR50001P003C01-SCONNA
M_B_CPU0_SB_DQ<16>       U2               K20      SOCKET4677_AZIFS054P001C01-SOCA
M_B_CPU0_SB_DQ<17>       J3               124      SCONN288_ADR50001P013C01-SCONNA
M_B_CPU0_SB_DQ<17>       J4               124      SCONN288_ADR50001P003C01-SCONNA
M_B_CPU0_SB_DQ<17>       U2               J19      SOCKET4677_AZIFS054P001C01-SOCA
M_B_CPU0_SB_DQ<18>       J3               267      SCONN288_ADR50001P013C01-SCONNA
M_B_CPU0_SB_DQ<18>       J4               267      SCONN288_ADR50001P003C01-SCONNA
M_B_CPU0_SB_DQ<18>       U2               M20      SOCKET4677_AZIFS054P001C01-SOCA
M_B_CPU0_SB_DQ<19>       J3               269      SCONN288_ADR50001P013C01-SCONNA
M_B_CPU0_SB_DQ<19>       J4               269      SCONN288_ADR50001P003C01-SCONNA
M_B_CPU0_SB_DQ<19>       U2               N19      SOCKET4677_AZIFS054P001C01-SOCA
M_B_CPU0_SB_DQ<20>       J3               129      SCONN288_ADR50001P013C01-SCONNA
M_B_CPU0_SB_DQ<20>       J4               129      SCONN288_ADR50001P003C01-SCONNA
M_B_CPU0_SB_DQ<20>       U2               J17      SOCKET4677_AZIFS054P001C01-SOCA
M_B_CPU0_SB_DQ<21>       J3               131      SCONN288_ADR50001P013C01-SCONNA
M_B_CPU0_SB_DQ<21>       J4               131      SCONN288_ADR50001P003C01-SCONNA
M_B_CPU0_SB_DQ<21>       U2               K16      SOCKET4677_AZIFS054P001C01-SOCA
M_B_CPU0_SB_DQ<22>       J3               274      SCONN288_ADR50001P013C01-SCONNA
M_B_CPU0_SB_DQ<22>       J4               274      SCONN288_ADR50001P003C01-SCONNA
M_B_CPU0_SB_DQ<22>       U2               N17      SOCKET4677_AZIFS054P001C01-SOCA
M_B_CPU0_SB_DQ<23>       J3               276      SCONN288_ADR50001P013C01-SCONNA
M_B_CPU0_SB_DQ<23>       J4               276      SCONN288_ADR50001P003C01-SCONNA
M_B_CPU0_SB_DQ<23>       U2               M16      SOCKET4677_AZIFS054P001C01-SOCA
M_B_CPU0_SB_DQ<24>       J3               133      SCONN288_ADR50001P013C01-SCONNA
M_B_CPU0_SB_DQ<24>       J4               133      SCONN288_ADR50001P003C01-SCONNA
M_B_CPU0_SB_DQ<24>       U2               C17      SOCKET4677_AZIFS054P001C01-SOCA
M_B_CPU0_SB_DQ<25>       J3               135      SCONN288_ADR50001P013C01-SCONNA
M_B_CPU0_SB_DQ<25>       J4               135      SCONN288_ADR50001P003C01-SCONNA
M_B_CPU0_SB_DQ<25>       U2               B16      SOCKET4677_AZIFS054P001C01-SOCA
M_B_CPU0_SB_DQ<26>       J3               278      SCONN288_ADR50001P013C01-SCONNA
M_B_CPU0_SB_DQ<26>       J4               278      SCONN288_ADR50001P003C01-SCONNA
M_B_CPU0_SB_DQ<26>       U2               E17      SOCKET4677_AZIFS054P001C01-SOCA
M_B_CPU0_SB_DQ<27>       J3               280      SCONN288_ADR50001P013C01-SCONNA
M_B_CPU0_SB_DQ<27>       J4               280      SCONN288_ADR50001P003C01-SCONNA
M_B_CPU0_SB_DQ<27>       U2               F16      SOCKET4677_AZIFS054P001C01-SOCA
M_B_CPU0_SB_DQ<28>       J3               140      SCONN288_ADR50001P013C01-SCONNA
M_B_CPU0_SB_DQ<28>       J4               140      SCONN288_ADR50001P003C01-SCONNA
M_B_CPU0_SB_DQ<28>       U2               C13      SOCKET4677_AZIFS054P001C01-SOCA
M_B_CPU0_SB_DQ<29>       J3               142      SCONN288_ADR50001P013C01-SCONNA
M_B_CPU0_SB_DQ<29>       J4               142      SCONN288_ADR50001P003C01-SCONNA
M_B_CPU0_SB_DQ<29>       U2               E13      SOCKET4677_AZIFS054P001C01-SOCA
M_B_CPU0_SB_DQ<30>       J3               285      SCONN288_ADR50001P013C01-SCONNA
M_B_CPU0_SB_DQ<30>       J4               285      SCONN288_ADR50001P003C01-SCONNA
M_B_CPU0_SB_DQ<30>       U2               B14      SOCKET4677_AZIFS054P001C01-SOCA
M_B_CPU0_SB_DQ<31>       J3               287      SCONN288_ADR50001P013C01-SCONNA
M_B_CPU0_SB_DQ<31>       J4               287      SCONN288_ADR50001P003C01-SCONNA
M_B_CPU0_SB_DQ<31>       U2               F14      SOCKET4677_AZIFS054P001C01-SOCA
M_B_CPU0_SB_DQS_DN<0>    J3               105      SCONN288_ADR50001P013C01-SCONNA
M_B_CPU0_SB_DQS_DN<0>    J4               105      SCONN288_ADR50001P003C01-SCONNA
M_B_CPU0_SB_DQS_DN<0>    U2               R27      SOCKET4677_AZIFS054P001C01-SOCA
M_B_CPU0_SB_DQS_DN<1>    J3               116      SCONN288_ADR50001P013C01-SCONNA
M_B_CPU0_SB_DQS_DN<1>    J4               116      SCONN288_ADR50001P003C01-SCONNA
M_B_CPU0_SB_DQS_DN<1>    U2               H24      SOCKET4677_AZIFS054P001C01-SOCA
M_B_CPU0_SB_DQS_DN<2>    J3               127      SCONN288_ADR50001P013C01-SCONNA
M_B_CPU0_SB_DQS_DN<2>    J4               127      SCONN288_ADR50001P003C01-SCONNA
M_B_CPU0_SB_DQS_DN<2>    U2               H18      SOCKET4677_AZIFS054P001C01-SOCA
M_B_CPU0_SB_DQS_DN<3>    J3               138      SCONN288_ADR50001P013C01-SCONNA
M_B_CPU0_SB_DQS_DN<3>    J4               138      SCONN288_ADR50001P003C01-SCONNA
M_B_CPU0_SB_DQS_DN<3>    U2               A15      SOCKET4677_AZIFS054P001C01-SOCA
M_B_CPU0_SB_DQS_DN<4>    J3               238      SCONN288_ADR50001P013C01-SCONNA
M_B_CPU0_SB_DQS_DN<4>    J4               238      SCONN288_ADR50001P003C01-SCONNA
M_B_CPU0_SB_DQS_DN<4>    U2               P36      SOCKET4677_AZIFS054P001C01-SOCA
M_B_CPU0_SB_DQS_DN<5>    J3               249      SCONN288_ADR50001P013C01-SCONNA
M_B_CPU0_SB_DQS_DN<5>    J4               249      SCONN288_ADR50001P003C01-SCONNA
M_B_CPU0_SB_DQS_DN<5>    U2               W27      SOCKET4677_AZIFS054P001C01-SOCA
M_B_CPU0_SB_DQS_DN<6>    J3               260      SCONN288_ADR50001P013C01-SCONNA
M_B_CPU0_SB_DQS_DN<6>    J4               260      SCONN288_ADR50001P003C01-SCONNA
M_B_CPU0_SB_DQS_DN<6>    U2               M24      SOCKET4677_AZIFS054P001C01-SOCA
M_B_CPU0_SB_DQS_DN<7>    J3               271      SCONN288_ADR50001P013C01-SCONNA
M_B_CPU0_SB_DQS_DN<7>    J4               271      SCONN288_ADR50001P003C01-SCONNA
M_B_CPU0_SB_DQS_DN<7>    U2               M18      SOCKET4677_AZIFS054P001C01-SOCA
M_B_CPU0_SB_DQS_DN<8>    J3               282      SCONN288_ADR50001P013C01-SCONNA
M_B_CPU0_SB_DQS_DN<8>    J4               282      SCONN288_ADR50001P003C01-SCONNA
M_B_CPU0_SB_DQS_DN<8>    U2               E15      SOCKET4677_AZIFS054P001C01-SOCA
M_B_CPU0_SB_DQS_DN<9>    J3               94       SCONN288_ADR50001P013C01-SCONNA
M_B_CPU0_SB_DQS_DN<9>    J4               94       SCONN288_ADR50001P003C01-SCONNA
M_B_CPU0_SB_DQS_DN<9>    U2               K36      SOCKET4677_AZIFS054P001C01-SOCA
M_B_CPU0_SB_DQS_DP<0>    J3               104      SCONN288_ADR50001P013C01-SCONNA
M_B_CPU0_SB_DQS_DP<0>    J4               104      SCONN288_ADR50001P003C01-SCONNA
M_B_CPU0_SB_DQS_DP<0>    U2               U27      SOCKET4677_AZIFS054P001C01-SOCA
M_B_CPU0_SB_DQS_DP<1>    J3               115      SCONN288_ADR50001P013C01-SCONNA
M_B_CPU0_SB_DQS_DP<1>    J4               115      SCONN288_ADR50001P003C01-SCONNA
M_B_CPU0_SB_DQS_DP<1>    U2               K24      SOCKET4677_AZIFS054P001C01-SOCA
M_B_CPU0_SB_DQS_DP<2>    J3               126      SCONN288_ADR50001P013C01-SCONNA
M_B_CPU0_SB_DQS_DP<2>    J4               126      SCONN288_ADR50001P003C01-SCONNA
M_B_CPU0_SB_DQS_DP<2>    U2               K18      SOCKET4677_AZIFS054P001C01-SOCA
M_B_CPU0_SB_DQS_DP<3>    J3               137      SCONN288_ADR50001P013C01-SCONNA
M_B_CPU0_SB_DQS_DP<3>    J4               137      SCONN288_ADR50001P003C01-SCONNA
M_B_CPU0_SB_DQS_DP<3>    U2               C15      SOCKET4677_AZIFS054P001C01-SOCA
M_B_CPU0_SB_DQS_DP<4>    J3               239      SCONN288_ADR50001P013C01-SCONNA
M_B_CPU0_SB_DQS_DP<4>    J4               239      SCONN288_ADR50001P003C01-SCONNA
M_B_CPU0_SB_DQS_DP<4>    U2               M36      SOCKET4677_AZIFS054P001C01-SOCA
M_B_CPU0_SB_DQS_DP<5>    J3               250      SCONN288_ADR50001P013C01-SCONNA
M_B_CPU0_SB_DQS_DP<5>    J4               250      SCONN288_ADR50001P003C01-SCONNA
M_B_CPU0_SB_DQS_DP<5>    U2               AA27     SOCKET4677_AZIFS054P001C01-SOCA
M_B_CPU0_SB_DQS_DP<6>    J3               261      SCONN288_ADR50001P013C01-SCONNA
M_B_CPU0_SB_DQS_DP<6>    J4               261      SCONN288_ADR50001P003C01-SCONNA
M_B_CPU0_SB_DQS_DP<6>    U2               P24      SOCKET4677_AZIFS054P001C01-SOCA
M_B_CPU0_SB_DQS_DP<7>    J3               272      SCONN288_ADR50001P013C01-SCONNA
M_B_CPU0_SB_DQS_DP<7>    J4               272      SCONN288_ADR50001P003C01-SCONNA
M_B_CPU0_SB_DQS_DP<7>    U2               P18      SOCKET4677_AZIFS054P001C01-SOCA
M_B_CPU0_SB_DQS_DP<8>    J3               283      SCONN288_ADR50001P013C01-SCONNA
M_B_CPU0_SB_DQS_DP<8>    J4               283      SCONN288_ADR50001P003C01-SCONNA
M_B_CPU0_SB_DQS_DP<8>    U2               G15      SOCKET4677_AZIFS054P001C01-SOCA
M_B_CPU0_SB_DQS_DP<9>    J3               93       SCONN288_ADR50001P013C01-SCONNA
M_B_CPU0_SB_DQS_DP<9>    J4               93       SCONN288_ADR50001P003C01-SCONNA
M_B_CPU0_SB_DQS_DP<9>    U2               H36      SOCKET4677_AZIFS054P001C01-SOCA
M_B_CPU0_SB_PAR          J3               227      SCONN288_ADR50001P013C01-SCONNA
M_B_CPU0_SB_PAR          J4               227      SCONN288_ADR50001P003C01-SCONNA
M_B_CPU0_SB_PAR          U2               P42      SOCKET4677_AZIFS054P001C01-SOCA
M_B_CPU0_SB_RSP<0>       J3               87       SCONN288_ADR50001P013C01-SCONNA
M_B_CPU0_SB_RSP<0>       U2               AN48     SOCKET4677_AZIFS054P001C01-SOCA
M_B_CPU0_SB_RSP<1>       J4               87       SCONN288_ADR50001P003C01-SCONNA
M_B_CPU0_SB_RSP<1>       U2               AP47     SOCKET4677_AZIFS054P001C01-SOCA
M_B_CPU1_ALERT_N         J19              62       SCONN288_ADR50001P013C01-SCONNA
M_B_CPU1_ALERT_N         J20              62       SCONN288_ADR50001P003C01-SCONNA
M_B_CPU1_ALERT_N         U1               AV49     SOCKET4677_AZIFS054P001C01-SOCA
M_B_CPU1_CLK_DN<0>       J19              218      SCONN288_ADR50001P013C01-SCONNA
M_B_CPU1_CLK_DN<0>       U1               R45      SOCKET4677_AZIFS054P001C01-SOCA
M_B_CPU1_CLK_DN<1>       J20              218      SCONN288_ADR50001P003C01-SCONNA
M_B_CPU1_CLK_DN<1>       U1               W45      SOCKET4677_AZIFS054P001C01-SOCA
M_B_CPU1_CLK_DP<0>       J19              217      SCONN288_ADR50001P013C01-SCONNA
M_B_CPU1_CLK_DP<0>       U1               U45      SOCKET4677_AZIFS054P001C01-SOCA
M_B_CPU1_CLK_DP<1>       J20              217      SCONN288_ADR50001P003C01-SCONNA
M_B_CPU1_CLK_DP<1>       U1               AA45     SOCKET4677_AZIFS054P001C01-SOCA
M_B_CPU1_SA_CA<0>        J19              66       SCONN288_ADR50001P013C01-SCONNA
M_B_CPU1_SA_CA<0>        J20              66       SCONN288_ADR50001P003C01-SCONNA
M_B_CPU1_SA_CA<0>        U1               H49      SOCKET4677_AZIFS054P001C01-SOCA
M_B_CPU1_SA_CA<1>        J19              211      SCONN288_ADR50001P013C01-SCONNA
M_B_CPU1_SA_CA<1>        J20              211      SCONN288_ADR50001P003C01-SCONNA
M_B_CPU1_SA_CA<1>        U1               P49      SOCKET4677_AZIFS054P001C01-SOCA
M_B_CPU1_SA_CA<2>        J19              68       SCONN288_ADR50001P013C01-SCONNA
M_B_CPU1_SA_CA<2>        J20              68       SCONN288_ADR50001P003C01-SCONNA
M_B_CPU1_SA_CA<2>        U1               J48      SOCKET4677_AZIFS054P001C01-SOCA
M_B_CPU1_SA_CA<3>        J19              213      SCONN288_ADR50001P013C01-SCONNA
M_B_CPU1_SA_CA<3>        J20              213      SCONN288_ADR50001P003C01-SCONNA
M_B_CPU1_SA_CA<3>        U1               N48      SOCKET4677_AZIFS054P001C01-SOCA
M_B_CPU1_SA_CA<4>        J19              70       SCONN288_ADR50001P013C01-SCONNA
M_B_CPU1_SA_CA<4>        J20              70       SCONN288_ADR50001P003C01-SCONNA
M_B_CPU1_SA_CA<4>        U1               K47      SOCKET4677_AZIFS054P001C01-SOCA
M_B_CPU1_SA_CA<5>        J19              215      SCONN288_ADR50001P013C01-SCONNA
M_B_CPU1_SA_CA<5>        J20              215      SCONN288_ADR50001P003C01-SCONNA
M_B_CPU1_SA_CA<5>        U1               M47      SOCKET4677_AZIFS054P001C01-SOCA
M_B_CPU1_SA_CA<6>        J19              72       SCONN288_ADR50001P013C01-SCONNA
M_B_CPU1_SA_CA<6>        J20              72       SCONN288_ADR50001P003C01-SCONNA
M_B_CPU1_SA_CA<6>        U1               Y44      SOCKET4677_AZIFS054P001C01-SOCA
M_B_CPU1_SA_CB<0>        J19              51       SCONN288_ADR50001P013C01-SCONNA
M_B_CPU1_SA_CB<0>        J20              51       SCONN288_ADR50001P003C01-SCONNA
M_B_CPU1_SA_CB<0>        U1               K57      SOCKET4677_AZIFS054P001C01-SOCA
M_B_CPU1_SA_CB<1>        J19              53       SCONN288_ADR50001P013C01-SCONNA
M_B_CPU1_SA_CB<1>        J20              53       SCONN288_ADR50001P003C01-SCONNA
M_B_CPU1_SA_CB<1>        U1               J56      SOCKET4677_AZIFS054P001C01-SOCA
M_B_CPU1_SA_CB<2>        J19              196      SCONN288_ADR50001P013C01-SCONNA
M_B_CPU1_SA_CB<2>        J20              196      SCONN288_ADR50001P003C01-SCONNA
M_B_CPU1_SA_CB<2>        U1               M57      SOCKET4677_AZIFS054P001C01-SOCA
M_B_CPU1_SA_CB<3>        J19              198      SCONN288_ADR50001P013C01-SCONNA
M_B_CPU1_SA_CB<3>        J20              198      SCONN288_ADR50001P003C01-SCONNA
M_B_CPU1_SA_CB<3>        U1               N56      SOCKET4677_AZIFS054P001C01-SOCA
M_B_CPU1_SA_CB<4>        J19              58       SCONN288_ADR50001P013C01-SCONNA
M_B_CPU1_SA_CB<4>        J20              58       SCONN288_ADR50001P003C01-SCONNA
M_B_CPU1_SA_CB<4>        U1               J54      SOCKET4677_AZIFS054P001C01-SOCA
M_B_CPU1_SA_CB<5>        J19              60       SCONN288_ADR50001P013C01-SCONNA
M_B_CPU1_SA_CB<5>        J20              60       SCONN288_ADR50001P003C01-SCONNA
M_B_CPU1_SA_CB<5>        U1               K53      SOCKET4677_AZIFS054P001C01-SOCA
M_B_CPU1_SA_CB<6>        J19              203      SCONN288_ADR50001P013C01-SCONNA
M_B_CPU1_SA_CB<6>        J20              203      SCONN288_ADR50001P003C01-SCONNA
M_B_CPU1_SA_CB<6>        U1               N54      SOCKET4677_AZIFS054P001C01-SOCA
M_B_CPU1_SA_CB<7>        J19              205      SCONN288_ADR50001P013C01-SCONNA
M_B_CPU1_SA_CB<7>        J20              205      SCONN288_ADR50001P003C01-SCONNA
M_B_CPU1_SA_CB<7>        U1               M53      SOCKET4677_AZIFS054P001C01-SOCA
M_B_CPU1_SA_CS_N<0>      J19              64       SCONN288_ADR50001P013C01-SCONNA
M_B_CPU1_SA_CS_N<0>      U1               K51      SOCKET4677_AZIFS054P001C01-SOCA
M_B_CPU1_SA_CS_N<1>      J19              209      SCONN288_ADR50001P013C01-SCONNA
M_B_CPU1_SA_CS_N<1>      U1               J50      SOCKET4677_AZIFS054P001C01-SOCA
M_B_CPU1_SA_CS_N<2>      J20              64       SCONN288_ADR50001P003C01-SCONNA
M_B_CPU1_SA_CS_N<2>      U1               M51      SOCKET4677_AZIFS054P001C01-SOCA
M_B_CPU1_SA_CS_N<3>      J20              209      SCONN288_ADR50001P003C01-SCONNA
M_B_CPU1_SA_CS_N<3>      U1               N50      SOCKET4677_AZIFS054P001C01-SOCA
M_B_CPU1_SA_DQ<0>        J19              7        SCONN288_ADR50001P013C01-SCONNA
M_B_CPU1_SA_DQ<0>        J20              7        SCONN288_ADR50001P003C01-SCONNA
M_B_CPU1_SA_DQ<0>        U1               K75      SOCKET4677_AZIFS054P001C01-SOCA
M_B_CPU1_SA_DQ<1>        J19              9        SCONN288_ADR50001P013C01-SCONNA
M_B_CPU1_SA_DQ<1>        J20              9        SCONN288_ADR50001P003C01-SCONNA
M_B_CPU1_SA_DQ<1>        U1               J74      SOCKET4677_AZIFS054P001C01-SOCA
M_B_CPU1_SA_DQ<2>        J19              152      SCONN288_ADR50001P013C01-SCONNA
M_B_CPU1_SA_DQ<2>        J20              152      SCONN288_ADR50001P003C01-SCONNA
M_B_CPU1_SA_DQ<2>        U1               M75      SOCKET4677_AZIFS054P001C01-SOCA
M_B_CPU1_SA_DQ<3>        J19              154      SCONN288_ADR50001P013C01-SCONNA
M_B_CPU1_SA_DQ<3>        J20              154      SCONN288_ADR50001P003C01-SCONNA
M_B_CPU1_SA_DQ<3>        U1               N74      SOCKET4677_AZIFS054P001C01-SOCA
M_B_CPU1_SA_DQ<4>        J19              14       SCONN288_ADR50001P013C01-SCONNA
M_B_CPU1_SA_DQ<4>        J20              14       SCONN288_ADR50001P003C01-SCONNA
M_B_CPU1_SA_DQ<4>        U1               J72      SOCKET4677_AZIFS054P001C01-SOCA
M_B_CPU1_SA_DQ<5>        J19              16       SCONN288_ADR50001P013C01-SCONNA
M_B_CPU1_SA_DQ<5>        J20              16       SCONN288_ADR50001P003C01-SCONNA
M_B_CPU1_SA_DQ<5>        U1               K71      SOCKET4677_AZIFS054P001C01-SOCA
M_B_CPU1_SA_DQ<6>        J19              159      SCONN288_ADR50001P013C01-SCONNA
M_B_CPU1_SA_DQ<6>        J20              159      SCONN288_ADR50001P003C01-SCONNA
M_B_CPU1_SA_DQ<6>        U1               N72      SOCKET4677_AZIFS054P001C01-SOCA
M_B_CPU1_SA_DQ<7>        J19              161      SCONN288_ADR50001P013C01-SCONNA
M_B_CPU1_SA_DQ<7>        J20              161      SCONN288_ADR50001P003C01-SCONNA
M_B_CPU1_SA_DQ<7>        U1               M71      SOCKET4677_AZIFS054P001C01-SOCA
M_B_CPU1_SA_DQ<8>        J19              18       SCONN288_ADR50001P013C01-SCONNA
M_B_CPU1_SA_DQ<8>        J20              18       SCONN288_ADR50001P003C01-SCONNA
M_B_CPU1_SA_DQ<8>        U1               U72      SOCKET4677_AZIFS054P001C01-SOCA
M_B_CPU1_SA_DQ<9>        J19              20       SCONN288_ADR50001P013C01-SCONNA
M_B_CPU1_SA_DQ<9>        J20              20       SCONN288_ADR50001P003C01-SCONNA
M_B_CPU1_SA_DQ<9>        U1               T71      SOCKET4677_AZIFS054P001C01-SOCA
M_B_CPU1_SA_DQ<10>       J19              163      SCONN288_ADR50001P013C01-SCONNA
M_B_CPU1_SA_DQ<10>       J20              163      SCONN288_ADR50001P003C01-SCONNA
M_B_CPU1_SA_DQ<10>       U1               W72      SOCKET4677_AZIFS054P001C01-SOCA
M_B_CPU1_SA_DQ<11>       J19              165      SCONN288_ADR50001P013C01-SCONNA
M_B_CPU1_SA_DQ<11>       J20              165      SCONN288_ADR50001P003C01-SCONNA
M_B_CPU1_SA_DQ<11>       U1               Y71      SOCKET4677_AZIFS054P001C01-SOCA
M_B_CPU1_SA_DQ<12>       J19              25       SCONN288_ADR50001P013C01-SCONNA
M_B_CPU1_SA_DQ<12>       J20              25       SCONN288_ADR50001P003C01-SCONNA
M_B_CPU1_SA_DQ<12>       U1               T69      SOCKET4677_AZIFS054P001C01-SOCA
M_B_CPU1_SA_DQ<13>       J19              27       SCONN288_ADR50001P013C01-SCONNA
M_B_CPU1_SA_DQ<13>       J20              27       SCONN288_ADR50001P003C01-SCONNA
M_B_CPU1_SA_DQ<13>       U1               U68      SOCKET4677_AZIFS054P001C01-SOCA
M_B_CPU1_SA_DQ<14>       J19              170      SCONN288_ADR50001P013C01-SCONNA
M_B_CPU1_SA_DQ<14>       J20              170      SCONN288_ADR50001P003C01-SCONNA
M_B_CPU1_SA_DQ<14>       U1               Y69      SOCKET4677_AZIFS054P001C01-SOCA
M_B_CPU1_SA_DQ<15>       J19              172      SCONN288_ADR50001P013C01-SCONNA
M_B_CPU1_SA_DQ<15>       J20              172      SCONN288_ADR50001P003C01-SCONNA
M_B_CPU1_SA_DQ<15>       U1               W68      SOCKET4677_AZIFS054P001C01-SOCA
M_B_CPU1_SA_DQ<16>       J19              29       SCONN288_ADR50001P013C01-SCONNA
M_B_CPU1_SA_DQ<16>       J20              29       SCONN288_ADR50001P003C01-SCONNA
M_B_CPU1_SA_DQ<16>       U1               K63      SOCKET4677_AZIFS054P001C01-SOCA
M_B_CPU1_SA_DQ<17>       J19              31       SCONN288_ADR50001P013C01-SCONNA
M_B_CPU1_SA_DQ<17>       J20              31       SCONN288_ADR50001P003C01-SCONNA
M_B_CPU1_SA_DQ<17>       U1               J62      SOCKET4677_AZIFS054P001C01-SOCA
M_B_CPU1_SA_DQ<18>       J19              174      SCONN288_ADR50001P013C01-SCONNA
M_B_CPU1_SA_DQ<18>       J20              174      SCONN288_ADR50001P003C01-SCONNA
M_B_CPU1_SA_DQ<18>       U1               M63      SOCKET4677_AZIFS054P001C01-SOCA
M_B_CPU1_SA_DQ<19>       J19              176      SCONN288_ADR50001P013C01-SCONNA
M_B_CPU1_SA_DQ<19>       J20              176      SCONN288_ADR50001P003C01-SCONNA
M_B_CPU1_SA_DQ<19>       U1               N62      SOCKET4677_AZIFS054P001C01-SOCA
M_B_CPU1_SA_DQ<20>       J19              36       SCONN288_ADR50001P013C01-SCONNA
M_B_CPU1_SA_DQ<20>       J20              36       SCONN288_ADR50001P003C01-SCONNA
M_B_CPU1_SA_DQ<20>       U1               J60      SOCKET4677_AZIFS054P001C01-SOCA
M_B_CPU1_SA_DQ<21>       J19              38       SCONN288_ADR50001P013C01-SCONNA
M_B_CPU1_SA_DQ<21>       J20              38       SCONN288_ADR50001P003C01-SCONNA
M_B_CPU1_SA_DQ<21>       U1               K59      SOCKET4677_AZIFS054P001C01-SOCA
M_B_CPU1_SA_DQ<22>       J19              181      SCONN288_ADR50001P013C01-SCONNA
M_B_CPU1_SA_DQ<22>       J20              181      SCONN288_ADR50001P003C01-SCONNA
M_B_CPU1_SA_DQ<22>       U1               N60      SOCKET4677_AZIFS054P001C01-SOCA
M_B_CPU1_SA_DQ<23>       J19              183      SCONN288_ADR50001P013C01-SCONNA
M_B_CPU1_SA_DQ<23>       J20              183      SCONN288_ADR50001P003C01-SCONNA
M_B_CPU1_SA_DQ<23>       U1               M59      SOCKET4677_AZIFS054P001C01-SOCA
M_B_CPU1_SA_DQ<24>       J19              40       SCONN288_ADR50001P013C01-SCONNA
M_B_CPU1_SA_DQ<24>       J20              40       SCONN288_ADR50001P003C01-SCONNA
M_B_CPU1_SA_DQ<24>       U1               U60      SOCKET4677_AZIFS054P001C01-SOCA
M_B_CPU1_SA_DQ<25>       J19              42       SCONN288_ADR50001P013C01-SCONNA
M_B_CPU1_SA_DQ<25>       J20              42       SCONN288_ADR50001P003C01-SCONNA
M_B_CPU1_SA_DQ<25>       U1               T59      SOCKET4677_AZIFS054P001C01-SOCA
M_B_CPU1_SA_DQ<26>       J19              185      SCONN288_ADR50001P013C01-SCONNA
M_B_CPU1_SA_DQ<26>       J20              185      SCONN288_ADR50001P003C01-SCONNA
M_B_CPU1_SA_DQ<26>       U1               W60      SOCKET4677_AZIFS054P001C01-SOCA
M_B_CPU1_SA_DQ<27>       J19              187      SCONN288_ADR50001P013C01-SCONNA
M_B_CPU1_SA_DQ<27>       J20              187      SCONN288_ADR50001P003C01-SCONNA
M_B_CPU1_SA_DQ<27>       U1               Y59      SOCKET4677_AZIFS054P001C01-SOCA
M_B_CPU1_SA_DQ<28>       J19              47       SCONN288_ADR50001P013C01-SCONNA
M_B_CPU1_SA_DQ<28>       J20              47       SCONN288_ADR50001P003C01-SCONNA
M_B_CPU1_SA_DQ<28>       U1               T57      SOCKET4677_AZIFS054P001C01-SOCA
M_B_CPU1_SA_DQ<29>       J19              49       SCONN288_ADR50001P013C01-SCONNA
M_B_CPU1_SA_DQ<29>       J20              49       SCONN288_ADR50001P003C01-SCONNA
M_B_CPU1_SA_DQ<29>       U1               U56      SOCKET4677_AZIFS054P001C01-SOCA
M_B_CPU1_SA_DQ<30>       J19              192      SCONN288_ADR50001P013C01-SCONNA
M_B_CPU1_SA_DQ<30>       J20              192      SCONN288_ADR50001P003C01-SCONNA
M_B_CPU1_SA_DQ<30>       U1               Y57      SOCKET4677_AZIFS054P001C01-SOCA
M_B_CPU1_SA_DQ<31>       J19              194      SCONN288_ADR50001P013C01-SCONNA
M_B_CPU1_SA_DQ<31>       J20              194      SCONN288_ADR50001P003C01-SCONNA
M_B_CPU1_SA_DQ<31>       U1               W56      SOCKET4677_AZIFS054P001C01-SOCA
M_B_CPU1_SA_DQS_DN<0>    J19              12       SCONN288_ADR50001P013C01-SCONNA
M_B_CPU1_SA_DQS_DN<0>    J20              12       SCONN288_ADR50001P003C01-SCONNA
M_B_CPU1_SA_DQS_DN<0>    U1               H73      SOCKET4677_AZIFS054P001C01-SOCA
M_B_CPU1_SA_DQS_DN<1>    J19              23       SCONN288_ADR50001P013C01-SCONNA
M_B_CPU1_SA_DQS_DN<1>    J20              23       SCONN288_ADR50001P003C01-SCONNA
M_B_CPU1_SA_DQS_DN<1>    U1               R70      SOCKET4677_AZIFS054P001C01-SOCA
M_B_CPU1_SA_DQS_DN<2>    J19              34       SCONN288_ADR50001P013C01-SCONNA
M_B_CPU1_SA_DQS_DN<2>    J20              34       SCONN288_ADR50001P003C01-SCONNA
M_B_CPU1_SA_DQS_DN<2>    U1               H61      SOCKET4677_AZIFS054P001C01-SOCA
M_B_CPU1_SA_DQS_DN<3>    J19              45       SCONN288_ADR50001P013C01-SCONNA
M_B_CPU1_SA_DQS_DN<3>    J20              45       SCONN288_ADR50001P003C01-SCONNA
M_B_CPU1_SA_DQS_DN<3>    U1               R58      SOCKET4677_AZIFS054P001C01-SOCA
M_B_CPU1_SA_DQS_DN<4>    J19              56       SCONN288_ADR50001P013C01-SCONNA
M_B_CPU1_SA_DQS_DN<4>    J20              56       SCONN288_ADR50001P003C01-SCONNA
M_B_CPU1_SA_DQS_DN<4>    U1               H55      SOCKET4677_AZIFS054P001C01-SOCA
M_B_CPU1_SA_DQS_DN<5>    J19              156      SCONN288_ADR50001P013C01-SCONNA
M_B_CPU1_SA_DQS_DN<5>    J20              156      SCONN288_ADR50001P003C01-SCONNA
M_B_CPU1_SA_DQS_DN<5>    U1               M73      SOCKET4677_AZIFS054P001C01-SOCA
M_B_CPU1_SA_DQS_DN<6>    J19              167      SCONN288_ADR50001P013C01-SCONNA
M_B_CPU1_SA_DQS_DN<6>    J20              167      SCONN288_ADR50001P003C01-SCONNA
M_B_CPU1_SA_DQS_DN<6>    U1               AA70     SOCKET4677_AZIFS054P001C01-SOCA
M_B_CPU1_SA_DQS_DN<7>    J19              178      SCONN288_ADR50001P013C01-SCONNA
M_B_CPU1_SA_DQS_DN<7>    J20              178      SCONN288_ADR50001P003C01-SCONNA
M_B_CPU1_SA_DQS_DN<7>    U1               M61      SOCKET4677_AZIFS054P001C01-SOCA
M_B_CPU1_SA_DQS_DN<8>    J19              189      SCONN288_ADR50001P013C01-SCONNA
M_B_CPU1_SA_DQS_DN<8>    J20              189      SCONN288_ADR50001P003C01-SCONNA
M_B_CPU1_SA_DQS_DN<8>    U1               AA58     SOCKET4677_AZIFS054P001C01-SOCA
M_B_CPU1_SA_DQS_DN<9>    J19              200      SCONN288_ADR50001P013C01-SCONNA
M_B_CPU1_SA_DQS_DN<9>    J20              200      SCONN288_ADR50001P003C01-SCONNA
M_B_CPU1_SA_DQS_DN<9>    U1               M55      SOCKET4677_AZIFS054P001C01-SOCA
M_B_CPU1_SA_DQS_DP<0>    J19              11       SCONN288_ADR50001P013C01-SCONNA
M_B_CPU1_SA_DQS_DP<0>    J20              11       SCONN288_ADR50001P003C01-SCONNA
M_B_CPU1_SA_DQS_DP<0>    U1               K73      SOCKET4677_AZIFS054P001C01-SOCA
M_B_CPU1_SA_DQS_DP<1>    J19              22       SCONN288_ADR50001P013C01-SCONNA
M_B_CPU1_SA_DQS_DP<1>    J20              22       SCONN288_ADR50001P003C01-SCONNA
M_B_CPU1_SA_DQS_DP<1>    U1               U70      SOCKET4677_AZIFS054P001C01-SOCA
M_B_CPU1_SA_DQS_DP<2>    J19              33       SCONN288_ADR50001P013C01-SCONNA
M_B_CPU1_SA_DQS_DP<2>    J20              33       SCONN288_ADR50001P003C01-SCONNA
M_B_CPU1_SA_DQS_DP<2>    U1               K61      SOCKET4677_AZIFS054P001C01-SOCA
M_B_CPU1_SA_DQS_DP<3>    J19              44       SCONN288_ADR50001P013C01-SCONNA
M_B_CPU1_SA_DQS_DP<3>    J20              44       SCONN288_ADR50001P003C01-SCONNA
M_B_CPU1_SA_DQS_DP<3>    U1               U58      SOCKET4677_AZIFS054P001C01-SOCA
M_B_CPU1_SA_DQS_DP<4>    J19              55       SCONN288_ADR50001P013C01-SCONNA
M_B_CPU1_SA_DQS_DP<4>    J20              55       SCONN288_ADR50001P003C01-SCONNA
M_B_CPU1_SA_DQS_DP<4>    U1               K55      SOCKET4677_AZIFS054P001C01-SOCA
M_B_CPU1_SA_DQS_DP<5>    J19              157      SCONN288_ADR50001P013C01-SCONNA
M_B_CPU1_SA_DQS_DP<5>    J20              157      SCONN288_ADR50001P003C01-SCONNA
M_B_CPU1_SA_DQS_DP<5>    U1               P73      SOCKET4677_AZIFS054P001C01-SOCA
M_B_CPU1_SA_DQS_DP<6>    J19              168      SCONN288_ADR50001P013C01-SCONNA
M_B_CPU1_SA_DQS_DP<6>    J20              168      SCONN288_ADR50001P003C01-SCONNA
M_B_CPU1_SA_DQS_DP<6>    U1               W70      SOCKET4677_AZIFS054P001C01-SOCA
M_B_CPU1_SA_DQS_DP<7>    J19              179      SCONN288_ADR50001P013C01-SCONNA
M_B_CPU1_SA_DQS_DP<7>    J20              179      SCONN288_ADR50001P003C01-SCONNA
M_B_CPU1_SA_DQS_DP<7>    U1               P61      SOCKET4677_AZIFS054P001C01-SOCA
M_B_CPU1_SA_DQS_DP<8>    J19              190      SCONN288_ADR50001P013C01-SCONNA
M_B_CPU1_SA_DQS_DP<8>    J20              190      SCONN288_ADR50001P003C01-SCONNA
M_B_CPU1_SA_DQS_DP<8>    U1               W58      SOCKET4677_AZIFS054P001C01-SOCA
M_B_CPU1_SA_DQS_DP<9>    J19              201      SCONN288_ADR50001P013C01-SCONNA
M_B_CPU1_SA_DQS_DP<9>    J20              201      SCONN288_ADR50001P003C01-SCONNA
M_B_CPU1_SA_DQS_DP<9>    U1               P55      SOCKET4677_AZIFS054P001C01-SOCA
M_B_CPU1_SA_PAR          J19              74       SCONN288_ADR50001P013C01-SCONNA
M_B_CPU1_SA_PAR          J20              74       SCONN288_ADR50001P003C01-SCONNA
M_B_CPU1_SA_PAR          U1               W43      SOCKET4677_AZIFS054P001C01-SOCA
M_B_CPU1_SA_RSP<0>       J19              86       SCONN288_ADR50001P013C01-SCONNA
M_B_CPU1_SA_RSP<0>       U1               AL48     SOCKET4677_AZIFS054P001C01-SOCA
M_B_CPU1_SA_RSP<1>       J20              86       SCONN288_ADR50001P003C01-SCONNA
M_B_CPU1_SA_RSP<1>       U1               AK47     SOCKET4677_AZIFS054P001C01-SOCA
M_B_CPU1_SB_CA<0>        J19              76       SCONN288_ADR50001P013C01-SCONNA
M_B_CPU1_SB_CA<0>        J20              76       SCONN288_ADR50001P003C01-SCONNA
M_B_CPU1_SB_CA<0>        U1               T44      SOCKET4677_AZIFS054P001C01-SOCA
M_B_CPU1_SB_CA<1>        J19              221      SCONN288_ADR50001P013C01-SCONNA
M_B_CPU1_SB_CA<1>        J20              221      SCONN288_ADR50001P003C01-SCONNA
M_B_CPU1_SB_CA<1>        U1               U43      SOCKET4677_AZIFS054P001C01-SOCA
M_B_CPU1_SB_CA<2>        J19              78       SCONN288_ADR50001P013C01-SCONNA
M_B_CPU1_SB_CA<2>        J20              78       SCONN288_ADR50001P003C01-SCONNA
M_B_CPU1_SB_CA<2>        U1               K44      SOCKET4677_AZIFS054P001C01-SOCA
M_B_CPU1_SB_CA<3>        J19              223      SCONN288_ADR50001P013C01-SCONNA
M_B_CPU1_SB_CA<3>        J20              223      SCONN288_ADR50001P003C01-SCONNA
M_B_CPU1_SB_CA<3>        U1               M44      SOCKET4677_AZIFS054P001C01-SOCA
M_B_CPU1_SB_CA<4>        J19              80       SCONN288_ADR50001P013C01-SCONNA
M_B_CPU1_SB_CA<4>        J20              80       SCONN288_ADR50001P003C01-SCONNA
M_B_CPU1_SB_CA<4>        U1               J43      SOCKET4677_AZIFS054P001C01-SOCA
M_B_CPU1_SB_CA<5>        J19              225      SCONN288_ADR50001P013C01-SCONNA
M_B_CPU1_SB_CA<5>        J20              225      SCONN288_ADR50001P003C01-SCONNA
M_B_CPU1_SB_CA<5>        U1               N43      SOCKET4677_AZIFS054P001C01-SOCA
M_B_CPU1_SB_CA<6>        J19              82       SCONN288_ADR50001P013C01-SCONNA
M_B_CPU1_SB_CA<6>        J20              82       SCONN288_ADR50001P003C01-SCONNA
M_B_CPU1_SB_CA<6>        U1               H42      SOCKET4677_AZIFS054P001C01-SOCA
M_B_CPU1_SB_CB<0>        J19              96       SCONN288_ADR50001P013C01-SCONNA
M_B_CPU1_SB_CB<0>        J20              96       SCONN288_ADR50001P003C01-SCONNA
M_B_CPU1_SB_CB<0>        U1               J35      SOCKET4677_AZIFS054P001C01-SOCA
M_B_CPU1_SB_CB<1>        J19              98       SCONN288_ADR50001P013C01-SCONNA
M_B_CPU1_SB_CB<1>        J20              98       SCONN288_ADR50001P003C01-SCONNA
M_B_CPU1_SB_CB<1>        U1               K34      SOCKET4677_AZIFS054P001C01-SOCA
M_B_CPU1_SB_CB<2>        J19              241      SCONN288_ADR50001P013C01-SCONNA
M_B_CPU1_SB_CB<2>        J20              241      SCONN288_ADR50001P003C01-SCONNA
M_B_CPU1_SB_CB<2>        U1               N35      SOCKET4677_AZIFS054P001C01-SOCA
M_B_CPU1_SB_CB<3>        J19              243      SCONN288_ADR50001P013C01-SCONNA
M_B_CPU1_SB_CB<3>        J20              243      SCONN288_ADR50001P003C01-SCONNA
M_B_CPU1_SB_CB<3>        U1               M34      SOCKET4677_AZIFS054P001C01-SOCA
M_B_CPU1_SB_CB<4>        J19              89       SCONN288_ADR50001P013C01-SCONNA
M_B_CPU1_SB_CB<4>        J20              89       SCONN288_ADR50001P003C01-SCONNA
M_B_CPU1_SB_CB<4>        U1               K38      SOCKET4677_AZIFS054P001C01-SOCA
M_B_CPU1_SB_CB<5>        J19              91       SCONN288_ADR50001P013C01-SCONNA
M_B_CPU1_SB_CB<5>        J20              91       SCONN288_ADR50001P003C01-SCONNA
M_B_CPU1_SB_CB<5>        U1               J37      SOCKET4677_AZIFS054P001C01-SOCA
M_B_CPU1_SB_CB<6>        J19              234      SCONN288_ADR50001P013C01-SCONNA
M_B_CPU1_SB_CB<6>        J20              234      SCONN288_ADR50001P003C01-SCONNA
M_B_CPU1_SB_CB<6>        U1               M38      SOCKET4677_AZIFS054P001C01-SOCA
M_B_CPU1_SB_CB<7>        J19              236      SCONN288_ADR50001P013C01-SCONNA
M_B_CPU1_SB_CB<7>        J20              236      SCONN288_ADR50001P003C01-SCONNA
M_B_CPU1_SB_CB<7>        U1               N37      SOCKET4677_AZIFS054P001C01-SOCA
M_B_CPU1_SB_CS_N<0>      J19              84       SCONN288_ADR50001P013C01-SCONNA
M_B_CPU1_SB_CS_N<0>      U1               J41      SOCKET4677_AZIFS054P001C01-SOCA
M_B_CPU1_SB_CS_N<1>      J19              229      SCONN288_ADR50001P013C01-SCONNA
M_B_CPU1_SB_CS_N<1>      U1               K40      SOCKET4677_AZIFS054P001C01-SOCA
M_B_CPU1_SB_CS_N<2>      J20              84       SCONN288_ADR50001P003C01-SCONNA
M_B_CPU1_SB_CS_N<2>      U1               N41      SOCKET4677_AZIFS054P001C01-SOCA
M_B_CPU1_SB_CS_N<3>      J20              229      SCONN288_ADR50001P003C01-SCONNA
M_B_CPU1_SB_CS_N<3>      U1               M40      SOCKET4677_AZIFS054P001C01-SOCA
M_B_CPU1_SB_DQ<0>        J19              100      SCONN288_ADR50001P013C01-SCONNA
M_B_CPU1_SB_DQ<0>        J20              100      SCONN288_ADR50001P003C01-SCONNA
M_B_CPU1_SB_DQ<0>        U1               U29      SOCKET4677_AZIFS054P001C01-SOCA
M_B_CPU1_SB_DQ<1>        J19              102      SCONN288_ADR50001P013C01-SCONNA
M_B_CPU1_SB_DQ<1>        J20              102      SCONN288_ADR50001P003C01-SCONNA
M_B_CPU1_SB_DQ<1>        U1               T28      SOCKET4677_AZIFS054P001C01-SOCA
M_B_CPU1_SB_DQ<2>        J19              245      SCONN288_ADR50001P013C01-SCONNA
M_B_CPU1_SB_DQ<2>        J20              245      SCONN288_ADR50001P003C01-SCONNA
M_B_CPU1_SB_DQ<2>        U1               W29      SOCKET4677_AZIFS054P001C01-SOCA
M_B_CPU1_SB_DQ<3>        J19              247      SCONN288_ADR50001P013C01-SCONNA
M_B_CPU1_SB_DQ<3>        J20              247      SCONN288_ADR50001P003C01-SCONNA
M_B_CPU1_SB_DQ<3>        U1               Y28      SOCKET4677_AZIFS054P001C01-SOCA
M_B_CPU1_SB_DQ<4>        J19              107      SCONN288_ADR50001P013C01-SCONNA
M_B_CPU1_SB_DQ<4>        J20              107      SCONN288_ADR50001P003C01-SCONNA
M_B_CPU1_SB_DQ<4>        U1               T26      SOCKET4677_AZIFS054P001C01-SOCA
M_B_CPU1_SB_DQ<5>        J19              109      SCONN288_ADR50001P013C01-SCONNA
M_B_CPU1_SB_DQ<5>        J20              109      SCONN288_ADR50001P003C01-SCONNA
M_B_CPU1_SB_DQ<5>        U1               U25      SOCKET4677_AZIFS054P001C01-SOCA
M_B_CPU1_SB_DQ<6>        J19              252      SCONN288_ADR50001P013C01-SCONNA
M_B_CPU1_SB_DQ<6>        J20              252      SCONN288_ADR50001P003C01-SCONNA
M_B_CPU1_SB_DQ<6>        U1               Y26      SOCKET4677_AZIFS054P001C01-SOCA
M_B_CPU1_SB_DQ<7>        J19              254      SCONN288_ADR50001P013C01-SCONNA
M_B_CPU1_SB_DQ<7>        J20              254      SCONN288_ADR50001P003C01-SCONNA
M_B_CPU1_SB_DQ<7>        U1               W25      SOCKET4677_AZIFS054P001C01-SOCA
M_B_CPU1_SB_DQ<8>        J19              111      SCONN288_ADR50001P013C01-SCONNA
M_B_CPU1_SB_DQ<8>        J20              111      SCONN288_ADR50001P003C01-SCONNA
M_B_CPU1_SB_DQ<8>        U1               K26      SOCKET4677_AZIFS054P001C01-SOCA
M_B_CPU1_SB_DQ<9>        J19              113      SCONN288_ADR50001P013C01-SCONNA
M_B_CPU1_SB_DQ<9>        J20              113      SCONN288_ADR50001P003C01-SCONNA
M_B_CPU1_SB_DQ<9>        U1               J25      SOCKET4677_AZIFS054P001C01-SOCA
M_B_CPU1_SB_DQ<10>       J19              256      SCONN288_ADR50001P013C01-SCONNA
M_B_CPU1_SB_DQ<10>       J20              256      SCONN288_ADR50001P003C01-SCONNA
M_B_CPU1_SB_DQ<10>       U1               M26      SOCKET4677_AZIFS054P001C01-SOCA
M_B_CPU1_SB_DQ<11>       J19              258      SCONN288_ADR50001P013C01-SCONNA
M_B_CPU1_SB_DQ<11>       J20              258      SCONN288_ADR50001P003C01-SCONNA
M_B_CPU1_SB_DQ<11>       U1               N25      SOCKET4677_AZIFS054P001C01-SOCA
M_B_CPU1_SB_DQ<12>       J19              118      SCONN288_ADR50001P013C01-SCONNA
M_B_CPU1_SB_DQ<12>       J20              118      SCONN288_ADR50001P003C01-SCONNA
M_B_CPU1_SB_DQ<12>       U1               J23      SOCKET4677_AZIFS054P001C01-SOCA
M_B_CPU1_SB_DQ<13>       J19              120      SCONN288_ADR50001P013C01-SCONNA
M_B_CPU1_SB_DQ<13>       J20              120      SCONN288_ADR50001P003C01-SCONNA
M_B_CPU1_SB_DQ<13>       U1               K22      SOCKET4677_AZIFS054P001C01-SOCA
M_B_CPU1_SB_DQ<14>       J19              263      SCONN288_ADR50001P013C01-SCONNA
M_B_CPU1_SB_DQ<14>       J20              263      SCONN288_ADR50001P003C01-SCONNA
M_B_CPU1_SB_DQ<14>       U1               N23      SOCKET4677_AZIFS054P001C01-SOCA
M_B_CPU1_SB_DQ<15>       J19              265      SCONN288_ADR50001P013C01-SCONNA
M_B_CPU1_SB_DQ<15>       J20              265      SCONN288_ADR50001P003C01-SCONNA
M_B_CPU1_SB_DQ<15>       U1               M22      SOCKET4677_AZIFS054P001C01-SOCA
M_B_CPU1_SB_DQ<16>       J19              122      SCONN288_ADR50001P013C01-SCONNA
M_B_CPU1_SB_DQ<16>       J20              122      SCONN288_ADR50001P003C01-SCONNA
M_B_CPU1_SB_DQ<16>       U1               K20      SOCKET4677_AZIFS054P001C01-SOCA
M_B_CPU1_SB_DQ<17>       J19              124      SCONN288_ADR50001P013C01-SCONNA
M_B_CPU1_SB_DQ<17>       J20              124      SCONN288_ADR50001P003C01-SCONNA
M_B_CPU1_SB_DQ<17>       U1               J19      SOCKET4677_AZIFS054P001C01-SOCA
M_B_CPU1_SB_DQ<18>       J19              267      SCONN288_ADR50001P013C01-SCONNA
M_B_CPU1_SB_DQ<18>       J20              267      SCONN288_ADR50001P003C01-SCONNA
M_B_CPU1_SB_DQ<18>       U1               M20      SOCKET4677_AZIFS054P001C01-SOCA
M_B_CPU1_SB_DQ<19>       J19              269      SCONN288_ADR50001P013C01-SCONNA
M_B_CPU1_SB_DQ<19>       J20              269      SCONN288_ADR50001P003C01-SCONNA
M_B_CPU1_SB_DQ<19>       U1               N19      SOCKET4677_AZIFS054P001C01-SOCA
M_B_CPU1_SB_DQ<20>       J19              129      SCONN288_ADR50001P013C01-SCONNA
M_B_CPU1_SB_DQ<20>       J20              129      SCONN288_ADR50001P003C01-SCONNA
M_B_CPU1_SB_DQ<20>       U1               J17      SOCKET4677_AZIFS054P001C01-SOCA
M_B_CPU1_SB_DQ<21>       J19              131      SCONN288_ADR50001P013C01-SCONNA
M_B_CPU1_SB_DQ<21>       J20              131      SCONN288_ADR50001P003C01-SCONNA
M_B_CPU1_SB_DQ<21>       U1               K16      SOCKET4677_AZIFS054P001C01-SOCA
M_B_CPU1_SB_DQ<22>       J19              274      SCONN288_ADR50001P013C01-SCONNA
M_B_CPU1_SB_DQ<22>       J20              274      SCONN288_ADR50001P003C01-SCONNA
M_B_CPU1_SB_DQ<22>       U1               N17      SOCKET4677_AZIFS054P001C01-SOCA
M_B_CPU1_SB_DQ<23>       J19              276      SCONN288_ADR50001P013C01-SCONNA
M_B_CPU1_SB_DQ<23>       J20              276      SCONN288_ADR50001P003C01-SCONNA
M_B_CPU1_SB_DQ<23>       U1               M16      SOCKET4677_AZIFS054P001C01-SOCA
M_B_CPU1_SB_DQ<24>       J19              133      SCONN288_ADR50001P013C01-SCONNA
M_B_CPU1_SB_DQ<24>       J20              133      SCONN288_ADR50001P003C01-SCONNA
M_B_CPU1_SB_DQ<24>       U1               C17      SOCKET4677_AZIFS054P001C01-SOCA
M_B_CPU1_SB_DQ<25>       J19              135      SCONN288_ADR50001P013C01-SCONNA
M_B_CPU1_SB_DQ<25>       J20              135      SCONN288_ADR50001P003C01-SCONNA
M_B_CPU1_SB_DQ<25>       U1               B16      SOCKET4677_AZIFS054P001C01-SOCA
M_B_CPU1_SB_DQ<26>       J19              278      SCONN288_ADR50001P013C01-SCONNA
M_B_CPU1_SB_DQ<26>       J20              278      SCONN288_ADR50001P003C01-SCONNA
M_B_CPU1_SB_DQ<26>       U1               E17      SOCKET4677_AZIFS054P001C01-SOCA
M_B_CPU1_SB_DQ<27>       J19              280      SCONN288_ADR50001P013C01-SCONNA
M_B_CPU1_SB_DQ<27>       J20              280      SCONN288_ADR50001P003C01-SCONNA
M_B_CPU1_SB_DQ<27>       U1               F16      SOCKET4677_AZIFS054P001C01-SOCA
M_B_CPU1_SB_DQ<28>       J19              140      SCONN288_ADR50001P013C01-SCONNA
M_B_CPU1_SB_DQ<28>       J20              140      SCONN288_ADR50001P003C01-SCONNA
M_B_CPU1_SB_DQ<28>       U1               C13      SOCKET4677_AZIFS054P001C01-SOCA
M_B_CPU1_SB_DQ<29>       J19              142      SCONN288_ADR50001P013C01-SCONNA
M_B_CPU1_SB_DQ<29>       J20              142      SCONN288_ADR50001P003C01-SCONNA
M_B_CPU1_SB_DQ<29>       U1               E13      SOCKET4677_AZIFS054P001C01-SOCA
M_B_CPU1_SB_DQ<30>       J19              285      SCONN288_ADR50001P013C01-SCONNA
M_B_CPU1_SB_DQ<30>       J20              285      SCONN288_ADR50001P003C01-SCONNA
M_B_CPU1_SB_DQ<30>       U1               B14      SOCKET4677_AZIFS054P001C01-SOCA
M_B_CPU1_SB_DQ<31>       J19              287      SCONN288_ADR50001P013C01-SCONNA
M_B_CPU1_SB_DQ<31>       J20              287      SCONN288_ADR50001P003C01-SCONNA
M_B_CPU1_SB_DQ<31>       U1               F14      SOCKET4677_AZIFS054P001C01-SOCA
M_B_CPU1_SB_DQS_DN<0>    J19              105      SCONN288_ADR50001P013C01-SCONNA
M_B_CPU1_SB_DQS_DN<0>    J20              105      SCONN288_ADR50001P003C01-SCONNA
M_B_CPU1_SB_DQS_DN<0>    U1               R27      SOCKET4677_AZIFS054P001C01-SOCA
M_B_CPU1_SB_DQS_DN<1>    J19              116      SCONN288_ADR50001P013C01-SCONNA
M_B_CPU1_SB_DQS_DN<1>    J20              116      SCONN288_ADR50001P003C01-SCONNA
M_B_CPU1_SB_DQS_DN<1>    U1               H24      SOCKET4677_AZIFS054P001C01-SOCA
M_B_CPU1_SB_DQS_DN<2>    J19              127      SCONN288_ADR50001P013C01-SCONNA
M_B_CPU1_SB_DQS_DN<2>    J20              127      SCONN288_ADR50001P003C01-SCONNA
M_B_CPU1_SB_DQS_DN<2>    U1               H18      SOCKET4677_AZIFS054P001C01-SOCA
M_B_CPU1_SB_DQS_DN<3>    J19              138      SCONN288_ADR50001P013C01-SCONNA
M_B_CPU1_SB_DQS_DN<3>    J20              138      SCONN288_ADR50001P003C01-SCONNA
M_B_CPU1_SB_DQS_DN<3>    U1               A15      SOCKET4677_AZIFS054P001C01-SOCA
M_B_CPU1_SB_DQS_DN<4>    J19              238      SCONN288_ADR50001P013C01-SCONNA
M_B_CPU1_SB_DQS_DN<4>    J20              238      SCONN288_ADR50001P003C01-SCONNA
M_B_CPU1_SB_DQS_DN<4>    U1               P36      SOCKET4677_AZIFS054P001C01-SOCA
M_B_CPU1_SB_DQS_DN<5>    J19              249      SCONN288_ADR50001P013C01-SCONNA
M_B_CPU1_SB_DQS_DN<5>    J20              249      SCONN288_ADR50001P003C01-SCONNA
M_B_CPU1_SB_DQS_DN<5>    U1               W27      SOCKET4677_AZIFS054P001C01-SOCA
M_B_CPU1_SB_DQS_DN<6>    J19              260      SCONN288_ADR50001P013C01-SCONNA
M_B_CPU1_SB_DQS_DN<6>    J20              260      SCONN288_ADR50001P003C01-SCONNA
M_B_CPU1_SB_DQS_DN<6>    U1               M24      SOCKET4677_AZIFS054P001C01-SOCA
M_B_CPU1_SB_DQS_DN<7>    J19              271      SCONN288_ADR50001P013C01-SCONNA
M_B_CPU1_SB_DQS_DN<7>    J20              271      SCONN288_ADR50001P003C01-SCONNA
M_B_CPU1_SB_DQS_DN<7>    U1               M18      SOCKET4677_AZIFS054P001C01-SOCA
M_B_CPU1_SB_DQS_DN<8>    J19              282      SCONN288_ADR50001P013C01-SCONNA
M_B_CPU1_SB_DQS_DN<8>    J20              282      SCONN288_ADR50001P003C01-SCONNA
M_B_CPU1_SB_DQS_DN<8>    U1               E15      SOCKET4677_AZIFS054P001C01-SOCA
M_B_CPU1_SB_DQS_DN<9>    J19              94       SCONN288_ADR50001P013C01-SCONNA
M_B_CPU1_SB_DQS_DN<9>    J20              94       SCONN288_ADR50001P003C01-SCONNA
M_B_CPU1_SB_DQS_DN<9>    U1               K36      SOCKET4677_AZIFS054P001C01-SOCA
M_B_CPU1_SB_DQS_DP<0>    J19              104      SCONN288_ADR50001P013C01-SCONNA
M_B_CPU1_SB_DQS_DP<0>    J20              104      SCONN288_ADR50001P003C01-SCONNA
M_B_CPU1_SB_DQS_DP<0>    U1               U27      SOCKET4677_AZIFS054P001C01-SOCA
M_B_CPU1_SB_DQS_DP<1>    J19              115      SCONN288_ADR50001P013C01-SCONNA
M_B_CPU1_SB_DQS_DP<1>    J20              115      SCONN288_ADR50001P003C01-SCONNA
M_B_CPU1_SB_DQS_DP<1>    U1               K24      SOCKET4677_AZIFS054P001C01-SOCA
M_B_CPU1_SB_DQS_DP<2>    J19              126      SCONN288_ADR50001P013C01-SCONNA
M_B_CPU1_SB_DQS_DP<2>    J20              126      SCONN288_ADR50001P003C01-SCONNA
M_B_CPU1_SB_DQS_DP<2>    U1               K18      SOCKET4677_AZIFS054P001C01-SOCA
M_B_CPU1_SB_DQS_DP<3>    J19              137      SCONN288_ADR50001P013C01-SCONNA
M_B_CPU1_SB_DQS_DP<3>    J20              137      SCONN288_ADR50001P003C01-SCONNA
M_B_CPU1_SB_DQS_DP<3>    U1               C15      SOCKET4677_AZIFS054P001C01-SOCA
M_B_CPU1_SB_DQS_DP<4>    J19              239      SCONN288_ADR50001P013C01-SCONNA
M_B_CPU1_SB_DQS_DP<4>    J20              239      SCONN288_ADR50001P003C01-SCONNA
M_B_CPU1_SB_DQS_DP<4>    U1               M36      SOCKET4677_AZIFS054P001C01-SOCA
M_B_CPU1_SB_DQS_DP<5>    J19              250      SCONN288_ADR50001P013C01-SCONNA
M_B_CPU1_SB_DQS_DP<5>    J20              250      SCONN288_ADR50001P003C01-SCONNA
M_B_CPU1_SB_DQS_DP<5>    U1               AA27     SOCKET4677_AZIFS054P001C01-SOCA
M_B_CPU1_SB_DQS_DP<6>    J19              261      SCONN288_ADR50001P013C01-SCONNA
M_B_CPU1_SB_DQS_DP<6>    J20              261      SCONN288_ADR50001P003C01-SCONNA
M_B_CPU1_SB_DQS_DP<6>    U1               P24      SOCKET4677_AZIFS054P001C01-SOCA
M_B_CPU1_SB_DQS_DP<7>    J19              272      SCONN288_ADR50001P013C01-SCONNA
M_B_CPU1_SB_DQS_DP<7>    J20              272      SCONN288_ADR50001P003C01-SCONNA
M_B_CPU1_SB_DQS_DP<7>    U1               P18      SOCKET4677_AZIFS054P001C01-SOCA
M_B_CPU1_SB_DQS_DP<8>    J19              283      SCONN288_ADR50001P013C01-SCONNA
M_B_CPU1_SB_DQS_DP<8>    J20              283      SCONN288_ADR50001P003C01-SCONNA
M_B_CPU1_SB_DQS_DP<8>    U1               G15      SOCKET4677_AZIFS054P001C01-SOCA
M_B_CPU1_SB_DQS_DP<9>    J19              93       SCONN288_ADR50001P013C01-SCONNA
M_B_CPU1_SB_DQS_DP<9>    J20              93       SCONN288_ADR50001P003C01-SCONNA
M_B_CPU1_SB_DQS_DP<9>    U1               H36      SOCKET4677_AZIFS054P001C01-SOCA
M_B_CPU1_SB_PAR          J19              227      SCONN288_ADR50001P013C01-SCONNA
M_B_CPU1_SB_PAR          J20              227      SCONN288_ADR50001P003C01-SCONNA
M_B_CPU1_SB_PAR          U1               P42      SOCKET4677_AZIFS054P001C01-SOCA
M_B_CPU1_SB_RSP<0>       J19              87       SCONN288_ADR50001P013C01-SCONNA
M_B_CPU1_SB_RSP<0>       U1               AN48     SOCKET4677_AZIFS054P001C01-SOCA
M_B_CPU1_SB_RSP<1>       J20              87       SCONN288_ADR50001P003C01-SCONNA
M_B_CPU1_SB_RSP<1>       U1               AP47     SOCKET4677_AZIFS054P001C01-SOCA
M_C_CPU0_ALERT_N         J5               62       SCONN288_ADR50001P013C01-SCONNA
M_C_CPU0_ALERT_N         J6               62       SCONN288_ADR50001P003C01-SCONNA
M_C_CPU0_ALERT_N         U2               AT47     SOCKET4677_AZIFS054P001C01-SOCA
M_C_CPU0_CLK_DN<0>       J5               218      SCONN288_ADR50001P013C01-SCONNA
M_C_CPU0_CLK_DN<0>       U2               AB49     SOCKET4677_AZIFS054P001C01-SOCA
M_C_CPU0_CLK_DN<1>       J6               218      SCONN288_ADR50001P003C01-SCONNA
M_C_CPU0_CLK_DN<1>       U2               AF49     SOCKET4677_AZIFS054P001C01-SOCA
M_C_CPU0_CLK_DP<0>       J5               217      SCONN288_ADR50001P013C01-SCONNA
M_C_CPU0_CLK_DP<0>       U2               AD49     SOCKET4677_AZIFS054P001C01-SOCA
M_C_CPU0_CLK_DP<1>       J6               217      SCONN288_ADR50001P003C01-SCONNA
M_C_CPU0_CLK_DP<1>       U2               AH49     SOCKET4677_AZIFS054P001C01-SOCA
M_C_CPU0_SA_CA<0>        J5               66       SCONN288_ADR50001P013C01-SCONNA
M_C_CPU0_SA_CA<0>        J6               66       SCONN288_ADR50001P003C01-SCONNA
M_C_CPU0_SA_CA<0>        U2               R52      SOCKET4677_AZIFS054P001C01-SOCA
M_C_CPU0_SA_CA<1>        J5               211      SCONN288_ADR50001P013C01-SCONNA
M_C_CPU0_SA_CA<1>        J6               211      SCONN288_ADR50001P003C01-SCONNA
M_C_CPU0_SA_CA<1>        U2               AA52     SOCKET4677_AZIFS054P001C01-SOCA
M_C_CPU0_SA_CA<2>        J5               68       SCONN288_ADR50001P013C01-SCONNA
M_C_CPU0_SA_CA<2>        J6               68       SCONN288_ADR50001P003C01-SCONNA
M_C_CPU0_SA_CA<2>        U2               T51      SOCKET4677_AZIFS054P001C01-SOCA
M_C_CPU0_SA_CA<3>        J5               213      SCONN288_ADR50001P013C01-SCONNA
M_C_CPU0_SA_CA<3>        J6               213      SCONN288_ADR50001P003C01-SCONNA
M_C_CPU0_SA_CA<3>        U2               Y51      SOCKET4677_AZIFS054P001C01-SOCA
M_C_CPU0_SA_CA<4>        J5               70       SCONN288_ADR50001P013C01-SCONNA
M_C_CPU0_SA_CA<4>        J6               70       SCONN288_ADR50001P003C01-SCONNA
M_C_CPU0_SA_CA<4>        U2               U50      SOCKET4677_AZIFS054P001C01-SOCA
M_C_CPU0_SA_CA<5>        J5               215      SCONN288_ADR50001P013C01-SCONNA
M_C_CPU0_SA_CA<5>        J6               215      SCONN288_ADR50001P003C01-SCONNA
M_C_CPU0_SA_CA<5>        U2               W50      SOCKET4677_AZIFS054P001C01-SOCA
M_C_CPU0_SA_CA<6>        J5               72       SCONN288_ADR50001P013C01-SCONNA
M_C_CPU0_SA_CA<6>        J6               72       SCONN288_ADR50001P003C01-SCONNA
M_C_CPU0_SA_CA<6>        U2               U48      SOCKET4677_AZIFS054P001C01-SOCA
M_C_CPU0_SA_CB<0>        J5               51       SCONN288_ADR50001P013C01-SCONNA
M_C_CPU0_SA_CB<0>        J6               51       SCONN288_ADR50001P003C01-SCONNA
M_C_CPU0_SA_CB<0>        U2               AD57     SOCKET4677_AZIFS054P001C01-SOCA
M_C_CPU0_SA_CB<1>        J5               53       SCONN288_ADR50001P013C01-SCONNA
M_C_CPU0_SA_CB<1>        J6               53       SCONN288_ADR50001P003C01-SCONNA
M_C_CPU0_SA_CB<1>        U2               AC56     SOCKET4677_AZIFS054P001C01-SOCA
M_C_CPU0_SA_CB<2>        J5               196      SCONN288_ADR50001P013C01-SCONNA
M_C_CPU0_SA_CB<2>        J6               196      SCONN288_ADR50001P003C01-SCONNA
M_C_CPU0_SA_CB<2>        U2               AF57     SOCKET4677_AZIFS054P001C01-SOCA
M_C_CPU0_SA_CB<3>        J5               198      SCONN288_ADR50001P013C01-SCONNA
M_C_CPU0_SA_CB<3>        J6               198      SCONN288_ADR50001P003C01-SCONNA
M_C_CPU0_SA_CB<3>        U2               AG56     SOCKET4677_AZIFS054P001C01-SOCA
M_C_CPU0_SA_CB<4>        J5               58       SCONN288_ADR50001P013C01-SCONNA
M_C_CPU0_SA_CB<4>        J6               58       SCONN288_ADR50001P003C01-SCONNA
M_C_CPU0_SA_CB<4>        U2               AC54     SOCKET4677_AZIFS054P001C01-SOCA
M_C_CPU0_SA_CB<5>        J5               60       SCONN288_ADR50001P013C01-SCONNA
M_C_CPU0_SA_CB<5>        J6               60       SCONN288_ADR50001P003C01-SCONNA
M_C_CPU0_SA_CB<5>        U2               AD53     SOCKET4677_AZIFS054P001C01-SOCA
M_C_CPU0_SA_CB<6>        J5               203      SCONN288_ADR50001P013C01-SCONNA
M_C_CPU0_SA_CB<6>        J6               203      SCONN288_ADR50001P003C01-SCONNA
M_C_CPU0_SA_CB<6>        U2               AG54     SOCKET4677_AZIFS054P001C01-SOCA
M_C_CPU0_SA_CB<7>        J5               205      SCONN288_ADR50001P013C01-SCONNA
M_C_CPU0_SA_CB<7>        J6               205      SCONN288_ADR50001P003C01-SCONNA
M_C_CPU0_SA_CB<7>        U2               AF53     SOCKET4677_AZIFS054P001C01-SOCA
M_C_CPU0_SA_CS_N<0>      J5               64       SCONN288_ADR50001P013C01-SCONNA
M_C_CPU0_SA_CS_N<0>      U2               U54      SOCKET4677_AZIFS054P001C01-SOCA
M_C_CPU0_SA_CS_N<1>      J5               209      SCONN288_ADR50001P013C01-SCONNA
M_C_CPU0_SA_CS_N<1>      U2               T53      SOCKET4677_AZIFS054P001C01-SOCA
M_C_CPU0_SA_CS_N<2>      J6               64       SCONN288_ADR50001P003C01-SCONNA
M_C_CPU0_SA_CS_N<2>      U2               W54      SOCKET4677_AZIFS054P001C01-SOCA
M_C_CPU0_SA_CS_N<3>      J6               209      SCONN288_ADR50001P003C01-SCONNA
M_C_CPU0_SA_CS_N<3>      U2               Y53      SOCKET4677_AZIFS054P001C01-SOCA
M_C_CPU0_SA_DQ<0>        J5               7        SCONN288_ADR50001P013C01-SCONNA
M_C_CPU0_SA_DQ<0>        J6               7        SCONN288_ADR50001P003C01-SCONNA
M_C_CPU0_SA_DQ<0>        U2               U78      SOCKET4677_AZIFS054P001C01-SOCA
M_C_CPU0_SA_DQ<1>        J5               9        SCONN288_ADR50001P013C01-SCONNA
M_C_CPU0_SA_DQ<1>        J6               9        SCONN288_ADR50001P003C01-SCONNA
M_C_CPU0_SA_DQ<1>        U2               T77      SOCKET4677_AZIFS054P001C01-SOCA
M_C_CPU0_SA_DQ<2>        J5               152      SCONN288_ADR50001P013C01-SCONNA
M_C_CPU0_SA_DQ<2>        J6               152      SCONN288_ADR50001P003C01-SCONNA
M_C_CPU0_SA_DQ<2>        U2               W78      SOCKET4677_AZIFS054P001C01-SOCA
M_C_CPU0_SA_DQ<3>        J5               154      SCONN288_ADR50001P013C01-SCONNA
M_C_CPU0_SA_DQ<3>        J6               154      SCONN288_ADR50001P003C01-SCONNA
M_C_CPU0_SA_DQ<3>        U2               Y77      SOCKET4677_AZIFS054P001C01-SOCA
M_C_CPU0_SA_DQ<4>        J5               14       SCONN288_ADR50001P013C01-SCONNA
M_C_CPU0_SA_DQ<4>        J6               14       SCONN288_ADR50001P003C01-SCONNA
M_C_CPU0_SA_DQ<4>        U2               T75      SOCKET4677_AZIFS054P001C01-SOCA
M_C_CPU0_SA_DQ<5>        J5               16       SCONN288_ADR50001P013C01-SCONNA
M_C_CPU0_SA_DQ<5>        J6               16       SCONN288_ADR50001P003C01-SCONNA
M_C_CPU0_SA_DQ<5>        U2               U74      SOCKET4677_AZIFS054P001C01-SOCA
M_C_CPU0_SA_DQ<6>        J5               159      SCONN288_ADR50001P013C01-SCONNA
M_C_CPU0_SA_DQ<6>        J6               159      SCONN288_ADR50001P003C01-SCONNA
M_C_CPU0_SA_DQ<6>        U2               Y75      SOCKET4677_AZIFS054P001C01-SOCA
M_C_CPU0_SA_DQ<7>        J5               161      SCONN288_ADR50001P013C01-SCONNA
M_C_CPU0_SA_DQ<7>        J6               161      SCONN288_ADR50001P003C01-SCONNA
M_C_CPU0_SA_DQ<7>        U2               W74      SOCKET4677_AZIFS054P001C01-SOCA
M_C_CPU0_SA_DQ<8>        J5               18       SCONN288_ADR50001P013C01-SCONNA
M_C_CPU0_SA_DQ<8>        J6               18       SCONN288_ADR50001P003C01-SCONNA
M_C_CPU0_SA_DQ<8>        U2               AD69     SOCKET4677_AZIFS054P001C01-SOCA
M_C_CPU0_SA_DQ<9>        J5               20       SCONN288_ADR50001P013C01-SCONNA
M_C_CPU0_SA_DQ<9>        J6               20       SCONN288_ADR50001P003C01-SCONNA
M_C_CPU0_SA_DQ<9>        U2               AC68     SOCKET4677_AZIFS054P001C01-SOCA
M_C_CPU0_SA_DQ<10>       J5               163      SCONN288_ADR50001P013C01-SCONNA
M_C_CPU0_SA_DQ<10>       J6               163      SCONN288_ADR50001P003C01-SCONNA
M_C_CPU0_SA_DQ<10>       U2               AF69     SOCKET4677_AZIFS054P001C01-SOCA
M_C_CPU0_SA_DQ<11>       J5               165      SCONN288_ADR50001P013C01-SCONNA
M_C_CPU0_SA_DQ<11>       J6               165      SCONN288_ADR50001P003C01-SCONNA
M_C_CPU0_SA_DQ<11>       U2               AG68     SOCKET4677_AZIFS054P001C01-SOCA
M_C_CPU0_SA_DQ<12>       J5               25       SCONN288_ADR50001P013C01-SCONNA
M_C_CPU0_SA_DQ<12>       J6               25       SCONN288_ADR50001P003C01-SCONNA
M_C_CPU0_SA_DQ<12>       U2               AC66     SOCKET4677_AZIFS054P001C01-SOCA
M_C_CPU0_SA_DQ<13>       J5               27       SCONN288_ADR50001P013C01-SCONNA
M_C_CPU0_SA_DQ<13>       J6               27       SCONN288_ADR50001P003C01-SCONNA
M_C_CPU0_SA_DQ<13>       U2               AD65     SOCKET4677_AZIFS054P001C01-SOCA
M_C_CPU0_SA_DQ<14>       J5               170      SCONN288_ADR50001P013C01-SCONNA
M_C_CPU0_SA_DQ<14>       J6               170      SCONN288_ADR50001P003C01-SCONNA
M_C_CPU0_SA_DQ<14>       U2               AG66     SOCKET4677_AZIFS054P001C01-SOCA
M_C_CPU0_SA_DQ<15>       J5               172      SCONN288_ADR50001P013C01-SCONNA
M_C_CPU0_SA_DQ<15>       J6               172      SCONN288_ADR50001P003C01-SCONNA
M_C_CPU0_SA_DQ<15>       U2               AF65     SOCKET4677_AZIFS054P001C01-SOCA
M_C_CPU0_SA_DQ<16>       J5               29       SCONN288_ADR50001P013C01-SCONNA
M_C_CPU0_SA_DQ<16>       J6               29       SCONN288_ADR50001P003C01-SCONNA
M_C_CPU0_SA_DQ<16>       U2               U66      SOCKET4677_AZIFS054P001C01-SOCA
M_C_CPU0_SA_DQ<17>       J5               31       SCONN288_ADR50001P013C01-SCONNA
M_C_CPU0_SA_DQ<17>       J6               31       SCONN288_ADR50001P003C01-SCONNA
M_C_CPU0_SA_DQ<17>       U2               T65      SOCKET4677_AZIFS054P001C01-SOCA
M_C_CPU0_SA_DQ<18>       J5               174      SCONN288_ADR50001P013C01-SCONNA
M_C_CPU0_SA_DQ<18>       J6               174      SCONN288_ADR50001P003C01-SCONNA
M_C_CPU0_SA_DQ<18>       U2               W66      SOCKET4677_AZIFS054P001C01-SOCA
M_C_CPU0_SA_DQ<19>       J5               176      SCONN288_ADR50001P013C01-SCONNA
M_C_CPU0_SA_DQ<19>       J6               176      SCONN288_ADR50001P003C01-SCONNA
M_C_CPU0_SA_DQ<19>       U2               Y65      SOCKET4677_AZIFS054P001C01-SOCA
M_C_CPU0_SA_DQ<20>       J5               36       SCONN288_ADR50001P013C01-SCONNA
M_C_CPU0_SA_DQ<20>       J6               36       SCONN288_ADR50001P003C01-SCONNA
M_C_CPU0_SA_DQ<20>       U2               T63      SOCKET4677_AZIFS054P001C01-SOCA
M_C_CPU0_SA_DQ<21>       J5               38       SCONN288_ADR50001P013C01-SCONNA
M_C_CPU0_SA_DQ<21>       J6               38       SCONN288_ADR50001P003C01-SCONNA
M_C_CPU0_SA_DQ<21>       U2               U62      SOCKET4677_AZIFS054P001C01-SOCA
M_C_CPU0_SA_DQ<22>       J5               181      SCONN288_ADR50001P013C01-SCONNA
M_C_CPU0_SA_DQ<22>       J6               181      SCONN288_ADR50001P003C01-SCONNA
M_C_CPU0_SA_DQ<22>       U2               Y63      SOCKET4677_AZIFS054P001C01-SOCA
M_C_CPU0_SA_DQ<23>       J5               183      SCONN288_ADR50001P013C01-SCONNA
M_C_CPU0_SA_DQ<23>       J6               183      SCONN288_ADR50001P003C01-SCONNA
M_C_CPU0_SA_DQ<23>       U2               W62      SOCKET4677_AZIFS054P001C01-SOCA
M_C_CPU0_SA_DQ<24>       J5               40       SCONN288_ADR50001P013C01-SCONNA
M_C_CPU0_SA_DQ<24>       J6               40       SCONN288_ADR50001P003C01-SCONNA
M_C_CPU0_SA_DQ<24>       U2               AD63     SOCKET4677_AZIFS054P001C01-SOCA
M_C_CPU0_SA_DQ<25>       J5               42       SCONN288_ADR50001P013C01-SCONNA
M_C_CPU0_SA_DQ<25>       J6               42       SCONN288_ADR50001P003C01-SCONNA
M_C_CPU0_SA_DQ<25>       U2               AC62     SOCKET4677_AZIFS054P001C01-SOCA
M_C_CPU0_SA_DQ<26>       J5               185      SCONN288_ADR50001P013C01-SCONNA
M_C_CPU0_SA_DQ<26>       J6               185      SCONN288_ADR50001P003C01-SCONNA
M_C_CPU0_SA_DQ<26>       U2               AF63     SOCKET4677_AZIFS054P001C01-SOCA
M_C_CPU0_SA_DQ<27>       J5               187      SCONN288_ADR50001P013C01-SCONNA
M_C_CPU0_SA_DQ<27>       J6               187      SCONN288_ADR50001P003C01-SCONNA
M_C_CPU0_SA_DQ<27>       U2               AG62     SOCKET4677_AZIFS054P001C01-SOCA
M_C_CPU0_SA_DQ<28>       J5               47       SCONN288_ADR50001P013C01-SCONNA
M_C_CPU0_SA_DQ<28>       J6               47       SCONN288_ADR50001P003C01-SCONNA
M_C_CPU0_SA_DQ<28>       U2               AC60     SOCKET4677_AZIFS054P001C01-SOCA
M_C_CPU0_SA_DQ<29>       J5               49       SCONN288_ADR50001P013C01-SCONNA
M_C_CPU0_SA_DQ<29>       J6               49       SCONN288_ADR50001P003C01-SCONNA
M_C_CPU0_SA_DQ<29>       U2               AD59     SOCKET4677_AZIFS054P001C01-SOCA
M_C_CPU0_SA_DQ<30>       J5               192      SCONN288_ADR50001P013C01-SCONNA
M_C_CPU0_SA_DQ<30>       J6               192      SCONN288_ADR50001P003C01-SCONNA
M_C_CPU0_SA_DQ<30>       U2               AG60     SOCKET4677_AZIFS054P001C01-SOCA
M_C_CPU0_SA_DQ<31>       J5               194      SCONN288_ADR50001P013C01-SCONNA
M_C_CPU0_SA_DQ<31>       J6               194      SCONN288_ADR50001P003C01-SCONNA
M_C_CPU0_SA_DQ<31>       U2               AF59     SOCKET4677_AZIFS054P001C01-SOCA
M_C_CPU0_SA_DQS_DN<0>    J5               12       SCONN288_ADR50001P013C01-SCONNA
M_C_CPU0_SA_DQS_DN<0>    J6               12       SCONN288_ADR50001P003C01-SCONNA
M_C_CPU0_SA_DQS_DN<0>    U2               R76      SOCKET4677_AZIFS054P001C01-SOCA
M_C_CPU0_SA_DQS_DN<1>    J5               23       SCONN288_ADR50001P013C01-SCONNA
M_C_CPU0_SA_DQS_DN<1>    J6               23       SCONN288_ADR50001P003C01-SCONNA
M_C_CPU0_SA_DQS_DN<1>    U2               AB67     SOCKET4677_AZIFS054P001C01-SOCA
M_C_CPU0_SA_DQS_DN<2>    J5               34       SCONN288_ADR50001P013C01-SCONNA
M_C_CPU0_SA_DQS_DN<2>    J6               34       SCONN288_ADR50001P003C01-SCONNA
M_C_CPU0_SA_DQS_DN<2>    U2               R64      SOCKET4677_AZIFS054P001C01-SOCA
M_C_CPU0_SA_DQS_DN<3>    J5               45       SCONN288_ADR50001P013C01-SCONNA
M_C_CPU0_SA_DQS_DN<3>    J6               45       SCONN288_ADR50001P003C01-SCONNA
M_C_CPU0_SA_DQS_DN<3>    U2               AB61     SOCKET4677_AZIFS054P001C01-SOCA
M_C_CPU0_SA_DQS_DN<4>    J5               56       SCONN288_ADR50001P013C01-SCONNA
M_C_CPU0_SA_DQS_DN<4>    J6               56       SCONN288_ADR50001P003C01-SCONNA
M_C_CPU0_SA_DQS_DN<4>    U2               AD55     SOCKET4677_AZIFS054P001C01-SOCA
M_C_CPU0_SA_DQS_DN<5>    J5               156      SCONN288_ADR50001P013C01-SCONNA
M_C_CPU0_SA_DQS_DN<5>    J6               156      SCONN288_ADR50001P003C01-SCONNA
M_C_CPU0_SA_DQS_DN<5>    U2               W76      SOCKET4677_AZIFS054P001C01-SOCA
M_C_CPU0_SA_DQS_DN<6>    J5               167      SCONN288_ADR50001P013C01-SCONNA
M_C_CPU0_SA_DQS_DN<6>    J6               167      SCONN288_ADR50001P003C01-SCONNA
M_C_CPU0_SA_DQS_DN<6>    U2               AH67     SOCKET4677_AZIFS054P001C01-SOCA
M_C_CPU0_SA_DQS_DN<7>    J5               178      SCONN288_ADR50001P013C01-SCONNA
M_C_CPU0_SA_DQS_DN<7>    J6               178      SCONN288_ADR50001P003C01-SCONNA
M_C_CPU0_SA_DQS_DN<7>    U2               AA64     SOCKET4677_AZIFS054P001C01-SOCA
M_C_CPU0_SA_DQS_DN<8>    J5               189      SCONN288_ADR50001P013C01-SCONNA
M_C_CPU0_SA_DQS_DN<8>    J6               189      SCONN288_ADR50001P003C01-SCONNA
M_C_CPU0_SA_DQS_DN<8>    U2               AF61     SOCKET4677_AZIFS054P001C01-SOCA
M_C_CPU0_SA_DQS_DN<9>    J5               200      SCONN288_ADR50001P013C01-SCONNA
M_C_CPU0_SA_DQS_DN<9>    J6               200      SCONN288_ADR50001P003C01-SCONNA
M_C_CPU0_SA_DQS_DN<9>    U2               AH55     SOCKET4677_AZIFS054P001C01-SOCA
M_C_CPU0_SA_DQS_DP<0>    J5               11       SCONN288_ADR50001P013C01-SCONNA
M_C_CPU0_SA_DQS_DP<0>    J6               11       SCONN288_ADR50001P003C01-SCONNA
M_C_CPU0_SA_DQS_DP<0>    U2               U76      SOCKET4677_AZIFS054P001C01-SOCA
M_C_CPU0_SA_DQS_DP<1>    J5               22       SCONN288_ADR50001P013C01-SCONNA
M_C_CPU0_SA_DQS_DP<1>    J6               22       SCONN288_ADR50001P003C01-SCONNA
M_C_CPU0_SA_DQS_DP<1>    U2               AD67     SOCKET4677_AZIFS054P001C01-SOCA
M_C_CPU0_SA_DQS_DP<2>    J5               33       SCONN288_ADR50001P013C01-SCONNA
M_C_CPU0_SA_DQS_DP<2>    J6               33       SCONN288_ADR50001P003C01-SCONNA
M_C_CPU0_SA_DQS_DP<2>    U2               U64      SOCKET4677_AZIFS054P001C01-SOCA
M_C_CPU0_SA_DQS_DP<3>    J5               44       SCONN288_ADR50001P013C01-SCONNA
M_C_CPU0_SA_DQS_DP<3>    J6               44       SCONN288_ADR50001P003C01-SCONNA
M_C_CPU0_SA_DQS_DP<3>    U2               AD61     SOCKET4677_AZIFS054P001C01-SOCA
M_C_CPU0_SA_DQS_DP<4>    J5               55       SCONN288_ADR50001P013C01-SCONNA
M_C_CPU0_SA_DQS_DP<4>    J6               55       SCONN288_ADR50001P003C01-SCONNA
M_C_CPU0_SA_DQS_DP<4>    U2               AB55     SOCKET4677_AZIFS054P001C01-SOCA
M_C_CPU0_SA_DQS_DP<5>    J5               157      SCONN288_ADR50001P013C01-SCONNA
M_C_CPU0_SA_DQS_DP<5>    J6               157      SCONN288_ADR50001P003C01-SCONNA
M_C_CPU0_SA_DQS_DP<5>    U2               AA76     SOCKET4677_AZIFS054P001C01-SOCA
M_C_CPU0_SA_DQS_DP<6>    J5               168      SCONN288_ADR50001P013C01-SCONNA
M_C_CPU0_SA_DQS_DP<6>    J6               168      SCONN288_ADR50001P003C01-SCONNA
M_C_CPU0_SA_DQS_DP<6>    U2               AF67     SOCKET4677_AZIFS054P001C01-SOCA
M_C_CPU0_SA_DQS_DP<7>    J5               179      SCONN288_ADR50001P013C01-SCONNA
M_C_CPU0_SA_DQS_DP<7>    J6               179      SCONN288_ADR50001P003C01-SCONNA
M_C_CPU0_SA_DQS_DP<7>    U2               W64      SOCKET4677_AZIFS054P001C01-SOCA
M_C_CPU0_SA_DQS_DP<8>    J5               190      SCONN288_ADR50001P013C01-SCONNA
M_C_CPU0_SA_DQS_DP<8>    J6               190      SCONN288_ADR50001P003C01-SCONNA
M_C_CPU0_SA_DQS_DP<8>    U2               AH61     SOCKET4677_AZIFS054P001C01-SOCA
M_C_CPU0_SA_DQS_DP<9>    J5               201      SCONN288_ADR50001P013C01-SCONNA
M_C_CPU0_SA_DQS_DP<9>    J6               201      SCONN288_ADR50001P003C01-SCONNA
M_C_CPU0_SA_DQS_DP<9>    U2               AF55     SOCKET4677_AZIFS054P001C01-SOCA
M_C_CPU0_SA_PAR          J5               74       SCONN288_ADR50001P013C01-SCONNA
M_C_CPU0_SA_PAR          J6               74       SCONN288_ADR50001P003C01-SCONNA
M_C_CPU0_SA_PAR          U2               T47      SOCKET4677_AZIFS054P001C01-SOCA
M_C_CPU0_SA_RSP<0>       J5               86       SCONN288_ADR50001P013C01-SCONNA
M_C_CPU0_SA_RSP<0>       U2               AC48     SOCKET4677_AZIFS054P001C01-SOCA
M_C_CPU0_SA_RSP<1>       J6               86       SCONN288_ADR50001P003C01-SCONNA
M_C_CPU0_SA_RSP<1>       U2               AD47     SOCKET4677_AZIFS054P001C01-SOCA
M_C_CPU0_SB_CA<0>        J5               76       SCONN288_ADR50001P013C01-SCONNA
M_C_CPU0_SB_CA<0>        J6               76       SCONN288_ADR50001P003C01-SCONNA
M_C_CPU0_SB_CA<0>        U2               W48      SOCKET4677_AZIFS054P001C01-SOCA
M_C_CPU0_SB_CA<1>        J5               221      SCONN288_ADR50001P013C01-SCONNA
M_C_CPU0_SB_CA<1>        J6               221      SCONN288_ADR50001P003C01-SCONNA
M_C_CPU0_SB_CA<1>        U2               Y47      SOCKET4677_AZIFS054P001C01-SOCA
M_C_CPU0_SB_CA<2>        J5               78       SCONN288_ADR50001P013C01-SCONNA
M_C_CPU0_SB_CA<2>        J6               78       SCONN288_ADR50001P003C01-SCONNA
M_C_CPU0_SB_CA<2>        U2               U41      SOCKET4677_AZIFS054P001C01-SOCA
M_C_CPU0_SB_CA<3>        J5               223      SCONN288_ADR50001P013C01-SCONNA
M_C_CPU0_SB_CA<3>        J6               223      SCONN288_ADR50001P003C01-SCONNA
M_C_CPU0_SB_CA<3>        U2               W41      SOCKET4677_AZIFS054P001C01-SOCA
M_C_CPU0_SB_CA<4>        J5               80       SCONN288_ADR50001P013C01-SCONNA
M_C_CPU0_SB_CA<4>        J6               80       SCONN288_ADR50001P003C01-SCONNA
M_C_CPU0_SB_CA<4>        U2               T40      SOCKET4677_AZIFS054P001C01-SOCA
M_C_CPU0_SB_CA<5>        J5               225      SCONN288_ADR50001P013C01-SCONNA
M_C_CPU0_SB_CA<5>        J6               225      SCONN288_ADR50001P003C01-SCONNA
M_C_CPU0_SB_CA<5>        U2               Y40      SOCKET4677_AZIFS054P001C01-SOCA
M_C_CPU0_SB_CA<6>        J5               82       SCONN288_ADR50001P013C01-SCONNA
M_C_CPU0_SB_CA<6>        J6               82       SCONN288_ADR50001P003C01-SCONNA
M_C_CPU0_SB_CA<6>        U2               R39      SOCKET4677_AZIFS054P001C01-SOCA
M_C_CPU0_SB_CB<0>        J5               96       SCONN288_ADR50001P013C01-SCONNA
M_C_CPU0_SB_CB<0>        J6               96       SCONN288_ADR50001P003C01-SCONNA
M_C_CPU0_SB_CB<0>        U2               T32      SOCKET4677_AZIFS054P001C01-SOCA
M_C_CPU0_SB_CB<1>        J5               98       SCONN288_ADR50001P013C01-SCONNA
M_C_CPU0_SB_CB<1>        J6               98       SCONN288_ADR50001P003C01-SCONNA
M_C_CPU0_SB_CB<1>        U2               U31      SOCKET4677_AZIFS054P001C01-SOCA
M_C_CPU0_SB_CB<2>        J5               241      SCONN288_ADR50001P013C01-SCONNA
M_C_CPU0_SB_CB<2>        J6               241      SCONN288_ADR50001P003C01-SCONNA
M_C_CPU0_SB_CB<2>        U2               Y32      SOCKET4677_AZIFS054P001C01-SOCA
M_C_CPU0_SB_CB<3>        J5               243      SCONN288_ADR50001P013C01-SCONNA
M_C_CPU0_SB_CB<3>        J6               243      SCONN288_ADR50001P003C01-SCONNA
M_C_CPU0_SB_CB<3>        U2               W31      SOCKET4677_AZIFS054P001C01-SOCA
M_C_CPU0_SB_CB<4>        J5               89       SCONN288_ADR50001P013C01-SCONNA
M_C_CPU0_SB_CB<4>        J6               89       SCONN288_ADR50001P003C01-SCONNA
M_C_CPU0_SB_CB<4>        U2               U35      SOCKET4677_AZIFS054P001C01-SOCA
M_C_CPU0_SB_CB<5>        J5               91       SCONN288_ADR50001P013C01-SCONNA
M_C_CPU0_SB_CB<5>        J6               91       SCONN288_ADR50001P003C01-SCONNA
M_C_CPU0_SB_CB<5>        U2               T34      SOCKET4677_AZIFS054P001C01-SOCA
M_C_CPU0_SB_CB<6>        J5               234      SCONN288_ADR50001P013C01-SCONNA
M_C_CPU0_SB_CB<6>        J6               234      SCONN288_ADR50001P003C01-SCONNA
M_C_CPU0_SB_CB<6>        U2               W35      SOCKET4677_AZIFS054P001C01-SOCA
M_C_CPU0_SB_CB<7>        J5               236      SCONN288_ADR50001P013C01-SCONNA
M_C_CPU0_SB_CB<7>        J6               236      SCONN288_ADR50001P003C01-SCONNA
M_C_CPU0_SB_CB<7>        U2               Y34      SOCKET4677_AZIFS054P001C01-SOCA
M_C_CPU0_SB_CS_N<0>      J5               84       SCONN288_ADR50001P013C01-SCONNA
M_C_CPU0_SB_CS_N<0>      U2               T38      SOCKET4677_AZIFS054P001C01-SOCA
M_C_CPU0_SB_CS_N<1>      J5               229      SCONN288_ADR50001P013C01-SCONNA
M_C_CPU0_SB_CS_N<1>      U2               U37      SOCKET4677_AZIFS054P001C01-SOCA
M_C_CPU0_SB_CS_N<2>      J6               84       SCONN288_ADR50001P003C01-SCONNA
M_C_CPU0_SB_CS_N<2>      U2               Y38      SOCKET4677_AZIFS054P001C01-SOCA
M_C_CPU0_SB_CS_N<3>      J6               229      SCONN288_ADR50001P003C01-SCONNA
M_C_CPU0_SB_CS_N<3>      U2               W37      SOCKET4677_AZIFS054P001C01-SOCA
M_C_CPU0_SB_DQ<0>        J5               100      SCONN288_ADR50001P013C01-SCONNA
M_C_CPU0_SB_DQ<0>        J6               100      SCONN288_ADR50001P003C01-SCONNA
M_C_CPU0_SB_DQ<0>        U2               AD38     SOCKET4677_AZIFS054P001C01-SOCA
M_C_CPU0_SB_DQ<1>        J5               102      SCONN288_ADR50001P013C01-SCONNA
M_C_CPU0_SB_DQ<1>        J6               102      SCONN288_ADR50001P003C01-SCONNA
M_C_CPU0_SB_DQ<1>        U2               AC37     SOCKET4677_AZIFS054P001C01-SOCA
M_C_CPU0_SB_DQ<2>        J5               245      SCONN288_ADR50001P013C01-SCONNA
M_C_CPU0_SB_DQ<2>        J6               245      SCONN288_ADR50001P003C01-SCONNA
M_C_CPU0_SB_DQ<2>        U2               AF38     SOCKET4677_AZIFS054P001C01-SOCA
M_C_CPU0_SB_DQ<3>        J5               247      SCONN288_ADR50001P013C01-SCONNA
M_C_CPU0_SB_DQ<3>        J6               247      SCONN288_ADR50001P003C01-SCONNA
M_C_CPU0_SB_DQ<3>        U2               AG37     SOCKET4677_AZIFS054P001C01-SOCA
M_C_CPU0_SB_DQ<4>        J5               107      SCONN288_ADR50001P013C01-SCONNA
M_C_CPU0_SB_DQ<4>        J6               107      SCONN288_ADR50001P003C01-SCONNA
M_C_CPU0_SB_DQ<4>        U2               AC35     SOCKET4677_AZIFS054P001C01-SOCA
M_C_CPU0_SB_DQ<5>        J5               109      SCONN288_ADR50001P013C01-SCONNA
M_C_CPU0_SB_DQ<5>        J6               109      SCONN288_ADR50001P003C01-SCONNA
M_C_CPU0_SB_DQ<5>        U2               AD34     SOCKET4677_AZIFS054P001C01-SOCA
M_C_CPU0_SB_DQ<6>        J5               252      SCONN288_ADR50001P013C01-SCONNA
M_C_CPU0_SB_DQ<6>        J6               252      SCONN288_ADR50001P003C01-SCONNA
M_C_CPU0_SB_DQ<6>        U2               AG35     SOCKET4677_AZIFS054P001C01-SOCA
M_C_CPU0_SB_DQ<7>        J5               254      SCONN288_ADR50001P013C01-SCONNA
M_C_CPU0_SB_DQ<7>        J6               254      SCONN288_ADR50001P003C01-SCONNA
M_C_CPU0_SB_DQ<7>        U2               AF34     SOCKET4677_AZIFS054P001C01-SOCA
M_C_CPU0_SB_DQ<8>        J5               111      SCONN288_ADR50001P013C01-SCONNA
M_C_CPU0_SB_DQ<8>        J6               111      SCONN288_ADR50001P003C01-SCONNA
M_C_CPU0_SB_DQ<8>        U2               AD32     SOCKET4677_AZIFS054P001C01-SOCA
M_C_CPU0_SB_DQ<9>        J5               113      SCONN288_ADR50001P013C01-SCONNA
M_C_CPU0_SB_DQ<9>        J6               113      SCONN288_ADR50001P003C01-SCONNA
M_C_CPU0_SB_DQ<9>        U2               AC31     SOCKET4677_AZIFS054P001C01-SOCA
M_C_CPU0_SB_DQ<10>       J5               256      SCONN288_ADR50001P013C01-SCONNA
M_C_CPU0_SB_DQ<10>       J6               256      SCONN288_ADR50001P003C01-SCONNA
M_C_CPU0_SB_DQ<10>       U2               AF32     SOCKET4677_AZIFS054P001C01-SOCA
M_C_CPU0_SB_DQ<11>       J5               258      SCONN288_ADR50001P013C01-SCONNA
M_C_CPU0_SB_DQ<11>       J6               258      SCONN288_ADR50001P003C01-SCONNA
M_C_CPU0_SB_DQ<11>       U2               AG31     SOCKET4677_AZIFS054P001C01-SOCA
M_C_CPU0_SB_DQ<12>       J5               118      SCONN288_ADR50001P013C01-SCONNA
M_C_CPU0_SB_DQ<12>       J6               118      SCONN288_ADR50001P003C01-SCONNA
M_C_CPU0_SB_DQ<12>       U2               AC29     SOCKET4677_AZIFS054P001C01-SOCA
M_C_CPU0_SB_DQ<13>       J5               120      SCONN288_ADR50001P013C01-SCONNA
M_C_CPU0_SB_DQ<13>       J6               120      SCONN288_ADR50001P003C01-SCONNA
M_C_CPU0_SB_DQ<13>       U2               AD28     SOCKET4677_AZIFS054P001C01-SOCA
M_C_CPU0_SB_DQ<14>       J5               263      SCONN288_ADR50001P013C01-SCONNA
M_C_CPU0_SB_DQ<14>       J6               263      SCONN288_ADR50001P003C01-SCONNA
M_C_CPU0_SB_DQ<14>       U2               AG29     SOCKET4677_AZIFS054P001C01-SOCA
M_C_CPU0_SB_DQ<15>       J5               265      SCONN288_ADR50001P013C01-SCONNA
M_C_CPU0_SB_DQ<15>       J6               265      SCONN288_ADR50001P003C01-SCONNA
M_C_CPU0_SB_DQ<15>       U2               AF28     SOCKET4677_AZIFS054P001C01-SOCA
M_C_CPU0_SB_DQ<16>       J5               122      SCONN288_ADR50001P013C01-SCONNA
M_C_CPU0_SB_DQ<16>       J6               122      SCONN288_ADR50001P003C01-SCONNA
M_C_CPU0_SB_DQ<16>       U2               U23      SOCKET4677_AZIFS054P001C01-SOCA
M_C_CPU0_SB_DQ<17>       J5               124      SCONN288_ADR50001P013C01-SCONNA
M_C_CPU0_SB_DQ<17>       J6               124      SCONN288_ADR50001P003C01-SCONNA
M_C_CPU0_SB_DQ<17>       U2               T22      SOCKET4677_AZIFS054P001C01-SOCA
M_C_CPU0_SB_DQ<18>       J5               267      SCONN288_ADR50001P013C01-SCONNA
M_C_CPU0_SB_DQ<18>       J6               267      SCONN288_ADR50001P003C01-SCONNA
M_C_CPU0_SB_DQ<18>       U2               W23      SOCKET4677_AZIFS054P001C01-SOCA
M_C_CPU0_SB_DQ<19>       J5               269      SCONN288_ADR50001P013C01-SCONNA
M_C_CPU0_SB_DQ<19>       J6               269      SCONN288_ADR50001P003C01-SCONNA
M_C_CPU0_SB_DQ<19>       U2               Y22      SOCKET4677_AZIFS054P001C01-SOCA
M_C_CPU0_SB_DQ<20>       J5               129      SCONN288_ADR50001P013C01-SCONNA
M_C_CPU0_SB_DQ<20>       J6               129      SCONN288_ADR50001P003C01-SCONNA
M_C_CPU0_SB_DQ<20>       U2               T20      SOCKET4677_AZIFS054P001C01-SOCA
M_C_CPU0_SB_DQ<21>       J5               131      SCONN288_ADR50001P013C01-SCONNA
M_C_CPU0_SB_DQ<21>       J6               131      SCONN288_ADR50001P003C01-SCONNA
M_C_CPU0_SB_DQ<21>       U2               U19      SOCKET4677_AZIFS054P001C01-SOCA
M_C_CPU0_SB_DQ<22>       J5               274      SCONN288_ADR50001P013C01-SCONNA
M_C_CPU0_SB_DQ<22>       J6               274      SCONN288_ADR50001P003C01-SCONNA
M_C_CPU0_SB_DQ<22>       U2               Y20      SOCKET4677_AZIFS054P001C01-SOCA
M_C_CPU0_SB_DQ<23>       J5               276      SCONN288_ADR50001P013C01-SCONNA
M_C_CPU0_SB_DQ<23>       J6               276      SCONN288_ADR50001P003C01-SCONNA
M_C_CPU0_SB_DQ<23>       U2               W19      SOCKET4677_AZIFS054P001C01-SOCA
M_C_CPU0_SB_DQ<24>       J5               133      SCONN288_ADR50001P013C01-SCONNA
M_C_CPU0_SB_DQ<24>       J6               133      SCONN288_ADR50001P003C01-SCONNA
M_C_CPU0_SB_DQ<24>       U2               AD20     SOCKET4677_AZIFS054P001C01-SOCA
M_C_CPU0_SB_DQ<25>       J5               135      SCONN288_ADR50001P013C01-SCONNA
M_C_CPU0_SB_DQ<25>       J6               135      SCONN288_ADR50001P003C01-SCONNA
M_C_CPU0_SB_DQ<25>       U2               AC19     SOCKET4677_AZIFS054P001C01-SOCA
M_C_CPU0_SB_DQ<26>       J5               278      SCONN288_ADR50001P013C01-SCONNA
M_C_CPU0_SB_DQ<26>       J6               278      SCONN288_ADR50001P003C01-SCONNA
M_C_CPU0_SB_DQ<26>       U2               AF20     SOCKET4677_AZIFS054P001C01-SOCA
M_C_CPU0_SB_DQ<27>       J5               280      SCONN288_ADR50001P013C01-SCONNA
M_C_CPU0_SB_DQ<27>       J6               280      SCONN288_ADR50001P003C01-SCONNA
M_C_CPU0_SB_DQ<27>       U2               AG19     SOCKET4677_AZIFS054P001C01-SOCA
M_C_CPU0_SB_DQ<28>       J5               140      SCONN288_ADR50001P013C01-SCONNA
M_C_CPU0_SB_DQ<28>       J6               140      SCONN288_ADR50001P003C01-SCONNA
M_C_CPU0_SB_DQ<28>       U2               AA17     SOCKET4677_AZIFS054P001C01-SOCA
M_C_CPU0_SB_DQ<29>       J5               142      SCONN288_ADR50001P013C01-SCONNA
M_C_CPU0_SB_DQ<29>       J6               142      SCONN288_ADR50001P003C01-SCONNA
M_C_CPU0_SB_DQ<29>       U2               AG17     SOCKET4677_AZIFS054P001C01-SOCA
M_C_CPU0_SB_DQ<30>       J5               285      SCONN288_ADR50001P013C01-SCONNA
M_C_CPU0_SB_DQ<30>       J6               285      SCONN288_ADR50001P003C01-SCONNA
M_C_CPU0_SB_DQ<30>       U2               AC17     SOCKET4677_AZIFS054P001C01-SOCA
M_C_CPU0_SB_DQ<31>       J5               287      SCONN288_ADR50001P013C01-SCONNA
M_C_CPU0_SB_DQ<31>       J6               287      SCONN288_ADR50001P003C01-SCONNA
M_C_CPU0_SB_DQ<31>       U2               AJ17     SOCKET4677_AZIFS054P001C01-SOCA
M_C_CPU0_SB_DQS_DN<0>    J5               105      SCONN288_ADR50001P013C01-SCONNA
M_C_CPU0_SB_DQS_DN<0>    J6               105      SCONN288_ADR50001P003C01-SCONNA
M_C_CPU0_SB_DQS_DN<0>    U2               AB36     SOCKET4677_AZIFS054P001C01-SOCA
M_C_CPU0_SB_DQS_DN<1>    J5               116      SCONN288_ADR50001P013C01-SCONNA
M_C_CPU0_SB_DQS_DN<1>    J6               116      SCONN288_ADR50001P003C01-SCONNA
M_C_CPU0_SB_DQS_DN<1>    U2               AB30     SOCKET4677_AZIFS054P001C01-SOCA
M_C_CPU0_SB_DQS_DN<2>    J5               127      SCONN288_ADR50001P013C01-SCONNA
M_C_CPU0_SB_DQS_DN<2>    J6               127      SCONN288_ADR50001P003C01-SCONNA
M_C_CPU0_SB_DQS_DN<2>    U2               R21      SOCKET4677_AZIFS054P001C01-SOCA
M_C_CPU0_SB_DQS_DN<3>    J5               138      SCONN288_ADR50001P013C01-SCONNA
M_C_CPU0_SB_DQS_DN<3>    J6               138      SCONN288_ADR50001P003C01-SCONNA
M_C_CPU0_SB_DQS_DN<3>    U2               AB18     SOCKET4677_AZIFS054P001C01-SOCA
M_C_CPU0_SB_DQS_DN<4>    J5               238      SCONN288_ADR50001P013C01-SCONNA
M_C_CPU0_SB_DQS_DN<4>    J6               238      SCONN288_ADR50001P003C01-SCONNA
M_C_CPU0_SB_DQS_DN<4>    U2               W33      SOCKET4677_AZIFS054P001C01-SOCA
M_C_CPU0_SB_DQS_DN<5>    J5               249      SCONN288_ADR50001P013C01-SCONNA
M_C_CPU0_SB_DQS_DN<5>    J6               249      SCONN288_ADR50001P003C01-SCONNA
M_C_CPU0_SB_DQS_DN<5>    U2               AF36     SOCKET4677_AZIFS054P001C01-SOCA
M_C_CPU0_SB_DQS_DN<6>    J5               260      SCONN288_ADR50001P013C01-SCONNA
M_C_CPU0_SB_DQS_DN<6>    J6               260      SCONN288_ADR50001P003C01-SCONNA
M_C_CPU0_SB_DQS_DN<6>    U2               AF30     SOCKET4677_AZIFS054P001C01-SOCA
M_C_CPU0_SB_DQS_DN<7>    J5               271      SCONN288_ADR50001P013C01-SCONNA
M_C_CPU0_SB_DQS_DN<7>    J6               271      SCONN288_ADR50001P003C01-SCONNA
M_C_CPU0_SB_DQS_DN<7>    U2               W21      SOCKET4677_AZIFS054P001C01-SOCA
M_C_CPU0_SB_DQS_DN<8>    J5               282      SCONN288_ADR50001P013C01-SCONNA
M_C_CPU0_SB_DQS_DN<8>    J6               282      SCONN288_ADR50001P003C01-SCONNA
M_C_CPU0_SB_DQS_DN<8>    U2               AF18     SOCKET4677_AZIFS054P001C01-SOCA
M_C_CPU0_SB_DQS_DN<9>    J5               94       SCONN288_ADR50001P013C01-SCONNA
M_C_CPU0_SB_DQS_DN<9>    J6               94       SCONN288_ADR50001P003C01-SCONNA
M_C_CPU0_SB_DQS_DN<9>    U2               R33      SOCKET4677_AZIFS054P001C01-SOCA
M_C_CPU0_SB_DQS_DP<0>    J5               104      SCONN288_ADR50001P013C01-SCONNA
M_C_CPU0_SB_DQS_DP<0>    J6               104      SCONN288_ADR50001P003C01-SCONNA
M_C_CPU0_SB_DQS_DP<0>    U2               AD36     SOCKET4677_AZIFS054P001C01-SOCA
M_C_CPU0_SB_DQS_DP<1>    J5               115      SCONN288_ADR50001P013C01-SCONNA
M_C_CPU0_SB_DQS_DP<1>    J6               115      SCONN288_ADR50001P003C01-SCONNA
M_C_CPU0_SB_DQS_DP<1>    U2               AD30     SOCKET4677_AZIFS054P001C01-SOCA
M_C_CPU0_SB_DQS_DP<2>    J5               126      SCONN288_ADR50001P013C01-SCONNA
M_C_CPU0_SB_DQS_DP<2>    J6               126      SCONN288_ADR50001P003C01-SCONNA
M_C_CPU0_SB_DQS_DP<2>    U2               U21      SOCKET4677_AZIFS054P001C01-SOCA
M_C_CPU0_SB_DQS_DP<3>    J5               137      SCONN288_ADR50001P013C01-SCONNA
M_C_CPU0_SB_DQS_DP<3>    J6               137      SCONN288_ADR50001P003C01-SCONNA
M_C_CPU0_SB_DQS_DP<3>    U2               AD18     SOCKET4677_AZIFS054P001C01-SOCA
M_C_CPU0_SB_DQS_DP<4>    J5               239      SCONN288_ADR50001P013C01-SCONNA
M_C_CPU0_SB_DQS_DP<4>    J6               239      SCONN288_ADR50001P003C01-SCONNA
M_C_CPU0_SB_DQS_DP<4>    U2               AA33     SOCKET4677_AZIFS054P001C01-SOCA
M_C_CPU0_SB_DQS_DP<5>    J5               250      SCONN288_ADR50001P013C01-SCONNA
M_C_CPU0_SB_DQS_DP<5>    J6               250      SCONN288_ADR50001P003C01-SCONNA
M_C_CPU0_SB_DQS_DP<5>    U2               AH36     SOCKET4677_AZIFS054P001C01-SOCA
M_C_CPU0_SB_DQS_DP<6>    J5               261      SCONN288_ADR50001P013C01-SCONNA
M_C_CPU0_SB_DQS_DP<6>    J6               261      SCONN288_ADR50001P003C01-SCONNA
M_C_CPU0_SB_DQS_DP<6>    U2               AH30     SOCKET4677_AZIFS054P001C01-SOCA
M_C_CPU0_SB_DQS_DP<7>    J5               272      SCONN288_ADR50001P013C01-SCONNA
M_C_CPU0_SB_DQS_DP<7>    J6               272      SCONN288_ADR50001P003C01-SCONNA
M_C_CPU0_SB_DQS_DP<7>    U2               AA21     SOCKET4677_AZIFS054P001C01-SOCA
M_C_CPU0_SB_DQS_DP<8>    J5               283      SCONN288_ADR50001P013C01-SCONNA
M_C_CPU0_SB_DQS_DP<8>    J6               283      SCONN288_ADR50001P003C01-SCONNA
M_C_CPU0_SB_DQS_DP<8>    U2               AH18     SOCKET4677_AZIFS054P001C01-SOCA
M_C_CPU0_SB_DQS_DP<9>    J5               93       SCONN288_ADR50001P013C01-SCONNA
M_C_CPU0_SB_DQS_DP<9>    J6               93       SCONN288_ADR50001P003C01-SCONNA
M_C_CPU0_SB_DQS_DP<9>    U2               U33      SOCKET4677_AZIFS054P001C01-SOCA
M_C_CPU0_SB_PAR          J5               227      SCONN288_ADR50001P013C01-SCONNA
M_C_CPU0_SB_PAR          J6               227      SCONN288_ADR50001P003C01-SCONNA
M_C_CPU0_SB_PAR          U2               AA39     SOCKET4677_AZIFS054P001C01-SOCA
M_C_CPU0_SB_RSP<0>       J5               87       SCONN288_ADR50001P013C01-SCONNA
M_C_CPU0_SB_RSP<0>       U2               AG48     SOCKET4677_AZIFS054P001C01-SOCA
M_C_CPU0_SB_RSP<1>       J6               87       SCONN288_ADR50001P003C01-SCONNA
M_C_CPU0_SB_RSP<1>       U2               AF47     SOCKET4677_AZIFS054P001C01-SOCA
M_C_CPU1_ALERT_N         J21              62       SCONN288_ADR50001P013C01-SCONNA
M_C_CPU1_ALERT_N         J22              62       SCONN288_ADR50001P003C01-SCONNA
M_C_CPU1_ALERT_N         U1               AT47     SOCKET4677_AZIFS054P001C01-SOCA
M_C_CPU1_CLK_DN<0>       J21              218      SCONN288_ADR50001P013C01-SCONNA
M_C_CPU1_CLK_DN<0>       U1               AB49     SOCKET4677_AZIFS054P001C01-SOCA
M_C_CPU1_CLK_DN<1>       J22              218      SCONN288_ADR50001P003C01-SCONNA
M_C_CPU1_CLK_DN<1>       U1               AF49     SOCKET4677_AZIFS054P001C01-SOCA
M_C_CPU1_CLK_DP<0>       J21              217      SCONN288_ADR50001P013C01-SCONNA
M_C_CPU1_CLK_DP<0>       U1               AD49     SOCKET4677_AZIFS054P001C01-SOCA
M_C_CPU1_CLK_DP<1>       J22              217      SCONN288_ADR50001P003C01-SCONNA
M_C_CPU1_CLK_DP<1>       U1               AH49     SOCKET4677_AZIFS054P001C01-SOCA
M_C_CPU1_SA_CA<0>        J21              66       SCONN288_ADR50001P013C01-SCONNA
M_C_CPU1_SA_CA<0>        J22              66       SCONN288_ADR50001P003C01-SCONNA
M_C_CPU1_SA_CA<0>        U1               R52      SOCKET4677_AZIFS054P001C01-SOCA
M_C_CPU1_SA_CA<1>        J21              211      SCONN288_ADR50001P013C01-SCONNA
M_C_CPU1_SA_CA<1>        J22              211      SCONN288_ADR50001P003C01-SCONNA
M_C_CPU1_SA_CA<1>        U1               AA52     SOCKET4677_AZIFS054P001C01-SOCA
M_C_CPU1_SA_CA<2>        J21              68       SCONN288_ADR50001P013C01-SCONNA
M_C_CPU1_SA_CA<2>        J22              68       SCONN288_ADR50001P003C01-SCONNA
M_C_CPU1_SA_CA<2>        U1               T51      SOCKET4677_AZIFS054P001C01-SOCA
M_C_CPU1_SA_CA<3>        J21              213      SCONN288_ADR50001P013C01-SCONNA
M_C_CPU1_SA_CA<3>        J22              213      SCONN288_ADR50001P003C01-SCONNA
M_C_CPU1_SA_CA<3>        U1               Y51      SOCKET4677_AZIFS054P001C01-SOCA
M_C_CPU1_SA_CA<4>        J21              70       SCONN288_ADR50001P013C01-SCONNA
M_C_CPU1_SA_CA<4>        J22              70       SCONN288_ADR50001P003C01-SCONNA
M_C_CPU1_SA_CA<4>        U1               U50      SOCKET4677_AZIFS054P001C01-SOCA
M_C_CPU1_SA_CA<5>        J21              215      SCONN288_ADR50001P013C01-SCONNA
M_C_CPU1_SA_CA<5>        J22              215      SCONN288_ADR50001P003C01-SCONNA
M_C_CPU1_SA_CA<5>        U1               W50      SOCKET4677_AZIFS054P001C01-SOCA
M_C_CPU1_SA_CA<6>        J21              72       SCONN288_ADR50001P013C01-SCONNA
M_C_CPU1_SA_CA<6>        J22              72       SCONN288_ADR50001P003C01-SCONNA
M_C_CPU1_SA_CA<6>        U1               U48      SOCKET4677_AZIFS054P001C01-SOCA
M_C_CPU1_SA_CB<0>        J21              51       SCONN288_ADR50001P013C01-SCONNA
M_C_CPU1_SA_CB<0>        J22              51       SCONN288_ADR50001P003C01-SCONNA
M_C_CPU1_SA_CB<0>        U1               AD57     SOCKET4677_AZIFS054P001C01-SOCA
M_C_CPU1_SA_CB<1>        J21              53       SCONN288_ADR50001P013C01-SCONNA
M_C_CPU1_SA_CB<1>        J22              53       SCONN288_ADR50001P003C01-SCONNA
M_C_CPU1_SA_CB<1>        U1               AC56     SOCKET4677_AZIFS054P001C01-SOCA
M_C_CPU1_SA_CB<2>        J21              196      SCONN288_ADR50001P013C01-SCONNA
M_C_CPU1_SA_CB<2>        J22              196      SCONN288_ADR50001P003C01-SCONNA
M_C_CPU1_SA_CB<2>        U1               AF57     SOCKET4677_AZIFS054P001C01-SOCA
M_C_CPU1_SA_CB<3>        J21              198      SCONN288_ADR50001P013C01-SCONNA
M_C_CPU1_SA_CB<3>        J22              198      SCONN288_ADR50001P003C01-SCONNA
M_C_CPU1_SA_CB<3>        U1               AG56     SOCKET4677_AZIFS054P001C01-SOCA
M_C_CPU1_SA_CB<4>        J21              58       SCONN288_ADR50001P013C01-SCONNA
M_C_CPU1_SA_CB<4>        J22              58       SCONN288_ADR50001P003C01-SCONNA
M_C_CPU1_SA_CB<4>        U1               AC54     SOCKET4677_AZIFS054P001C01-SOCA
M_C_CPU1_SA_CB<5>        J21              60       SCONN288_ADR50001P013C01-SCONNA
M_C_CPU1_SA_CB<5>        J22              60       SCONN288_ADR50001P003C01-SCONNA
M_C_CPU1_SA_CB<5>        U1               AD53     SOCKET4677_AZIFS054P001C01-SOCA
M_C_CPU1_SA_CB<6>        J21              203      SCONN288_ADR50001P013C01-SCONNA
M_C_CPU1_SA_CB<6>        J22              203      SCONN288_ADR50001P003C01-SCONNA
M_C_CPU1_SA_CB<6>        U1               AG54     SOCKET4677_AZIFS054P001C01-SOCA
M_C_CPU1_SA_CB<7>        J21              205      SCONN288_ADR50001P013C01-SCONNA
M_C_CPU1_SA_CB<7>        J22              205      SCONN288_ADR50001P003C01-SCONNA
M_C_CPU1_SA_CB<7>        U1               AF53     SOCKET4677_AZIFS054P001C01-SOCA
M_C_CPU1_SA_CS_N<0>      J21              64       SCONN288_ADR50001P013C01-SCONNA
M_C_CPU1_SA_CS_N<0>      U1               U54      SOCKET4677_AZIFS054P001C01-SOCA
M_C_CPU1_SA_CS_N<1>      J21              209      SCONN288_ADR50001P013C01-SCONNA
M_C_CPU1_SA_CS_N<1>      U1               T53      SOCKET4677_AZIFS054P001C01-SOCA
M_C_CPU1_SA_CS_N<2>      J22              64       SCONN288_ADR50001P003C01-SCONNA
M_C_CPU1_SA_CS_N<2>      U1               W54      SOCKET4677_AZIFS054P001C01-SOCA
M_C_CPU1_SA_CS_N<3>      J22              209      SCONN288_ADR50001P003C01-SCONNA
M_C_CPU1_SA_CS_N<3>      U1               Y53      SOCKET4677_AZIFS054P001C01-SOCA
M_C_CPU1_SA_DQ<0>        J21              7        SCONN288_ADR50001P013C01-SCONNA
M_C_CPU1_SA_DQ<0>        J22              7        SCONN288_ADR50001P003C01-SCONNA
M_C_CPU1_SA_DQ<0>        U1               U78      SOCKET4677_AZIFS054P001C01-SOCA
M_C_CPU1_SA_DQ<1>        J21              9        SCONN288_ADR50001P013C01-SCONNA
M_C_CPU1_SA_DQ<1>        J22              9        SCONN288_ADR50001P003C01-SCONNA
M_C_CPU1_SA_DQ<1>        U1               T77      SOCKET4677_AZIFS054P001C01-SOCA
M_C_CPU1_SA_DQ<2>        J21              152      SCONN288_ADR50001P013C01-SCONNA
M_C_CPU1_SA_DQ<2>        J22              152      SCONN288_ADR50001P003C01-SCONNA
M_C_CPU1_SA_DQ<2>        U1               W78      SOCKET4677_AZIFS054P001C01-SOCA
M_C_CPU1_SA_DQ<3>        J21              154      SCONN288_ADR50001P013C01-SCONNA
M_C_CPU1_SA_DQ<3>        J22              154      SCONN288_ADR50001P003C01-SCONNA
M_C_CPU1_SA_DQ<3>        U1               Y77      SOCKET4677_AZIFS054P001C01-SOCA
M_C_CPU1_SA_DQ<4>        J21              14       SCONN288_ADR50001P013C01-SCONNA
M_C_CPU1_SA_DQ<4>        J22              14       SCONN288_ADR50001P003C01-SCONNA
M_C_CPU1_SA_DQ<4>        U1               T75      SOCKET4677_AZIFS054P001C01-SOCA
M_C_CPU1_SA_DQ<5>        J21              16       SCONN288_ADR50001P013C01-SCONNA
M_C_CPU1_SA_DQ<5>        J22              16       SCONN288_ADR50001P003C01-SCONNA
M_C_CPU1_SA_DQ<5>        U1               U74      SOCKET4677_AZIFS054P001C01-SOCA
M_C_CPU1_SA_DQ<6>        J21              159      SCONN288_ADR50001P013C01-SCONNA
M_C_CPU1_SA_DQ<6>        J22              159      SCONN288_ADR50001P003C01-SCONNA
M_C_CPU1_SA_DQ<6>        U1               Y75      SOCKET4677_AZIFS054P001C01-SOCA
M_C_CPU1_SA_DQ<7>        J21              161      SCONN288_ADR50001P013C01-SCONNA
M_C_CPU1_SA_DQ<7>        J22              161      SCONN288_ADR50001P003C01-SCONNA
M_C_CPU1_SA_DQ<7>        U1               W74      SOCKET4677_AZIFS054P001C01-SOCA
M_C_CPU1_SA_DQ<8>        J21              18       SCONN288_ADR50001P013C01-SCONNA
M_C_CPU1_SA_DQ<8>        J22              18       SCONN288_ADR50001P003C01-SCONNA
M_C_CPU1_SA_DQ<8>        U1               AD69     SOCKET4677_AZIFS054P001C01-SOCA
M_C_CPU1_SA_DQ<9>        J21              20       SCONN288_ADR50001P013C01-SCONNA
M_C_CPU1_SA_DQ<9>        J22              20       SCONN288_ADR50001P003C01-SCONNA
M_C_CPU1_SA_DQ<9>        U1               AC68     SOCKET4677_AZIFS054P001C01-SOCA
M_C_CPU1_SA_DQ<10>       J21              163      SCONN288_ADR50001P013C01-SCONNA
M_C_CPU1_SA_DQ<10>       J22              163      SCONN288_ADR50001P003C01-SCONNA
M_C_CPU1_SA_DQ<10>       U1               AF69     SOCKET4677_AZIFS054P001C01-SOCA
M_C_CPU1_SA_DQ<11>       J21              165      SCONN288_ADR50001P013C01-SCONNA
M_C_CPU1_SA_DQ<11>       J22              165      SCONN288_ADR50001P003C01-SCONNA
M_C_CPU1_SA_DQ<11>       U1               AG68     SOCKET4677_AZIFS054P001C01-SOCA
M_C_CPU1_SA_DQ<12>       J21              25       SCONN288_ADR50001P013C01-SCONNA
M_C_CPU1_SA_DQ<12>       J22              25       SCONN288_ADR50001P003C01-SCONNA
M_C_CPU1_SA_DQ<12>       U1               AC66     SOCKET4677_AZIFS054P001C01-SOCA
M_C_CPU1_SA_DQ<13>       J21              27       SCONN288_ADR50001P013C01-SCONNA
M_C_CPU1_SA_DQ<13>       J22              27       SCONN288_ADR50001P003C01-SCONNA
M_C_CPU1_SA_DQ<13>       U1               AD65     SOCKET4677_AZIFS054P001C01-SOCA
M_C_CPU1_SA_DQ<14>       J21              170      SCONN288_ADR50001P013C01-SCONNA
M_C_CPU1_SA_DQ<14>       J22              170      SCONN288_ADR50001P003C01-SCONNA
M_C_CPU1_SA_DQ<14>       U1               AG66     SOCKET4677_AZIFS054P001C01-SOCA
M_C_CPU1_SA_DQ<15>       J21              172      SCONN288_ADR50001P013C01-SCONNA
M_C_CPU1_SA_DQ<15>       J22              172      SCONN288_ADR50001P003C01-SCONNA
M_C_CPU1_SA_DQ<15>       U1               AF65     SOCKET4677_AZIFS054P001C01-SOCA
M_C_CPU1_SA_DQ<16>       J21              29       SCONN288_ADR50001P013C01-SCONNA
M_C_CPU1_SA_DQ<16>       J22              29       SCONN288_ADR50001P003C01-SCONNA
M_C_CPU1_SA_DQ<16>       U1               U66      SOCKET4677_AZIFS054P001C01-SOCA
M_C_CPU1_SA_DQ<17>       J21              31       SCONN288_ADR50001P013C01-SCONNA
M_C_CPU1_SA_DQ<17>       J22              31       SCONN288_ADR50001P003C01-SCONNA
M_C_CPU1_SA_DQ<17>       U1               T65      SOCKET4677_AZIFS054P001C01-SOCA
M_C_CPU1_SA_DQ<18>       J21              174      SCONN288_ADR50001P013C01-SCONNA
M_C_CPU1_SA_DQ<18>       J22              174      SCONN288_ADR50001P003C01-SCONNA
M_C_CPU1_SA_DQ<18>       U1               W66      SOCKET4677_AZIFS054P001C01-SOCA
M_C_CPU1_SA_DQ<19>       J21              176      SCONN288_ADR50001P013C01-SCONNA
M_C_CPU1_SA_DQ<19>       J22              176      SCONN288_ADR50001P003C01-SCONNA
M_C_CPU1_SA_DQ<19>       U1               Y65      SOCKET4677_AZIFS054P001C01-SOCA
M_C_CPU1_SA_DQ<20>       J21              36       SCONN288_ADR50001P013C01-SCONNA
M_C_CPU1_SA_DQ<20>       J22              36       SCONN288_ADR50001P003C01-SCONNA
M_C_CPU1_SA_DQ<20>       U1               T63      SOCKET4677_AZIFS054P001C01-SOCA
M_C_CPU1_SA_DQ<21>       J21              38       SCONN288_ADR50001P013C01-SCONNA
M_C_CPU1_SA_DQ<21>       J22              38       SCONN288_ADR50001P003C01-SCONNA
M_C_CPU1_SA_DQ<21>       U1               U62      SOCKET4677_AZIFS054P001C01-SOCA
M_C_CPU1_SA_DQ<22>       J21              181      SCONN288_ADR50001P013C01-SCONNA
M_C_CPU1_SA_DQ<22>       J22              181      SCONN288_ADR50001P003C01-SCONNA
M_C_CPU1_SA_DQ<22>       U1               Y63      SOCKET4677_AZIFS054P001C01-SOCA
M_C_CPU1_SA_DQ<23>       J21              183      SCONN288_ADR50001P013C01-SCONNA
M_C_CPU1_SA_DQ<23>       J22              183      SCONN288_ADR50001P003C01-SCONNA
M_C_CPU1_SA_DQ<23>       U1               W62      SOCKET4677_AZIFS054P001C01-SOCA
M_C_CPU1_SA_DQ<24>       J21              40       SCONN288_ADR50001P013C01-SCONNA
M_C_CPU1_SA_DQ<24>       J22              40       SCONN288_ADR50001P003C01-SCONNA
M_C_CPU1_SA_DQ<24>       U1               AD63     SOCKET4677_AZIFS054P001C01-SOCA
M_C_CPU1_SA_DQ<25>       J21              42       SCONN288_ADR50001P013C01-SCONNA
M_C_CPU1_SA_DQ<25>       J22              42       SCONN288_ADR50001P003C01-SCONNA
M_C_CPU1_SA_DQ<25>       U1               AC62     SOCKET4677_AZIFS054P001C01-SOCA
M_C_CPU1_SA_DQ<26>       J21              185      SCONN288_ADR50001P013C01-SCONNA
M_C_CPU1_SA_DQ<26>       J22              185      SCONN288_ADR50001P003C01-SCONNA
M_C_CPU1_SA_DQ<26>       U1               AF63     SOCKET4677_AZIFS054P001C01-SOCA
M_C_CPU1_SA_DQ<27>       J21              187      SCONN288_ADR50001P013C01-SCONNA
M_C_CPU1_SA_DQ<27>       J22              187      SCONN288_ADR50001P003C01-SCONNA
M_C_CPU1_SA_DQ<27>       U1               AG62     SOCKET4677_AZIFS054P001C01-SOCA
M_C_CPU1_SA_DQ<28>       J21              47       SCONN288_ADR50001P013C01-SCONNA
M_C_CPU1_SA_DQ<28>       J22              47       SCONN288_ADR50001P003C01-SCONNA
M_C_CPU1_SA_DQ<28>       U1               AC60     SOCKET4677_AZIFS054P001C01-SOCA
M_C_CPU1_SA_DQ<29>       J21              49       SCONN288_ADR50001P013C01-SCONNA
M_C_CPU1_SA_DQ<29>       J22              49       SCONN288_ADR50001P003C01-SCONNA
M_C_CPU1_SA_DQ<29>       U1               AD59     SOCKET4677_AZIFS054P001C01-SOCA
M_C_CPU1_SA_DQ<30>       J21              192      SCONN288_ADR50001P013C01-SCONNA
M_C_CPU1_SA_DQ<30>       J22              192      SCONN288_ADR50001P003C01-SCONNA
M_C_CPU1_SA_DQ<30>       U1               AG60     SOCKET4677_AZIFS054P001C01-SOCA
M_C_CPU1_SA_DQ<31>       J21              194      SCONN288_ADR50001P013C01-SCONNA
M_C_CPU1_SA_DQ<31>       J22              194      SCONN288_ADR50001P003C01-SCONNA
M_C_CPU1_SA_DQ<31>       U1               AF59     SOCKET4677_AZIFS054P001C01-SOCA
M_C_CPU1_SA_DQS_DN<0>    J21              12       SCONN288_ADR50001P013C01-SCONNA
M_C_CPU1_SA_DQS_DN<0>    J22              12       SCONN288_ADR50001P003C01-SCONNA
M_C_CPU1_SA_DQS_DN<0>    U1               R76      SOCKET4677_AZIFS054P001C01-SOCA
M_C_CPU1_SA_DQS_DN<1>    J21              23       SCONN288_ADR50001P013C01-SCONNA
M_C_CPU1_SA_DQS_DN<1>    J22              23       SCONN288_ADR50001P003C01-SCONNA
M_C_CPU1_SA_DQS_DN<1>    U1               AB67     SOCKET4677_AZIFS054P001C01-SOCA
M_C_CPU1_SA_DQS_DN<2>    J21              34       SCONN288_ADR50001P013C01-SCONNA
M_C_CPU1_SA_DQS_DN<2>    J22              34       SCONN288_ADR50001P003C01-SCONNA
M_C_CPU1_SA_DQS_DN<2>    U1               R64      SOCKET4677_AZIFS054P001C01-SOCA
M_C_CPU1_SA_DQS_DN<3>    J21              45       SCONN288_ADR50001P013C01-SCONNA
M_C_CPU1_SA_DQS_DN<3>    J22              45       SCONN288_ADR50001P003C01-SCONNA
M_C_CPU1_SA_DQS_DN<3>    U1               AB61     SOCKET4677_AZIFS054P001C01-SOCA
M_C_CPU1_SA_DQS_DN<4>    J21              56       SCONN288_ADR50001P013C01-SCONNA
M_C_CPU1_SA_DQS_DN<4>    J22              56       SCONN288_ADR50001P003C01-SCONNA
M_C_CPU1_SA_DQS_DN<4>    U1               AD55     SOCKET4677_AZIFS054P001C01-SOCA
M_C_CPU1_SA_DQS_DN<5>    J21              156      SCONN288_ADR50001P013C01-SCONNA
M_C_CPU1_SA_DQS_DN<5>    J22              156      SCONN288_ADR50001P003C01-SCONNA
M_C_CPU1_SA_DQS_DN<5>    U1               W76      SOCKET4677_AZIFS054P001C01-SOCA
M_C_CPU1_SA_DQS_DN<6>    J21              167      SCONN288_ADR50001P013C01-SCONNA
M_C_CPU1_SA_DQS_DN<6>    J22              167      SCONN288_ADR50001P003C01-SCONNA
M_C_CPU1_SA_DQS_DN<6>    U1               AH67     SOCKET4677_AZIFS054P001C01-SOCA
M_C_CPU1_SA_DQS_DN<7>    J21              178      SCONN288_ADR50001P013C01-SCONNA
M_C_CPU1_SA_DQS_DN<7>    J22              178      SCONN288_ADR50001P003C01-SCONNA
M_C_CPU1_SA_DQS_DN<7>    U1               AA64     SOCKET4677_AZIFS054P001C01-SOCA
M_C_CPU1_SA_DQS_DN<8>    J21              189      SCONN288_ADR50001P013C01-SCONNA
M_C_CPU1_SA_DQS_DN<8>    J22              189      SCONN288_ADR50001P003C01-SCONNA
M_C_CPU1_SA_DQS_DN<8>    U1               AF61     SOCKET4677_AZIFS054P001C01-SOCA
M_C_CPU1_SA_DQS_DN<9>    J21              200      SCONN288_ADR50001P013C01-SCONNA
M_C_CPU1_SA_DQS_DN<9>    J22              200      SCONN288_ADR50001P003C01-SCONNA
M_C_CPU1_SA_DQS_DN<9>    U1               AH55     SOCKET4677_AZIFS054P001C01-SOCA
M_C_CPU1_SA_DQS_DP<0>    J21              11       SCONN288_ADR50001P013C01-SCONNA
M_C_CPU1_SA_DQS_DP<0>    J22              11       SCONN288_ADR50001P003C01-SCONNA
M_C_CPU1_SA_DQS_DP<0>    U1               U76      SOCKET4677_AZIFS054P001C01-SOCA
M_C_CPU1_SA_DQS_DP<1>    J21              22       SCONN288_ADR50001P013C01-SCONNA
M_C_CPU1_SA_DQS_DP<1>    J22              22       SCONN288_ADR50001P003C01-SCONNA
M_C_CPU1_SA_DQS_DP<1>    U1               AD67     SOCKET4677_AZIFS054P001C01-SOCA
M_C_CPU1_SA_DQS_DP<2>    J21              33       SCONN288_ADR50001P013C01-SCONNA
M_C_CPU1_SA_DQS_DP<2>    J22              33       SCONN288_ADR50001P003C01-SCONNA
M_C_CPU1_SA_DQS_DP<2>    U1               U64      SOCKET4677_AZIFS054P001C01-SOCA
M_C_CPU1_SA_DQS_DP<3>    J21              44       SCONN288_ADR50001P013C01-SCONNA
M_C_CPU1_SA_DQS_DP<3>    J22              44       SCONN288_ADR50001P003C01-SCONNA
M_C_CPU1_SA_DQS_DP<3>    U1               AD61     SOCKET4677_AZIFS054P001C01-SOCA
M_C_CPU1_SA_DQS_DP<4>    J21              55       SCONN288_ADR50001P013C01-SCONNA
M_C_CPU1_SA_DQS_DP<4>    J22              55       SCONN288_ADR50001P003C01-SCONNA
M_C_CPU1_SA_DQS_DP<4>    U1               AB55     SOCKET4677_AZIFS054P001C01-SOCA
M_C_CPU1_SA_DQS_DP<5>    J21              157      SCONN288_ADR50001P013C01-SCONNA
M_C_CPU1_SA_DQS_DP<5>    J22              157      SCONN288_ADR50001P003C01-SCONNA
M_C_CPU1_SA_DQS_DP<5>    U1               AA76     SOCKET4677_AZIFS054P001C01-SOCA
M_C_CPU1_SA_DQS_DP<6>    J21              168      SCONN288_ADR50001P013C01-SCONNA
M_C_CPU1_SA_DQS_DP<6>    J22              168      SCONN288_ADR50001P003C01-SCONNA
M_C_CPU1_SA_DQS_DP<6>    U1               AF67     SOCKET4677_AZIFS054P001C01-SOCA
M_C_CPU1_SA_DQS_DP<7>    J21              179      SCONN288_ADR50001P013C01-SCONNA
M_C_CPU1_SA_DQS_DP<7>    J22              179      SCONN288_ADR50001P003C01-SCONNA
M_C_CPU1_SA_DQS_DP<7>    U1               W64      SOCKET4677_AZIFS054P001C01-SOCA
M_C_CPU1_SA_DQS_DP<8>    J21              190      SCONN288_ADR50001P013C01-SCONNA
M_C_CPU1_SA_DQS_DP<8>    J22              190      SCONN288_ADR50001P003C01-SCONNA
M_C_CPU1_SA_DQS_DP<8>    U1               AH61     SOCKET4677_AZIFS054P001C01-SOCA
M_C_CPU1_SA_DQS_DP<9>    J21              201      SCONN288_ADR50001P013C01-SCONNA
M_C_CPU1_SA_DQS_DP<9>    J22              201      SCONN288_ADR50001P003C01-SCONNA
M_C_CPU1_SA_DQS_DP<9>    U1               AF55     SOCKET4677_AZIFS054P001C01-SOCA
M_C_CPU1_SA_PAR          J21              74       SCONN288_ADR50001P013C01-SCONNA
M_C_CPU1_SA_PAR          J22              74       SCONN288_ADR50001P003C01-SCONNA
M_C_CPU1_SA_PAR          U1               T47      SOCKET4677_AZIFS054P001C01-SOCA
M_C_CPU1_SA_RSP<0>       J21              86       SCONN288_ADR50001P013C01-SCONNA
M_C_CPU1_SA_RSP<0>       U1               AC48     SOCKET4677_AZIFS054P001C01-SOCA
M_C_CPU1_SA_RSP<1>       J22              86       SCONN288_ADR50001P003C01-SCONNA
M_C_CPU1_SA_RSP<1>       U1               AD47     SOCKET4677_AZIFS054P001C01-SOCA
M_C_CPU1_SB_CA<0>        J21              76       SCONN288_ADR50001P013C01-SCONNA
M_C_CPU1_SB_CA<0>        J22              76       SCONN288_ADR50001P003C01-SCONNA
M_C_CPU1_SB_CA<0>        U1               W48      SOCKET4677_AZIFS054P001C01-SOCA
M_C_CPU1_SB_CA<1>        J21              221      SCONN288_ADR50001P013C01-SCONNA
M_C_CPU1_SB_CA<1>        J22              221      SCONN288_ADR50001P003C01-SCONNA
M_C_CPU1_SB_CA<1>        U1               Y47      SOCKET4677_AZIFS054P001C01-SOCA
M_C_CPU1_SB_CA<2>        J21              78       SCONN288_ADR50001P013C01-SCONNA
M_C_CPU1_SB_CA<2>        J22              78       SCONN288_ADR50001P003C01-SCONNA
M_C_CPU1_SB_CA<2>        U1               U41      SOCKET4677_AZIFS054P001C01-SOCA
M_C_CPU1_SB_CA<3>        J21              223      SCONN288_ADR50001P013C01-SCONNA
M_C_CPU1_SB_CA<3>        J22              223      SCONN288_ADR50001P003C01-SCONNA
M_C_CPU1_SB_CA<3>        U1               W41      SOCKET4677_AZIFS054P001C01-SOCA
M_C_CPU1_SB_CA<4>        J21              80       SCONN288_ADR50001P013C01-SCONNA
M_C_CPU1_SB_CA<4>        J22              80       SCONN288_ADR50001P003C01-SCONNA
M_C_CPU1_SB_CA<4>        U1               T40      SOCKET4677_AZIFS054P001C01-SOCA
M_C_CPU1_SB_CA<5>        J21              225      SCONN288_ADR50001P013C01-SCONNA
M_C_CPU1_SB_CA<5>        J22              225      SCONN288_ADR50001P003C01-SCONNA
M_C_CPU1_SB_CA<5>        U1               Y40      SOCKET4677_AZIFS054P001C01-SOCA
M_C_CPU1_SB_CA<6>        J21              82       SCONN288_ADR50001P013C01-SCONNA
M_C_CPU1_SB_CA<6>        J22              82       SCONN288_ADR50001P003C01-SCONNA
M_C_CPU1_SB_CA<6>        U1               R39      SOCKET4677_AZIFS054P001C01-SOCA
M_C_CPU1_SB_CB<0>        J21              96       SCONN288_ADR50001P013C01-SCONNA
M_C_CPU1_SB_CB<0>        J22              96       SCONN288_ADR50001P003C01-SCONNA
M_C_CPU1_SB_CB<0>        U1               T32      SOCKET4677_AZIFS054P001C01-SOCA
M_C_CPU1_SB_CB<1>        J21              98       SCONN288_ADR50001P013C01-SCONNA
M_C_CPU1_SB_CB<1>        J22              98       SCONN288_ADR50001P003C01-SCONNA
M_C_CPU1_SB_CB<1>        U1               U31      SOCKET4677_AZIFS054P001C01-SOCA
M_C_CPU1_SB_CB<2>        J21              241      SCONN288_ADR50001P013C01-SCONNA
M_C_CPU1_SB_CB<2>        J22              241      SCONN288_ADR50001P003C01-SCONNA
M_C_CPU1_SB_CB<2>        U1               Y32      SOCKET4677_AZIFS054P001C01-SOCA
M_C_CPU1_SB_CB<3>        J21              243      SCONN288_ADR50001P013C01-SCONNA
M_C_CPU1_SB_CB<3>        J22              243      SCONN288_ADR50001P003C01-SCONNA
M_C_CPU1_SB_CB<3>        U1               W31      SOCKET4677_AZIFS054P001C01-SOCA
M_C_CPU1_SB_CB<4>        J21              89       SCONN288_ADR50001P013C01-SCONNA
M_C_CPU1_SB_CB<4>        J22              89       SCONN288_ADR50001P003C01-SCONNA
M_C_CPU1_SB_CB<4>        U1               U35      SOCKET4677_AZIFS054P001C01-SOCA
M_C_CPU1_SB_CB<5>        J21              91       SCONN288_ADR50001P013C01-SCONNA
M_C_CPU1_SB_CB<5>        J22              91       SCONN288_ADR50001P003C01-SCONNA
M_C_CPU1_SB_CB<5>        U1               T34      SOCKET4677_AZIFS054P001C01-SOCA
M_C_CPU1_SB_CB<6>        J21              234      SCONN288_ADR50001P013C01-SCONNA
M_C_CPU1_SB_CB<6>        J22              234      SCONN288_ADR50001P003C01-SCONNA
M_C_CPU1_SB_CB<6>        U1               W35      SOCKET4677_AZIFS054P001C01-SOCA
M_C_CPU1_SB_CB<7>        J21              236      SCONN288_ADR50001P013C01-SCONNA
M_C_CPU1_SB_CB<7>        J22              236      SCONN288_ADR50001P003C01-SCONNA
M_C_CPU1_SB_CB<7>        U1               Y34      SOCKET4677_AZIFS054P001C01-SOCA
M_C_CPU1_SB_CS_N<0>      J21              84       SCONN288_ADR50001P013C01-SCONNA
M_C_CPU1_SB_CS_N<0>      U1               T38      SOCKET4677_AZIFS054P001C01-SOCA
M_C_CPU1_SB_CS_N<1>      J21              229      SCONN288_ADR50001P013C01-SCONNA
M_C_CPU1_SB_CS_N<1>      U1               U37      SOCKET4677_AZIFS054P001C01-SOCA
M_C_CPU1_SB_CS_N<2>      J22              84       SCONN288_ADR50001P003C01-SCONNA
M_C_CPU1_SB_CS_N<2>      U1               Y38      SOCKET4677_AZIFS054P001C01-SOCA
M_C_CPU1_SB_CS_N<3>      J22              229      SCONN288_ADR50001P003C01-SCONNA
M_C_CPU1_SB_CS_N<3>      U1               W37      SOCKET4677_AZIFS054P001C01-SOCA
M_C_CPU1_SB_DQ<0>        J21              100      SCONN288_ADR50001P013C01-SCONNA
M_C_CPU1_SB_DQ<0>        J22              100      SCONN288_ADR50001P003C01-SCONNA
M_C_CPU1_SB_DQ<0>        U1               AD38     SOCKET4677_AZIFS054P001C01-SOCA
M_C_CPU1_SB_DQ<1>        J21              102      SCONN288_ADR50001P013C01-SCONNA
M_C_CPU1_SB_DQ<1>        J22              102      SCONN288_ADR50001P003C01-SCONNA
M_C_CPU1_SB_DQ<1>        U1               AC37     SOCKET4677_AZIFS054P001C01-SOCA
M_C_CPU1_SB_DQ<2>        J21              245      SCONN288_ADR50001P013C01-SCONNA
M_C_CPU1_SB_DQ<2>        J22              245      SCONN288_ADR50001P003C01-SCONNA
M_C_CPU1_SB_DQ<2>        U1               AF38     SOCKET4677_AZIFS054P001C01-SOCA
M_C_CPU1_SB_DQ<3>        J21              247      SCONN288_ADR50001P013C01-SCONNA
M_C_CPU1_SB_DQ<3>        J22              247      SCONN288_ADR50001P003C01-SCONNA
M_C_CPU1_SB_DQ<3>        U1               AG37     SOCKET4677_AZIFS054P001C01-SOCA
M_C_CPU1_SB_DQ<4>        J21              107      SCONN288_ADR50001P013C01-SCONNA
M_C_CPU1_SB_DQ<4>        J22              107      SCONN288_ADR50001P003C01-SCONNA
M_C_CPU1_SB_DQ<4>        U1               AC35     SOCKET4677_AZIFS054P001C01-SOCA
M_C_CPU1_SB_DQ<5>        J21              109      SCONN288_ADR50001P013C01-SCONNA
M_C_CPU1_SB_DQ<5>        J22              109      SCONN288_ADR50001P003C01-SCONNA
M_C_CPU1_SB_DQ<5>        U1               AD34     SOCKET4677_AZIFS054P001C01-SOCA
M_C_CPU1_SB_DQ<6>        J21              252      SCONN288_ADR50001P013C01-SCONNA
M_C_CPU1_SB_DQ<6>        J22              252      SCONN288_ADR50001P003C01-SCONNA
M_C_CPU1_SB_DQ<6>        U1               AG35     SOCKET4677_AZIFS054P001C01-SOCA
M_C_CPU1_SB_DQ<7>        J21              254      SCONN288_ADR50001P013C01-SCONNA
M_C_CPU1_SB_DQ<7>        J22              254      SCONN288_ADR50001P003C01-SCONNA
M_C_CPU1_SB_DQ<7>        U1               AF34     SOCKET4677_AZIFS054P001C01-SOCA
M_C_CPU1_SB_DQ<8>        J21              111      SCONN288_ADR50001P013C01-SCONNA
M_C_CPU1_SB_DQ<8>        J22              111      SCONN288_ADR50001P003C01-SCONNA
M_C_CPU1_SB_DQ<8>        U1               AD32     SOCKET4677_AZIFS054P001C01-SOCA
M_C_CPU1_SB_DQ<9>        J21              113      SCONN288_ADR50001P013C01-SCONNA
M_C_CPU1_SB_DQ<9>        J22              113      SCONN288_ADR50001P003C01-SCONNA
M_C_CPU1_SB_DQ<9>        U1               AC31     SOCKET4677_AZIFS054P001C01-SOCA
M_C_CPU1_SB_DQ<10>       J21              256      SCONN288_ADR50001P013C01-SCONNA
M_C_CPU1_SB_DQ<10>       J22              256      SCONN288_ADR50001P003C01-SCONNA
M_C_CPU1_SB_DQ<10>       U1               AF32     SOCKET4677_AZIFS054P001C01-SOCA
M_C_CPU1_SB_DQ<11>       J21              258      SCONN288_ADR50001P013C01-SCONNA
M_C_CPU1_SB_DQ<11>       J22              258      SCONN288_ADR50001P003C01-SCONNA
M_C_CPU1_SB_DQ<11>       U1               AG31     SOCKET4677_AZIFS054P001C01-SOCA
M_C_CPU1_SB_DQ<12>       J21              118      SCONN288_ADR50001P013C01-SCONNA
M_C_CPU1_SB_DQ<12>       J22              118      SCONN288_ADR50001P003C01-SCONNA
M_C_CPU1_SB_DQ<12>       U1               AC29     SOCKET4677_AZIFS054P001C01-SOCA
M_C_CPU1_SB_DQ<13>       J21              120      SCONN288_ADR50001P013C01-SCONNA
M_C_CPU1_SB_DQ<13>       J22              120      SCONN288_ADR50001P003C01-SCONNA
M_C_CPU1_SB_DQ<13>       U1               AD28     SOCKET4677_AZIFS054P001C01-SOCA
M_C_CPU1_SB_DQ<14>       J21              263      SCONN288_ADR50001P013C01-SCONNA
M_C_CPU1_SB_DQ<14>       J22              263      SCONN288_ADR50001P003C01-SCONNA
M_C_CPU1_SB_DQ<14>       U1               AG29     SOCKET4677_AZIFS054P001C01-SOCA
M_C_CPU1_SB_DQ<15>       J21              265      SCONN288_ADR50001P013C01-SCONNA
M_C_CPU1_SB_DQ<15>       J22              265      SCONN288_ADR50001P003C01-SCONNA
M_C_CPU1_SB_DQ<15>       U1               AF28     SOCKET4677_AZIFS054P001C01-SOCA
M_C_CPU1_SB_DQ<16>       J21              122      SCONN288_ADR50001P013C01-SCONNA
M_C_CPU1_SB_DQ<16>       J22              122      SCONN288_ADR50001P003C01-SCONNA
M_C_CPU1_SB_DQ<16>       U1               U23      SOCKET4677_AZIFS054P001C01-SOCA
M_C_CPU1_SB_DQ<17>       J21              124      SCONN288_ADR50001P013C01-SCONNA
M_C_CPU1_SB_DQ<17>       J22              124      SCONN288_ADR50001P003C01-SCONNA
M_C_CPU1_SB_DQ<17>       U1               T22      SOCKET4677_AZIFS054P001C01-SOCA
M_C_CPU1_SB_DQ<18>       J21              267      SCONN288_ADR50001P013C01-SCONNA
M_C_CPU1_SB_DQ<18>       J22              267      SCONN288_ADR50001P003C01-SCONNA
M_C_CPU1_SB_DQ<18>       U1               W23      SOCKET4677_AZIFS054P001C01-SOCA
M_C_CPU1_SB_DQ<19>       J21              269      SCONN288_ADR50001P013C01-SCONNA
M_C_CPU1_SB_DQ<19>       J22              269      SCONN288_ADR50001P003C01-SCONNA
M_C_CPU1_SB_DQ<19>       U1               Y22      SOCKET4677_AZIFS054P001C01-SOCA
M_C_CPU1_SB_DQ<20>       J21              129      SCONN288_ADR50001P013C01-SCONNA
M_C_CPU1_SB_DQ<20>       J22              129      SCONN288_ADR50001P003C01-SCONNA
M_C_CPU1_SB_DQ<20>       U1               T20      SOCKET4677_AZIFS054P001C01-SOCA
M_C_CPU1_SB_DQ<21>       J21              131      SCONN288_ADR50001P013C01-SCONNA
M_C_CPU1_SB_DQ<21>       J22              131      SCONN288_ADR50001P003C01-SCONNA
M_C_CPU1_SB_DQ<21>       U1               U19      SOCKET4677_AZIFS054P001C01-SOCA
M_C_CPU1_SB_DQ<22>       J21              274      SCONN288_ADR50001P013C01-SCONNA
M_C_CPU1_SB_DQ<22>       J22              274      SCONN288_ADR50001P003C01-SCONNA
M_C_CPU1_SB_DQ<22>       U1               Y20      SOCKET4677_AZIFS054P001C01-SOCA
M_C_CPU1_SB_DQ<23>       J21              276      SCONN288_ADR50001P013C01-SCONNA
M_C_CPU1_SB_DQ<23>       J22              276      SCONN288_ADR50001P003C01-SCONNA
M_C_CPU1_SB_DQ<23>       U1               W19      SOCKET4677_AZIFS054P001C01-SOCA
M_C_CPU1_SB_DQ<24>       J21              133      SCONN288_ADR50001P013C01-SCONNA
M_C_CPU1_SB_DQ<24>       J22              133      SCONN288_ADR50001P003C01-SCONNA
M_C_CPU1_SB_DQ<24>       U1               AD20     SOCKET4677_AZIFS054P001C01-SOCA
M_C_CPU1_SB_DQ<25>       J21              135      SCONN288_ADR50001P013C01-SCONNA
M_C_CPU1_SB_DQ<25>       J22              135      SCONN288_ADR50001P003C01-SCONNA
M_C_CPU1_SB_DQ<25>       U1               AC19     SOCKET4677_AZIFS054P001C01-SOCA
M_C_CPU1_SB_DQ<26>       J21              278      SCONN288_ADR50001P013C01-SCONNA
M_C_CPU1_SB_DQ<26>       J22              278      SCONN288_ADR50001P003C01-SCONNA
M_C_CPU1_SB_DQ<26>       U1               AF20     SOCKET4677_AZIFS054P001C01-SOCA
M_C_CPU1_SB_DQ<27>       J21              280      SCONN288_ADR50001P013C01-SCONNA
M_C_CPU1_SB_DQ<27>       J22              280      SCONN288_ADR50001P003C01-SCONNA
M_C_CPU1_SB_DQ<27>       U1               AG19     SOCKET4677_AZIFS054P001C01-SOCA
M_C_CPU1_SB_DQ<28>       J21              140      SCONN288_ADR50001P013C01-SCONNA
M_C_CPU1_SB_DQ<28>       J22              140      SCONN288_ADR50001P003C01-SCONNA
M_C_CPU1_SB_DQ<28>       U1               AA17     SOCKET4677_AZIFS054P001C01-SOCA
M_C_CPU1_SB_DQ<29>       J21              142      SCONN288_ADR50001P013C01-SCONNA
M_C_CPU1_SB_DQ<29>       J22              142      SCONN288_ADR50001P003C01-SCONNA
M_C_CPU1_SB_DQ<29>       U1               AG17     SOCKET4677_AZIFS054P001C01-SOCA
M_C_CPU1_SB_DQ<30>       J21              285      SCONN288_ADR50001P013C01-SCONNA
M_C_CPU1_SB_DQ<30>       J22              285      SCONN288_ADR50001P003C01-SCONNA
M_C_CPU1_SB_DQ<30>       U1               AC17     SOCKET4677_AZIFS054P001C01-SOCA
M_C_CPU1_SB_DQ<31>       J21              287      SCONN288_ADR50001P013C01-SCONNA
M_C_CPU1_SB_DQ<31>       J22              287      SCONN288_ADR50001P003C01-SCONNA
M_C_CPU1_SB_DQ<31>       U1               AJ17     SOCKET4677_AZIFS054P001C01-SOCA
M_C_CPU1_SB_DQS_DN<0>    J21              105      SCONN288_ADR50001P013C01-SCONNA
M_C_CPU1_SB_DQS_DN<0>    J22              105      SCONN288_ADR50001P003C01-SCONNA
M_C_CPU1_SB_DQS_DN<0>    U1               AB36     SOCKET4677_AZIFS054P001C01-SOCA
M_C_CPU1_SB_DQS_DN<1>    J21              116      SCONN288_ADR50001P013C01-SCONNA
M_C_CPU1_SB_DQS_DN<1>    J22              116      SCONN288_ADR50001P003C01-SCONNA
M_C_CPU1_SB_DQS_DN<1>    U1               AB30     SOCKET4677_AZIFS054P001C01-SOCA
M_C_CPU1_SB_DQS_DN<2>    J21              127      SCONN288_ADR50001P013C01-SCONNA
M_C_CPU1_SB_DQS_DN<2>    J22              127      SCONN288_ADR50001P003C01-SCONNA
M_C_CPU1_SB_DQS_DN<2>    U1               R21      SOCKET4677_AZIFS054P001C01-SOCA
M_C_CPU1_SB_DQS_DN<3>    J21              138      SCONN288_ADR50001P013C01-SCONNA
M_C_CPU1_SB_DQS_DN<3>    J22              138      SCONN288_ADR50001P003C01-SCONNA
M_C_CPU1_SB_DQS_DN<3>    U1               AB18     SOCKET4677_AZIFS054P001C01-SOCA
M_C_CPU1_SB_DQS_DN<4>    J21              238      SCONN288_ADR50001P013C01-SCONNA
M_C_CPU1_SB_DQS_DN<4>    J22              238      SCONN288_ADR50001P003C01-SCONNA
M_C_CPU1_SB_DQS_DN<4>    U1               W33      SOCKET4677_AZIFS054P001C01-SOCA
M_C_CPU1_SB_DQS_DN<5>    J21              249      SCONN288_ADR50001P013C01-SCONNA
M_C_CPU1_SB_DQS_DN<5>    J22              249      SCONN288_ADR50001P003C01-SCONNA
M_C_CPU1_SB_DQS_DN<5>    U1               AF36     SOCKET4677_AZIFS054P001C01-SOCA
M_C_CPU1_SB_DQS_DN<6>    J21              260      SCONN288_ADR50001P013C01-SCONNA
M_C_CPU1_SB_DQS_DN<6>    J22              260      SCONN288_ADR50001P003C01-SCONNA
M_C_CPU1_SB_DQS_DN<6>    U1               AF30     SOCKET4677_AZIFS054P001C01-SOCA
M_C_CPU1_SB_DQS_DN<7>    J21              271      SCONN288_ADR50001P013C01-SCONNA
M_C_CPU1_SB_DQS_DN<7>    J22              271      SCONN288_ADR50001P003C01-SCONNA
M_C_CPU1_SB_DQS_DN<7>    U1               W21      SOCKET4677_AZIFS054P001C01-SOCA
M_C_CPU1_SB_DQS_DN<8>    J21              282      SCONN288_ADR50001P013C01-SCONNA
M_C_CPU1_SB_DQS_DN<8>    J22              282      SCONN288_ADR50001P003C01-SCONNA
M_C_CPU1_SB_DQS_DN<8>    U1               AF18     SOCKET4677_AZIFS054P001C01-SOCA
M_C_CPU1_SB_DQS_DN<9>    J21              94       SCONN288_ADR50001P013C01-SCONNA
M_C_CPU1_SB_DQS_DN<9>    J22              94       SCONN288_ADR50001P003C01-SCONNA
M_C_CPU1_SB_DQS_DN<9>    U1               R33      SOCKET4677_AZIFS054P001C01-SOCA
M_C_CPU1_SB_DQS_DP<0>    J21              104      SCONN288_ADR50001P013C01-SCONNA
M_C_CPU1_SB_DQS_DP<0>    J22              104      SCONN288_ADR50001P003C01-SCONNA
M_C_CPU1_SB_DQS_DP<0>    U1               AD36     SOCKET4677_AZIFS054P001C01-SOCA
M_C_CPU1_SB_DQS_DP<1>    J21              115      SCONN288_ADR50001P013C01-SCONNA
M_C_CPU1_SB_DQS_DP<1>    J22              115      SCONN288_ADR50001P003C01-SCONNA
M_C_CPU1_SB_DQS_DP<1>    U1               AD30     SOCKET4677_AZIFS054P001C01-SOCA
M_C_CPU1_SB_DQS_DP<2>    J21              126      SCONN288_ADR50001P013C01-SCONNA
M_C_CPU1_SB_DQS_DP<2>    J22              126      SCONN288_ADR50001P003C01-SCONNA
M_C_CPU1_SB_DQS_DP<2>    U1               U21      SOCKET4677_AZIFS054P001C01-SOCA
M_C_CPU1_SB_DQS_DP<3>    J21              137      SCONN288_ADR50001P013C01-SCONNA
M_C_CPU1_SB_DQS_DP<3>    J22              137      SCONN288_ADR50001P003C01-SCONNA
M_C_CPU1_SB_DQS_DP<3>    U1               AD18     SOCKET4677_AZIFS054P001C01-SOCA
M_C_CPU1_SB_DQS_DP<4>    J21              239      SCONN288_ADR50001P013C01-SCONNA
M_C_CPU1_SB_DQS_DP<4>    J22              239      SCONN288_ADR50001P003C01-SCONNA
M_C_CPU1_SB_DQS_DP<4>    U1               AA33     SOCKET4677_AZIFS054P001C01-SOCA
M_C_CPU1_SB_DQS_DP<5>    J21              250      SCONN288_ADR50001P013C01-SCONNA
M_C_CPU1_SB_DQS_DP<5>    J22              250      SCONN288_ADR50001P003C01-SCONNA
M_C_CPU1_SB_DQS_DP<5>    U1               AH36     SOCKET4677_AZIFS054P001C01-SOCA
M_C_CPU1_SB_DQS_DP<6>    J21              261      SCONN288_ADR50001P013C01-SCONNA
M_C_CPU1_SB_DQS_DP<6>    J22              261      SCONN288_ADR50001P003C01-SCONNA
M_C_CPU1_SB_DQS_DP<6>    U1               AH30     SOCKET4677_AZIFS054P001C01-SOCA
M_C_CPU1_SB_DQS_DP<7>    J21              272      SCONN288_ADR50001P013C01-SCONNA
M_C_CPU1_SB_DQS_DP<7>    J22              272      SCONN288_ADR50001P003C01-SCONNA
M_C_CPU1_SB_DQS_DP<7>    U1               AA21     SOCKET4677_AZIFS054P001C01-SOCA
M_C_CPU1_SB_DQS_DP<8>    J21              283      SCONN288_ADR50001P013C01-SCONNA
M_C_CPU1_SB_DQS_DP<8>    J22              283      SCONN288_ADR50001P003C01-SCONNA
M_C_CPU1_SB_DQS_DP<8>    U1               AH18     SOCKET4677_AZIFS054P001C01-SOCA
M_C_CPU1_SB_DQS_DP<9>    J21              93       SCONN288_ADR50001P013C01-SCONNA
M_C_CPU1_SB_DQS_DP<9>    J22              93       SCONN288_ADR50001P003C01-SCONNA
M_C_CPU1_SB_DQS_DP<9>    U1               U33      SOCKET4677_AZIFS054P001C01-SOCA
M_C_CPU1_SB_PAR          J21              227      SCONN288_ADR50001P013C01-SCONNA
M_C_CPU1_SB_PAR          J22              227      SCONN288_ADR50001P003C01-SCONNA
M_C_CPU1_SB_PAR          U1               AA39     SOCKET4677_AZIFS054P001C01-SOCA
M_C_CPU1_SB_RSP<0>       J21              87       SCONN288_ADR50001P013C01-SCONNA
M_C_CPU1_SB_RSP<0>       U1               AG48     SOCKET4677_AZIFS054P001C01-SOCA
M_C_CPU1_SB_RSP<1>       J22              87       SCONN288_ADR50001P003C01-SCONNA
M_C_CPU1_SB_RSP<1>       U1               AF47     SOCKET4677_AZIFS054P001C01-SOCA
M_D_CPU0_ALERT_N         J7               62       SCONN288_ADR50001P013C01-SCONNA
M_D_CPU0_ALERT_N         J8               62       SCONN288_ADR50001P003C01-SCONNA
M_D_CPU0_ALERT_N         U2               AV47     SOCKET4677_AZIFS054P001C01-SOCA
M_D_CPU0_CLK_DN<0>       J7               218      SCONN288_ADR50001P013C01-SCONNA
M_D_CPU0_CLK_DN<0>       U2               AJ45     SOCKET4677_AZIFS054P001C01-SOCA
M_D_CPU0_CLK_DN<1>       J8               218      SCONN288_ADR50001P003C01-SCONNA
M_D_CPU0_CLK_DN<1>       U2               AN45     SOCKET4677_AZIFS054P001C01-SOCA
M_D_CPU0_CLK_DP<0>       J7               217      SCONN288_ADR50001P013C01-SCONNA
M_D_CPU0_CLK_DP<0>       U2               AL45     SOCKET4677_AZIFS054P001C01-SOCA
M_D_CPU0_CLK_DP<1>       J8               217      SCONN288_ADR50001P003C01-SCONNA
M_D_CPU0_CLK_DP<1>       U2               AR45     SOCKET4677_AZIFS054P001C01-SOCA
M_D_CPU0_SA_CA<0>        J7               66       SCONN288_ADR50001P013C01-SCONNA
M_D_CPU0_SA_CA<0>        J8               66       SCONN288_ADR50001P003C01-SCONNA
M_D_CPU0_SA_CA<0>        U2               AJ52     SOCKET4677_AZIFS054P001C01-SOCA
M_D_CPU0_SA_CA<1>        J7               211      SCONN288_ADR50001P013C01-SCONNA
M_D_CPU0_SA_CA<1>        J8               211      SCONN288_ADR50001P003C01-SCONNA
M_D_CPU0_SA_CA<1>        U2               AR52     SOCKET4677_AZIFS054P001C01-SOCA
M_D_CPU0_SA_CA<2>        J7               68       SCONN288_ADR50001P013C01-SCONNA
M_D_CPU0_SA_CA<2>        J8               68       SCONN288_ADR50001P003C01-SCONNA
M_D_CPU0_SA_CA<2>        U2               AK51     SOCKET4677_AZIFS054P001C01-SOCA
M_D_CPU0_SA_CA<3>        J7               213      SCONN288_ADR50001P013C01-SCONNA
M_D_CPU0_SA_CA<3>        J8               213      SCONN288_ADR50001P003C01-SCONNA
M_D_CPU0_SA_CA<3>        U2               AP51     SOCKET4677_AZIFS054P001C01-SOCA
M_D_CPU0_SA_CA<4>        J7               70       SCONN288_ADR50001P013C01-SCONNA
M_D_CPU0_SA_CA<4>        J8               70       SCONN288_ADR50001P003C01-SCONNA
M_D_CPU0_SA_CA<4>        U2               AL50     SOCKET4677_AZIFS054P001C01-SOCA
M_D_CPU0_SA_CA<5>        J7               215      SCONN288_ADR50001P013C01-SCONNA
M_D_CPU0_SA_CA<5>        J8               215      SCONN288_ADR50001P003C01-SCONNA
M_D_CPU0_SA_CA<5>        U2               AN50     SOCKET4677_AZIFS054P001C01-SOCA
M_D_CPU0_SA_CA<6>        J7               72       SCONN288_ADR50001P013C01-SCONNA
M_D_CPU0_SA_CA<6>        J8               72       SCONN288_ADR50001P003C01-SCONNA
M_D_CPU0_SA_CA<6>        U2               AN43     SOCKET4677_AZIFS054P001C01-SOCA
M_D_CPU0_SA_CB<0>        J7               51       SCONN288_ADR50001P013C01-SCONNA
M_D_CPU0_SA_CB<0>        J8               51       SCONN288_ADR50001P003C01-SCONNA
M_D_CPU0_SA_CB<0>        U2               AL60     SOCKET4677_AZIFS054P001C01-SOCA
M_D_CPU0_SA_CB<1>        J7               53       SCONN288_ADR50001P013C01-SCONNA
M_D_CPU0_SA_CB<1>        J8               53       SCONN288_ADR50001P003C01-SCONNA
M_D_CPU0_SA_CB<1>        U2               AK59     SOCKET4677_AZIFS054P001C01-SOCA
M_D_CPU0_SA_CB<2>        J7               196      SCONN288_ADR50001P013C01-SCONNA
M_D_CPU0_SA_CB<2>        J8               196      SCONN288_ADR50001P003C01-SCONNA
M_D_CPU0_SA_CB<2>        U2               AN60     SOCKET4677_AZIFS054P001C01-SOCA
M_D_CPU0_SA_CB<3>        J7               198      SCONN288_ADR50001P013C01-SCONNA
M_D_CPU0_SA_CB<3>        J8               198      SCONN288_ADR50001P003C01-SCONNA
M_D_CPU0_SA_CB<3>        U2               AP59     SOCKET4677_AZIFS054P001C01-SOCA
M_D_CPU0_SA_CB<4>        J7               58       SCONN288_ADR50001P013C01-SCONNA
M_D_CPU0_SA_CB<4>        J8               58       SCONN288_ADR50001P003C01-SCONNA
M_D_CPU0_SA_CB<4>        U2               AK57     SOCKET4677_AZIFS054P001C01-SOCA
M_D_CPU0_SA_CB<5>        J7               60       SCONN288_ADR50001P013C01-SCONNA
M_D_CPU0_SA_CB<5>        J8               60       SCONN288_ADR50001P003C01-SCONNA
M_D_CPU0_SA_CB<5>        U2               AL56     SOCKET4677_AZIFS054P001C01-SOCA
M_D_CPU0_SA_CB<6>        J7               203      SCONN288_ADR50001P013C01-SCONNA
M_D_CPU0_SA_CB<6>        J8               203      SCONN288_ADR50001P003C01-SCONNA
M_D_CPU0_SA_CB<6>        U2               AP57     SOCKET4677_AZIFS054P001C01-SOCA
M_D_CPU0_SA_CB<7>        J7               205      SCONN288_ADR50001P013C01-SCONNA
M_D_CPU0_SA_CB<7>        J8               205      SCONN288_ADR50001P003C01-SCONNA
M_D_CPU0_SA_CB<7>        U2               AN56     SOCKET4677_AZIFS054P001C01-SOCA
M_D_CPU0_SA_CS_N<0>      J7               64       SCONN288_ADR50001P013C01-SCONNA
M_D_CPU0_SA_CS_N<0>      U2               AL54     SOCKET4677_AZIFS054P001C01-SOCA
M_D_CPU0_SA_CS_N<1>      J7               209      SCONN288_ADR50001P013C01-SCONNA
M_D_CPU0_SA_CS_N<1>      U2               AK53     SOCKET4677_AZIFS054P001C01-SOCA
M_D_CPU0_SA_CS_N<2>      J8               64       SCONN288_ADR50001P003C01-SCONNA
M_D_CPU0_SA_CS_N<2>      U2               AN54     SOCKET4677_AZIFS054P001C01-SOCA
M_D_CPU0_SA_CS_N<3>      J8               209      SCONN288_ADR50001P003C01-SCONNA
M_D_CPU0_SA_CS_N<3>      U2               AP53     SOCKET4677_AZIFS054P001C01-SOCA
M_D_CPU0_SA_DQ<0>        J7               7        SCONN288_ADR50001P013C01-SCONNA
M_D_CPU0_SA_DQ<0>        J8               7        SCONN288_ADR50001P003C01-SCONNA
M_D_CPU0_SA_DQ<0>        U2               AD75     SOCKET4677_AZIFS054P001C01-SOCA
M_D_CPU0_SA_DQ<1>        J7               9        SCONN288_ADR50001P013C01-SCONNA
M_D_CPU0_SA_DQ<1>        J8               9        SCONN288_ADR50001P003C01-SCONNA
M_D_CPU0_SA_DQ<1>        U2               AC74     SOCKET4677_AZIFS054P001C01-SOCA
M_D_CPU0_SA_DQ<2>        J7               152      SCONN288_ADR50001P013C01-SCONNA
M_D_CPU0_SA_DQ<2>        J8               152      SCONN288_ADR50001P003C01-SCONNA
M_D_CPU0_SA_DQ<2>        U2               AF75     SOCKET4677_AZIFS054P001C01-SOCA
M_D_CPU0_SA_DQ<3>        J7               154      SCONN288_ADR50001P013C01-SCONNA
M_D_CPU0_SA_DQ<3>        J8               154      SCONN288_ADR50001P003C01-SCONNA
M_D_CPU0_SA_DQ<3>        U2               AG74     SOCKET4677_AZIFS054P001C01-SOCA
M_D_CPU0_SA_DQ<4>        J7               14       SCONN288_ADR50001P013C01-SCONNA
M_D_CPU0_SA_DQ<4>        J8               14       SCONN288_ADR50001P003C01-SCONNA
M_D_CPU0_SA_DQ<4>        U2               AC72     SOCKET4677_AZIFS054P001C01-SOCA
M_D_CPU0_SA_DQ<5>        J7               16       SCONN288_ADR50001P013C01-SCONNA
M_D_CPU0_SA_DQ<5>        J8               16       SCONN288_ADR50001P003C01-SCONNA
M_D_CPU0_SA_DQ<5>        U2               AD71     SOCKET4677_AZIFS054P001C01-SOCA
M_D_CPU0_SA_DQ<6>        J7               159      SCONN288_ADR50001P013C01-SCONNA
M_D_CPU0_SA_DQ<6>        J8               159      SCONN288_ADR50001P003C01-SCONNA
M_D_CPU0_SA_DQ<6>        U2               AG72     SOCKET4677_AZIFS054P001C01-SOCA
M_D_CPU0_SA_DQ<7>        J7               161      SCONN288_ADR50001P013C01-SCONNA
M_D_CPU0_SA_DQ<7>        J8               161      SCONN288_ADR50001P003C01-SCONNA
M_D_CPU0_SA_DQ<7>        U2               AF71     SOCKET4677_AZIFS054P001C01-SOCA
M_D_CPU0_SA_DQ<8>        J7               18       SCONN288_ADR50001P013C01-SCONNA
M_D_CPU0_SA_DQ<8>        J8               18       SCONN288_ADR50001P003C01-SCONNA
M_D_CPU0_SA_DQ<8>        U2               AL78     SOCKET4677_AZIFS054P001C01-SOCA
M_D_CPU0_SA_DQ<9>        J7               20       SCONN288_ADR50001P013C01-SCONNA
M_D_CPU0_SA_DQ<9>        J8               20       SCONN288_ADR50001P003C01-SCONNA
M_D_CPU0_SA_DQ<9>        U2               AK77     SOCKET4677_AZIFS054P001C01-SOCA
M_D_CPU0_SA_DQ<10>       J7               163      SCONN288_ADR50001P013C01-SCONNA
M_D_CPU0_SA_DQ<10>       J8               163      SCONN288_ADR50001P003C01-SCONNA
M_D_CPU0_SA_DQ<10>       U2               AN78     SOCKET4677_AZIFS054P001C01-SOCA
M_D_CPU0_SA_DQ<11>       J7               165      SCONN288_ADR50001P013C01-SCONNA
M_D_CPU0_SA_DQ<11>       J8               165      SCONN288_ADR50001P003C01-SCONNA
M_D_CPU0_SA_DQ<11>       U2               AP77     SOCKET4677_AZIFS054P001C01-SOCA
M_D_CPU0_SA_DQ<12>       J7               25       SCONN288_ADR50001P013C01-SCONNA
M_D_CPU0_SA_DQ<12>       J8               25       SCONN288_ADR50001P003C01-SCONNA
M_D_CPU0_SA_DQ<12>       U2               AK75     SOCKET4677_AZIFS054P001C01-SOCA
M_D_CPU0_SA_DQ<13>       J7               27       SCONN288_ADR50001P013C01-SCONNA
M_D_CPU0_SA_DQ<13>       J8               27       SCONN288_ADR50001P003C01-SCONNA
M_D_CPU0_SA_DQ<13>       U2               AL74     SOCKET4677_AZIFS054P001C01-SOCA
M_D_CPU0_SA_DQ<14>       J7               170      SCONN288_ADR50001P013C01-SCONNA
M_D_CPU0_SA_DQ<14>       J8               170      SCONN288_ADR50001P003C01-SCONNA
M_D_CPU0_SA_DQ<14>       U2               AP75     SOCKET4677_AZIFS054P001C01-SOCA
M_D_CPU0_SA_DQ<15>       J7               172      SCONN288_ADR50001P013C01-SCONNA
M_D_CPU0_SA_DQ<15>       J8               172      SCONN288_ADR50001P003C01-SCONNA
M_D_CPU0_SA_DQ<15>       U2               AN74     SOCKET4677_AZIFS054P001C01-SOCA
M_D_CPU0_SA_DQ<16>       J7               29       SCONN288_ADR50001P013C01-SCONNA
M_D_CPU0_SA_DQ<16>       J8               29       SCONN288_ADR50001P003C01-SCONNA
M_D_CPU0_SA_DQ<16>       U2               AL72     SOCKET4677_AZIFS054P001C01-SOCA
M_D_CPU0_SA_DQ<17>       J7               31       SCONN288_ADR50001P013C01-SCONNA
M_D_CPU0_SA_DQ<17>       J8               31       SCONN288_ADR50001P003C01-SCONNA
M_D_CPU0_SA_DQ<17>       U2               AK71     SOCKET4677_AZIFS054P001C01-SOCA
M_D_CPU0_SA_DQ<18>       J7               174      SCONN288_ADR50001P013C01-SCONNA
M_D_CPU0_SA_DQ<18>       J8               174      SCONN288_ADR50001P003C01-SCONNA
M_D_CPU0_SA_DQ<18>       U2               AN72     SOCKET4677_AZIFS054P001C01-SOCA
M_D_CPU0_SA_DQ<19>       J7               176      SCONN288_ADR50001P013C01-SCONNA
M_D_CPU0_SA_DQ<19>       J8               176      SCONN288_ADR50001P003C01-SCONNA
M_D_CPU0_SA_DQ<19>       U2               AP71     SOCKET4677_AZIFS054P001C01-SOCA
M_D_CPU0_SA_DQ<20>       J7               36       SCONN288_ADR50001P013C01-SCONNA
M_D_CPU0_SA_DQ<20>       J8               36       SCONN288_ADR50001P003C01-SCONNA
M_D_CPU0_SA_DQ<20>       U2               AK69     SOCKET4677_AZIFS054P001C01-SOCA
M_D_CPU0_SA_DQ<21>       J7               38       SCONN288_ADR50001P013C01-SCONNA
M_D_CPU0_SA_DQ<21>       J8               38       SCONN288_ADR50001P003C01-SCONNA
M_D_CPU0_SA_DQ<21>       U2               AL68     SOCKET4677_AZIFS054P001C01-SOCA
M_D_CPU0_SA_DQ<22>       J7               181      SCONN288_ADR50001P013C01-SCONNA
M_D_CPU0_SA_DQ<22>       J8               181      SCONN288_ADR50001P003C01-SCONNA
M_D_CPU0_SA_DQ<22>       U2               AP69     SOCKET4677_AZIFS054P001C01-SOCA
M_D_CPU0_SA_DQ<23>       J7               183      SCONN288_ADR50001P013C01-SCONNA
M_D_CPU0_SA_DQ<23>       J8               183      SCONN288_ADR50001P003C01-SCONNA
M_D_CPU0_SA_DQ<23>       U2               AN68     SOCKET4677_AZIFS054P001C01-SOCA
M_D_CPU0_SA_DQ<24>       J7               40       SCONN288_ADR50001P013C01-SCONNA
M_D_CPU0_SA_DQ<24>       J8               40       SCONN288_ADR50001P003C01-SCONNA
M_D_CPU0_SA_DQ<24>       U2               AL66     SOCKET4677_AZIFS054P001C01-SOCA
M_D_CPU0_SA_DQ<25>       J7               42       SCONN288_ADR50001P013C01-SCONNA
M_D_CPU0_SA_DQ<25>       J8               42       SCONN288_ADR50001P003C01-SCONNA
M_D_CPU0_SA_DQ<25>       U2               AK65     SOCKET4677_AZIFS054P001C01-SOCA
M_D_CPU0_SA_DQ<26>       J7               185      SCONN288_ADR50001P013C01-SCONNA
M_D_CPU0_SA_DQ<26>       J8               185      SCONN288_ADR50001P003C01-SCONNA
M_D_CPU0_SA_DQ<26>       U2               AN66     SOCKET4677_AZIFS054P001C01-SOCA
M_D_CPU0_SA_DQ<27>       J7               187      SCONN288_ADR50001P013C01-SCONNA
M_D_CPU0_SA_DQ<27>       J8               187      SCONN288_ADR50001P003C01-SCONNA
M_D_CPU0_SA_DQ<27>       U2               AP65     SOCKET4677_AZIFS054P001C01-SOCA
M_D_CPU0_SA_DQ<28>       J7               47       SCONN288_ADR50001P013C01-SCONNA
M_D_CPU0_SA_DQ<28>       J8               47       SCONN288_ADR50001P003C01-SCONNA
M_D_CPU0_SA_DQ<28>       U2               AK63     SOCKET4677_AZIFS054P001C01-SOCA
M_D_CPU0_SA_DQ<29>       J7               49       SCONN288_ADR50001P013C01-SCONNA
M_D_CPU0_SA_DQ<29>       J8               49       SCONN288_ADR50001P003C01-SCONNA
M_D_CPU0_SA_DQ<29>       U2               AL62     SOCKET4677_AZIFS054P001C01-SOCA
M_D_CPU0_SA_DQ<30>       J7               192      SCONN288_ADR50001P013C01-SCONNA
M_D_CPU0_SA_DQ<30>       J8               192      SCONN288_ADR50001P003C01-SCONNA
M_D_CPU0_SA_DQ<30>       U2               AP63     SOCKET4677_AZIFS054P001C01-SOCA
M_D_CPU0_SA_DQ<31>       J7               194      SCONN288_ADR50001P013C01-SCONNA
M_D_CPU0_SA_DQ<31>       J8               194      SCONN288_ADR50001P003C01-SCONNA
M_D_CPU0_SA_DQ<31>       U2               AN62     SOCKET4677_AZIFS054P001C01-SOCA
M_D_CPU0_SA_DQS_DN<0>    J7               12       SCONN288_ADR50001P013C01-SCONNA
M_D_CPU0_SA_DQS_DN<0>    J8               12       SCONN288_ADR50001P003C01-SCONNA
M_D_CPU0_SA_DQS_DN<0>    U2               AB73     SOCKET4677_AZIFS054P001C01-SOCA
M_D_CPU0_SA_DQS_DN<1>    J7               23       SCONN288_ADR50001P013C01-SCONNA
M_D_CPU0_SA_DQS_DN<1>    J8               23       SCONN288_ADR50001P003C01-SCONNA
M_D_CPU0_SA_DQS_DN<1>    U2               AJ76     SOCKET4677_AZIFS054P001C01-SOCA
M_D_CPU0_SA_DQS_DN<2>    J7               34       SCONN288_ADR50001P013C01-SCONNA
M_D_CPU0_SA_DQS_DN<2>    J8               34       SCONN288_ADR50001P003C01-SCONNA
M_D_CPU0_SA_DQS_DN<2>    U2               AJ70     SOCKET4677_AZIFS054P001C01-SOCA
M_D_CPU0_SA_DQS_DN<3>    J7               45       SCONN288_ADR50001P013C01-SCONNA
M_D_CPU0_SA_DQS_DN<3>    J8               45       SCONN288_ADR50001P003C01-SCONNA
M_D_CPU0_SA_DQS_DN<3>    U2               AJ64     SOCKET4677_AZIFS054P001C01-SOCA
M_D_CPU0_SA_DQS_DN<4>    J7               56       SCONN288_ADR50001P013C01-SCONNA
M_D_CPU0_SA_DQS_DN<4>    J8               56       SCONN288_ADR50001P003C01-SCONNA
M_D_CPU0_SA_DQS_DN<4>    U2               AJ58     SOCKET4677_AZIFS054P001C01-SOCA
M_D_CPU0_SA_DQS_DN<5>    J7               156      SCONN288_ADR50001P013C01-SCONNA
M_D_CPU0_SA_DQS_DN<5>    J8               156      SCONN288_ADR50001P003C01-SCONNA
M_D_CPU0_SA_DQS_DN<5>    U2               AH73     SOCKET4677_AZIFS054P001C01-SOCA
M_D_CPU0_SA_DQS_DN<6>    J7               167      SCONN288_ADR50001P013C01-SCONNA
M_D_CPU0_SA_DQS_DN<6>    J8               167      SCONN288_ADR50001P003C01-SCONNA
M_D_CPU0_SA_DQS_DN<6>    U2               AN76     SOCKET4677_AZIFS054P001C01-SOCA
M_D_CPU0_SA_DQS_DN<7>    J7               178      SCONN288_ADR50001P013C01-SCONNA
M_D_CPU0_SA_DQS_DN<7>    J8               178      SCONN288_ADR50001P003C01-SCONNA
M_D_CPU0_SA_DQS_DN<7>    U2               AN70     SOCKET4677_AZIFS054P001C01-SOCA
M_D_CPU0_SA_DQS_DN<8>    J7               189      SCONN288_ADR50001P013C01-SCONNA
M_D_CPU0_SA_DQS_DN<8>    J8               189      SCONN288_ADR50001P003C01-SCONNA
M_D_CPU0_SA_DQS_DN<8>    U2               AN64     SOCKET4677_AZIFS054P001C01-SOCA
M_D_CPU0_SA_DQS_DN<9>    J7               200      SCONN288_ADR50001P013C01-SCONNA
M_D_CPU0_SA_DQS_DN<9>    J8               200      SCONN288_ADR50001P003C01-SCONNA
M_D_CPU0_SA_DQS_DN<9>    U2               AN58     SOCKET4677_AZIFS054P001C01-SOCA
M_D_CPU0_SA_DQS_DP<0>    J7               11       SCONN288_ADR50001P013C01-SCONNA
M_D_CPU0_SA_DQS_DP<0>    J8               11       SCONN288_ADR50001P003C01-SCONNA
M_D_CPU0_SA_DQS_DP<0>    U2               AD73     SOCKET4677_AZIFS054P001C01-SOCA
M_D_CPU0_SA_DQS_DP<1>    J7               22       SCONN288_ADR50001P013C01-SCONNA
M_D_CPU0_SA_DQS_DP<1>    J8               22       SCONN288_ADR50001P003C01-SCONNA
M_D_CPU0_SA_DQS_DP<1>    U2               AL76     SOCKET4677_AZIFS054P001C01-SOCA
M_D_CPU0_SA_DQS_DP<2>    J7               33       SCONN288_ADR50001P013C01-SCONNA
M_D_CPU0_SA_DQS_DP<2>    J8               33       SCONN288_ADR50001P003C01-SCONNA
M_D_CPU0_SA_DQS_DP<2>    U2               AL70     SOCKET4677_AZIFS054P001C01-SOCA
M_D_CPU0_SA_DQS_DP<3>    J7               44       SCONN288_ADR50001P013C01-SCONNA
M_D_CPU0_SA_DQS_DP<3>    J8               44       SCONN288_ADR50001P003C01-SCONNA
M_D_CPU0_SA_DQS_DP<3>    U2               AL64     SOCKET4677_AZIFS054P001C01-SOCA
M_D_CPU0_SA_DQS_DP<4>    J7               55       SCONN288_ADR50001P013C01-SCONNA
M_D_CPU0_SA_DQS_DP<4>    J8               55       SCONN288_ADR50001P003C01-SCONNA
M_D_CPU0_SA_DQS_DP<4>    U2               AL58     SOCKET4677_AZIFS054P001C01-SOCA
M_D_CPU0_SA_DQS_DP<5>    J7               157      SCONN288_ADR50001P013C01-SCONNA
M_D_CPU0_SA_DQS_DP<5>    J8               157      SCONN288_ADR50001P003C01-SCONNA
M_D_CPU0_SA_DQS_DP<5>    U2               AF73     SOCKET4677_AZIFS054P001C01-SOCA
M_D_CPU0_SA_DQS_DP<6>    J7               168      SCONN288_ADR50001P013C01-SCONNA
M_D_CPU0_SA_DQS_DP<6>    J8               168      SCONN288_ADR50001P003C01-SCONNA
M_D_CPU0_SA_DQS_DP<6>    U2               AR76     SOCKET4677_AZIFS054P001C01-SOCA
M_D_CPU0_SA_DQS_DP<7>    J7               179      SCONN288_ADR50001P013C01-SCONNA
M_D_CPU0_SA_DQS_DP<7>    J8               179      SCONN288_ADR50001P003C01-SCONNA
M_D_CPU0_SA_DQS_DP<7>    U2               AR70     SOCKET4677_AZIFS054P001C01-SOCA
M_D_CPU0_SA_DQS_DP<8>    J7               190      SCONN288_ADR50001P013C01-SCONNA
M_D_CPU0_SA_DQS_DP<8>    J8               190      SCONN288_ADR50001P003C01-SCONNA
M_D_CPU0_SA_DQS_DP<8>    U2               AR64     SOCKET4677_AZIFS054P001C01-SOCA
M_D_CPU0_SA_DQS_DP<9>    J7               201      SCONN288_ADR50001P013C01-SCONNA
M_D_CPU0_SA_DQS_DP<9>    J8               201      SCONN288_ADR50001P003C01-SCONNA
M_D_CPU0_SA_DQS_DP<9>    U2               AR58     SOCKET4677_AZIFS054P001C01-SOCA
M_D_CPU0_SA_PAR          J7               74       SCONN288_ADR50001P013C01-SCONNA
M_D_CPU0_SA_PAR          J8               74       SCONN288_ADR50001P003C01-SCONNA
M_D_CPU0_SA_PAR          U2               AP44     SOCKET4677_AZIFS054P001C01-SOCA
M_D_CPU0_SA_RSP<0>       J7               86       SCONN288_ADR50001P013C01-SCONNA
M_D_CPU0_SA_RSP<0>       U2               AD51     SOCKET4677_AZIFS054P001C01-SOCA
M_D_CPU0_SA_RSP<1>       J8               86       SCONN288_ADR50001P003C01-SCONNA
M_D_CPU0_SA_RSP<1>       U2               AC50     SOCKET4677_AZIFS054P001C01-SOCA
M_D_CPU0_SB_CA<0>        J7               76       SCONN288_ADR50001P013C01-SCONNA
M_D_CPU0_SB_CA<0>        J8               76       SCONN288_ADR50001P003C01-SCONNA
M_D_CPU0_SB_CA<0>        U2               AK44     SOCKET4677_AZIFS054P001C01-SOCA
M_D_CPU0_SB_CA<1>        J7               221      SCONN288_ADR50001P013C01-SCONNA
M_D_CPU0_SB_CA<1>        J8               221      SCONN288_ADR50001P003C01-SCONNA
M_D_CPU0_SB_CA<1>        U2               AL43     SOCKET4677_AZIFS054P001C01-SOCA
M_D_CPU0_SB_CA<2>        J7               78       SCONN288_ADR50001P013C01-SCONNA
M_D_CPU0_SB_CA<2>        J8               78       SCONN288_ADR50001P003C01-SCONNA
M_D_CPU0_SB_CA<2>        U2               AD44     SOCKET4677_AZIFS054P001C01-SOCA
M_D_CPU0_SB_CA<3>        J7               223      SCONN288_ADR50001P013C01-SCONNA
M_D_CPU0_SB_CA<3>        J8               223      SCONN288_ADR50001P003C01-SCONNA
M_D_CPU0_SB_CA<3>        U2               AF44     SOCKET4677_AZIFS054P001C01-SOCA
M_D_CPU0_SB_CA<4>        J7               80       SCONN288_ADR50001P013C01-SCONNA
M_D_CPU0_SB_CA<4>        J8               80       SCONN288_ADR50001P003C01-SCONNA
M_D_CPU0_SB_CA<4>        U2               AC43     SOCKET4677_AZIFS054P001C01-SOCA
M_D_CPU0_SB_CA<5>        J7               225      SCONN288_ADR50001P013C01-SCONNA
M_D_CPU0_SB_CA<5>        J8               225      SCONN288_ADR50001P003C01-SCONNA
M_D_CPU0_SB_CA<5>        U2               AG43     SOCKET4677_AZIFS054P001C01-SOCA
M_D_CPU0_SB_CA<6>        J7               82       SCONN288_ADR50001P013C01-SCONNA
M_D_CPU0_SB_CA<6>        J8               82       SCONN288_ADR50001P003C01-SCONNA
M_D_CPU0_SB_CA<6>        U2               AB42     SOCKET4677_AZIFS054P001C01-SOCA
M_D_CPU0_SB_CB<0>        J7               96       SCONN288_ADR50001P013C01-SCONNA
M_D_CPU0_SB_CB<0>        J8               96       SCONN288_ADR50001P003C01-SCONNA
M_D_CPU0_SB_CB<0>        U2               AK38     SOCKET4677_AZIFS054P001C01-SOCA
M_D_CPU0_SB_CB<1>        J7               98       SCONN288_ADR50001P013C01-SCONNA
M_D_CPU0_SB_CB<1>        J8               98       SCONN288_ADR50001P003C01-SCONNA
M_D_CPU0_SB_CB<1>        U2               AL37     SOCKET4677_AZIFS054P001C01-SOCA
M_D_CPU0_SB_CB<2>        J7               241      SCONN288_ADR50001P013C01-SCONNA
M_D_CPU0_SB_CB<2>        J8               241      SCONN288_ADR50001P003C01-SCONNA
M_D_CPU0_SB_CB<2>        U2               AP38     SOCKET4677_AZIFS054P001C01-SOCA
M_D_CPU0_SB_CB<3>        J7               243      SCONN288_ADR50001P013C01-SCONNA
M_D_CPU0_SB_CB<3>        J8               243      SCONN288_ADR50001P003C01-SCONNA
M_D_CPU0_SB_CB<3>        U2               AN37     SOCKET4677_AZIFS054P001C01-SOCA
M_D_CPU0_SB_CB<4>        J7               89       SCONN288_ADR50001P013C01-SCONNA
M_D_CPU0_SB_CB<4>        J8               89       SCONN288_ADR50001P003C01-SCONNA
M_D_CPU0_SB_CB<4>        U2               AL41     SOCKET4677_AZIFS054P001C01-SOCA
M_D_CPU0_SB_CB<5>        J7               91       SCONN288_ADR50001P013C01-SCONNA
M_D_CPU0_SB_CB<5>        J8               91       SCONN288_ADR50001P003C01-SCONNA
M_D_CPU0_SB_CB<5>        U2               AK40     SOCKET4677_AZIFS054P001C01-SOCA
M_D_CPU0_SB_CB<6>        J7               234      SCONN288_ADR50001P013C01-SCONNA
M_D_CPU0_SB_CB<6>        J8               234      SCONN288_ADR50001P003C01-SCONNA
M_D_CPU0_SB_CB<6>        U2               AN41     SOCKET4677_AZIFS054P001C01-SOCA
M_D_CPU0_SB_CB<7>        J7               236      SCONN288_ADR50001P013C01-SCONNA
M_D_CPU0_SB_CB<7>        J8               236      SCONN288_ADR50001P003C01-SCONNA
M_D_CPU0_SB_CB<7>        U2               AP40     SOCKET4677_AZIFS054P001C01-SOCA
M_D_CPU0_SB_CS_N<0>      J7               84       SCONN288_ADR50001P013C01-SCONNA
M_D_CPU0_SB_CS_N<0>      U2               AC41     SOCKET4677_AZIFS054P001C01-SOCA
M_D_CPU0_SB_CS_N<1>      J7               229      SCONN288_ADR50001P013C01-SCONNA
M_D_CPU0_SB_CS_N<1>      U2               AG41     SOCKET4677_AZIFS054P001C01-SOCA
M_D_CPU0_SB_CS_N<2>      J8               84       SCONN288_ADR50001P003C01-SCONNA
M_D_CPU0_SB_CS_N<2>      U2               AF40     SOCKET4677_AZIFS054P001C01-SOCA
M_D_CPU0_SB_CS_N<3>      J8               229      SCONN288_ADR50001P003C01-SCONNA
M_D_CPU0_SB_CS_N<3>      U2               AD40     SOCKET4677_AZIFS054P001C01-SOCA
M_D_CPU0_SB_DQ<0>        J7               100      SCONN288_ADR50001P013C01-SCONNA
M_D_CPU0_SB_DQ<0>        J8               100      SCONN288_ADR50001P003C01-SCONNA
M_D_CPU0_SB_DQ<0>        U2               AL35     SOCKET4677_AZIFS054P001C01-SOCA
M_D_CPU0_SB_DQ<1>        J7               102      SCONN288_ADR50001P013C01-SCONNA
M_D_CPU0_SB_DQ<1>        J8               102      SCONN288_ADR50001P003C01-SCONNA
M_D_CPU0_SB_DQ<1>        U2               AK34     SOCKET4677_AZIFS054P001C01-SOCA
M_D_CPU0_SB_DQ<2>        J7               245      SCONN288_ADR50001P013C01-SCONNA
M_D_CPU0_SB_DQ<2>        J8               245      SCONN288_ADR50001P003C01-SCONNA
M_D_CPU0_SB_DQ<2>        U2               AN35     SOCKET4677_AZIFS054P001C01-SOCA
M_D_CPU0_SB_DQ<3>        J7               247      SCONN288_ADR50001P013C01-SCONNA
M_D_CPU0_SB_DQ<3>        J8               247      SCONN288_ADR50001P003C01-SCONNA
M_D_CPU0_SB_DQ<3>        U2               AP34     SOCKET4677_AZIFS054P001C01-SOCA
M_D_CPU0_SB_DQ<4>        J7               107      SCONN288_ADR50001P013C01-SCONNA
M_D_CPU0_SB_DQ<4>        J8               107      SCONN288_ADR50001P003C01-SCONNA
M_D_CPU0_SB_DQ<4>        U2               AK32     SOCKET4677_AZIFS054P001C01-SOCA
M_D_CPU0_SB_DQ<5>        J7               109      SCONN288_ADR50001P013C01-SCONNA
M_D_CPU0_SB_DQ<5>        J8               109      SCONN288_ADR50001P003C01-SCONNA
M_D_CPU0_SB_DQ<5>        U2               AL31     SOCKET4677_AZIFS054P001C01-SOCA
M_D_CPU0_SB_DQ<6>        J7               252      SCONN288_ADR50001P013C01-SCONNA
M_D_CPU0_SB_DQ<6>        J8               252      SCONN288_ADR50001P003C01-SCONNA
M_D_CPU0_SB_DQ<6>        U2               AP32     SOCKET4677_AZIFS054P001C01-SOCA
M_D_CPU0_SB_DQ<7>        J7               254      SCONN288_ADR50001P013C01-SCONNA
M_D_CPU0_SB_DQ<7>        J8               254      SCONN288_ADR50001P003C01-SCONNA
M_D_CPU0_SB_DQ<7>        U2               AN31     SOCKET4677_AZIFS054P001C01-SOCA
M_D_CPU0_SB_DQ<8>        J7               111      SCONN288_ADR50001P013C01-SCONNA
M_D_CPU0_SB_DQ<8>        J8               111      SCONN288_ADR50001P003C01-SCONNA
M_D_CPU0_SB_DQ<8>        U2               AL29     SOCKET4677_AZIFS054P001C01-SOCA
M_D_CPU0_SB_DQ<9>        J7               113      SCONN288_ADR50001P013C01-SCONNA
M_D_CPU0_SB_DQ<9>        J8               113      SCONN288_ADR50001P003C01-SCONNA
M_D_CPU0_SB_DQ<9>        U2               AK28     SOCKET4677_AZIFS054P001C01-SOCA
M_D_CPU0_SB_DQ<10>       J7               256      SCONN288_ADR50001P013C01-SCONNA
M_D_CPU0_SB_DQ<10>       J8               256      SCONN288_ADR50001P003C01-SCONNA
M_D_CPU0_SB_DQ<10>       U2               AN29     SOCKET4677_AZIFS054P001C01-SOCA
M_D_CPU0_SB_DQ<11>       J7               258      SCONN288_ADR50001P013C01-SCONNA
M_D_CPU0_SB_DQ<11>       J8               258      SCONN288_ADR50001P003C01-SCONNA
M_D_CPU0_SB_DQ<11>       U2               AP28     SOCKET4677_AZIFS054P001C01-SOCA
M_D_CPU0_SB_DQ<12>       J7               118      SCONN288_ADR50001P013C01-SCONNA
M_D_CPU0_SB_DQ<12>       J8               118      SCONN288_ADR50001P003C01-SCONNA
M_D_CPU0_SB_DQ<12>       U2               AK26     SOCKET4677_AZIFS054P001C01-SOCA
M_D_CPU0_SB_DQ<13>       J7               120      SCONN288_ADR50001P013C01-SCONNA
M_D_CPU0_SB_DQ<13>       J8               120      SCONN288_ADR50001P003C01-SCONNA
M_D_CPU0_SB_DQ<13>       U2               AL25     SOCKET4677_AZIFS054P001C01-SOCA
M_D_CPU0_SB_DQ<14>       J7               263      SCONN288_ADR50001P013C01-SCONNA
M_D_CPU0_SB_DQ<14>       J8               263      SCONN288_ADR50001P003C01-SCONNA
M_D_CPU0_SB_DQ<14>       U2               AP26     SOCKET4677_AZIFS054P001C01-SOCA
M_D_CPU0_SB_DQ<15>       J7               265      SCONN288_ADR50001P013C01-SCONNA
M_D_CPU0_SB_DQ<15>       J8               265      SCONN288_ADR50001P003C01-SCONNA
M_D_CPU0_SB_DQ<15>       U2               AN25     SOCKET4677_AZIFS054P001C01-SOCA
M_D_CPU0_SB_DQ<16>       J7               122      SCONN288_ADR50001P013C01-SCONNA
M_D_CPU0_SB_DQ<16>       J8               122      SCONN288_ADR50001P003C01-SCONNA
M_D_CPU0_SB_DQ<16>       U2               AD26     SOCKET4677_AZIFS054P001C01-SOCA
M_D_CPU0_SB_DQ<17>       J7               124      SCONN288_ADR50001P013C01-SCONNA
M_D_CPU0_SB_DQ<17>       J8               124      SCONN288_ADR50001P003C01-SCONNA
M_D_CPU0_SB_DQ<17>       U2               AC25     SOCKET4677_AZIFS054P001C01-SOCA
M_D_CPU0_SB_DQ<18>       J7               267      SCONN288_ADR50001P013C01-SCONNA
M_D_CPU0_SB_DQ<18>       J8               267      SCONN288_ADR50001P003C01-SCONNA
M_D_CPU0_SB_DQ<18>       U2               AF26     SOCKET4677_AZIFS054P001C01-SOCA
M_D_CPU0_SB_DQ<19>       J7               269      SCONN288_ADR50001P013C01-SCONNA
M_D_CPU0_SB_DQ<19>       J8               269      SCONN288_ADR50001P003C01-SCONNA
M_D_CPU0_SB_DQ<19>       U2               AG25     SOCKET4677_AZIFS054P001C01-SOCA
M_D_CPU0_SB_DQ<20>       J7               129      SCONN288_ADR50001P013C01-SCONNA
M_D_CPU0_SB_DQ<20>       J8               129      SCONN288_ADR50001P003C01-SCONNA
M_D_CPU0_SB_DQ<20>       U2               AC23     SOCKET4677_AZIFS054P001C01-SOCA
M_D_CPU0_SB_DQ<21>       J7               131      SCONN288_ADR50001P013C01-SCONNA
M_D_CPU0_SB_DQ<21>       J8               131      SCONN288_ADR50001P003C01-SCONNA
M_D_CPU0_SB_DQ<21>       U2               AD22     SOCKET4677_AZIFS054P001C01-SOCA
M_D_CPU0_SB_DQ<22>       J7               274      SCONN288_ADR50001P013C01-SCONNA
M_D_CPU0_SB_DQ<22>       J8               274      SCONN288_ADR50001P003C01-SCONNA
M_D_CPU0_SB_DQ<22>       U2               AG23     SOCKET4677_AZIFS054P001C01-SOCA
M_D_CPU0_SB_DQ<23>       J7               276      SCONN288_ADR50001P013C01-SCONNA
M_D_CPU0_SB_DQ<23>       J8               276      SCONN288_ADR50001P003C01-SCONNA
M_D_CPU0_SB_DQ<23>       U2               AF22     SOCKET4677_AZIFS054P001C01-SOCA
M_D_CPU0_SB_DQ<24>       J7               133      SCONN288_ADR50001P013C01-SCONNA
M_D_CPU0_SB_DQ<24>       J8               133      SCONN288_ADR50001P003C01-SCONNA
M_D_CPU0_SB_DQ<24>       U2               AL23     SOCKET4677_AZIFS054P001C01-SOCA
M_D_CPU0_SB_DQ<25>       J7               135      SCONN288_ADR50001P013C01-SCONNA
M_D_CPU0_SB_DQ<25>       J8               135      SCONN288_ADR50001P003C01-SCONNA
M_D_CPU0_SB_DQ<25>       U2               AK22     SOCKET4677_AZIFS054P001C01-SOCA
M_D_CPU0_SB_DQ<26>       J7               278      SCONN288_ADR50001P013C01-SCONNA
M_D_CPU0_SB_DQ<26>       J8               278      SCONN288_ADR50001P003C01-SCONNA
M_D_CPU0_SB_DQ<26>       U2               AN23     SOCKET4677_AZIFS054P001C01-SOCA
M_D_CPU0_SB_DQ<27>       J7               280      SCONN288_ADR50001P013C01-SCONNA
M_D_CPU0_SB_DQ<27>       J8               280      SCONN288_ADR50001P003C01-SCONNA
M_D_CPU0_SB_DQ<27>       U2               AP22     SOCKET4677_AZIFS054P001C01-SOCA
M_D_CPU0_SB_DQ<28>       J7               140      SCONN288_ADR50001P013C01-SCONNA
M_D_CPU0_SB_DQ<28>       J8               140      SCONN288_ADR50001P003C01-SCONNA
M_D_CPU0_SB_DQ<28>       U2               AK20     SOCKET4677_AZIFS054P001C01-SOCA
M_D_CPU0_SB_DQ<29>       J7               142      SCONN288_ADR50001P013C01-SCONNA
M_D_CPU0_SB_DQ<29>       J8               142      SCONN288_ADR50001P003C01-SCONNA
M_D_CPU0_SB_DQ<29>       U2               AL19     SOCKET4677_AZIFS054P001C01-SOCA
M_D_CPU0_SB_DQ<30>       J7               285      SCONN288_ADR50001P013C01-SCONNA
M_D_CPU0_SB_DQ<30>       J8               285      SCONN288_ADR50001P003C01-SCONNA
M_D_CPU0_SB_DQ<30>       U2               AP20     SOCKET4677_AZIFS054P001C01-SOCA
M_D_CPU0_SB_DQ<31>       J7               287      SCONN288_ADR50001P013C01-SCONNA
M_D_CPU0_SB_DQ<31>       J8               287      SCONN288_ADR50001P003C01-SCONNA
M_D_CPU0_SB_DQ<31>       U2               AN19     SOCKET4677_AZIFS054P001C01-SOCA
M_D_CPU0_SB_DQS_DN<0>    J7               105      SCONN288_ADR50001P013C01-SCONNA
M_D_CPU0_SB_DQS_DN<0>    J8               105      SCONN288_ADR50001P003C01-SCONNA
M_D_CPU0_SB_DQS_DN<0>    U2               AJ33     SOCKET4677_AZIFS054P001C01-SOCA
M_D_CPU0_SB_DQS_DN<1>    J7               116      SCONN288_ADR50001P013C01-SCONNA
M_D_CPU0_SB_DQS_DN<1>    J8               116      SCONN288_ADR50001P003C01-SCONNA
M_D_CPU0_SB_DQS_DN<1>    U2               AJ27     SOCKET4677_AZIFS054P001C01-SOCA
M_D_CPU0_SB_DQS_DN<2>    J7               127      SCONN288_ADR50001P013C01-SCONNA
M_D_CPU0_SB_DQS_DN<2>    J8               127      SCONN288_ADR50001P003C01-SCONNA
M_D_CPU0_SB_DQS_DN<2>    U2               AB24     SOCKET4677_AZIFS054P001C01-SOCA
M_D_CPU0_SB_DQS_DN<3>    J7               138      SCONN288_ADR50001P013C01-SCONNA
M_D_CPU0_SB_DQS_DN<3>    J8               138      SCONN288_ADR50001P003C01-SCONNA
M_D_CPU0_SB_DQS_DN<3>    U2               AJ21     SOCKET4677_AZIFS054P001C01-SOCA
M_D_CPU0_SB_DQS_DN<4>    J7               238      SCONN288_ADR50001P013C01-SCONNA
M_D_CPU0_SB_DQS_DN<4>    J8               238      SCONN288_ADR50001P003C01-SCONNA
M_D_CPU0_SB_DQS_DN<4>    U2               AR39     SOCKET4677_AZIFS054P001C01-SOCA
M_D_CPU0_SB_DQS_DN<5>    J7               249      SCONN288_ADR50001P013C01-SCONNA
M_D_CPU0_SB_DQS_DN<5>    J8               249      SCONN288_ADR50001P003C01-SCONNA
M_D_CPU0_SB_DQS_DN<5>    U2               AN33     SOCKET4677_AZIFS054P001C01-SOCA
M_D_CPU0_SB_DQS_DN<6>    J7               260      SCONN288_ADR50001P013C01-SCONNA
M_D_CPU0_SB_DQS_DN<6>    J8               260      SCONN288_ADR50001P003C01-SCONNA
M_D_CPU0_SB_DQS_DN<6>    U2               AN27     SOCKET4677_AZIFS054P001C01-SOCA
M_D_CPU0_SB_DQS_DN<7>    J7               271      SCONN288_ADR50001P013C01-SCONNA
M_D_CPU0_SB_DQS_DN<7>    J8               271      SCONN288_ADR50001P003C01-SCONNA
M_D_CPU0_SB_DQS_DN<7>    U2               AF24     SOCKET4677_AZIFS054P001C01-SOCA
M_D_CPU0_SB_DQS_DN<8>    J7               282      SCONN288_ADR50001P013C01-SCONNA
M_D_CPU0_SB_DQS_DN<8>    J8               282      SCONN288_ADR50001P003C01-SCONNA
M_D_CPU0_SB_DQS_DN<8>    U2               AN21     SOCKET4677_AZIFS054P001C01-SOCA
M_D_CPU0_SB_DQS_DN<9>    J7               94       SCONN288_ADR50001P013C01-SCONNA
M_D_CPU0_SB_DQS_DN<9>    J8               94       SCONN288_ADR50001P003C01-SCONNA
M_D_CPU0_SB_DQS_DN<9>    U2               AJ39     SOCKET4677_AZIFS054P001C01-SOCA
M_D_CPU0_SB_DQS_DP<0>    J7               104      SCONN288_ADR50001P013C01-SCONNA
M_D_CPU0_SB_DQS_DP<0>    J8               104      SCONN288_ADR50001P003C01-SCONNA
M_D_CPU0_SB_DQS_DP<0>    U2               AL33     SOCKET4677_AZIFS054P001C01-SOCA
M_D_CPU0_SB_DQS_DP<1>    J7               115      SCONN288_ADR50001P013C01-SCONNA
M_D_CPU0_SB_DQS_DP<1>    J8               115      SCONN288_ADR50001P003C01-SCONNA
M_D_CPU0_SB_DQS_DP<1>    U2               AL27     SOCKET4677_AZIFS054P001C01-SOCA
M_D_CPU0_SB_DQS_DP<2>    J7               126      SCONN288_ADR50001P013C01-SCONNA
M_D_CPU0_SB_DQS_DP<2>    J8               126      SCONN288_ADR50001P003C01-SCONNA
M_D_CPU0_SB_DQS_DP<2>    U2               AD24     SOCKET4677_AZIFS054P001C01-SOCA
M_D_CPU0_SB_DQS_DP<3>    J7               137      SCONN288_ADR50001P013C01-SCONNA
M_D_CPU0_SB_DQS_DP<3>    J8               137      SCONN288_ADR50001P003C01-SCONNA
M_D_CPU0_SB_DQS_DP<3>    U2               AL21     SOCKET4677_AZIFS054P001C01-SOCA
M_D_CPU0_SB_DQS_DP<4>    J7               239      SCONN288_ADR50001P013C01-SCONNA
M_D_CPU0_SB_DQS_DP<4>    J8               239      SCONN288_ADR50001P003C01-SCONNA
M_D_CPU0_SB_DQS_DP<4>    U2               AN39     SOCKET4677_AZIFS054P001C01-SOCA
M_D_CPU0_SB_DQS_DP<5>    J7               250      SCONN288_ADR50001P013C01-SCONNA
M_D_CPU0_SB_DQS_DP<5>    J8               250      SCONN288_ADR50001P003C01-SCONNA
M_D_CPU0_SB_DQS_DP<5>    U2               AR33     SOCKET4677_AZIFS054P001C01-SOCA
M_D_CPU0_SB_DQS_DP<6>    J7               261      SCONN288_ADR50001P013C01-SCONNA
M_D_CPU0_SB_DQS_DP<6>    J8               261      SCONN288_ADR50001P003C01-SCONNA
M_D_CPU0_SB_DQS_DP<6>    U2               AR27     SOCKET4677_AZIFS054P001C01-SOCA
M_D_CPU0_SB_DQS_DP<7>    J7               272      SCONN288_ADR50001P013C01-SCONNA
M_D_CPU0_SB_DQS_DP<7>    J8               272      SCONN288_ADR50001P003C01-SCONNA
M_D_CPU0_SB_DQS_DP<7>    U2               AH24     SOCKET4677_AZIFS054P001C01-SOCA
M_D_CPU0_SB_DQS_DP<8>    J7               283      SCONN288_ADR50001P013C01-SCONNA
M_D_CPU0_SB_DQS_DP<8>    J8               283      SCONN288_ADR50001P003C01-SCONNA
M_D_CPU0_SB_DQS_DP<8>    U2               AR21     SOCKET4677_AZIFS054P001C01-SOCA
M_D_CPU0_SB_DQS_DP<9>    J7               93       SCONN288_ADR50001P013C01-SCONNA
M_D_CPU0_SB_DQS_DP<9>    J8               93       SCONN288_ADR50001P003C01-SCONNA
M_D_CPU0_SB_DQS_DP<9>    U2               AL39     SOCKET4677_AZIFS054P001C01-SOCA
M_D_CPU0_SB_PAR          J7               227      SCONN288_ADR50001P013C01-SCONNA
M_D_CPU0_SB_PAR          J8               227      SCONN288_ADR50001P003C01-SCONNA
M_D_CPU0_SB_PAR          U2               AH42     SOCKET4677_AZIFS054P001C01-SOCA
M_D_CPU0_SB_RSP<0>       J7               87       SCONN288_ADR50001P013C01-SCONNA
M_D_CPU0_SB_RSP<0>       U2               AF51     SOCKET4677_AZIFS054P001C01-SOCA
M_D_CPU0_SB_RSP<1>       J8               87       SCONN288_ADR50001P003C01-SCONNA
M_D_CPU0_SB_RSP<1>       U2               AG50     SOCKET4677_AZIFS054P001C01-SOCA
M_D_CPU1_ALERT_N         J23              62       SCONN288_ADR50001P013C01-SCONNA
M_D_CPU1_ALERT_N         J24              62       SCONN288_ADR50001P003C01-SCONNA
M_D_CPU1_ALERT_N         U1               AV47     SOCKET4677_AZIFS054P001C01-SOCA
M_D_CPU1_CLK_DN<0>       J23              218      SCONN288_ADR50001P013C01-SCONNA
M_D_CPU1_CLK_DN<0>       U1               AJ45     SOCKET4677_AZIFS054P001C01-SOCA
M_D_CPU1_CLK_DN<1>       J24              218      SCONN288_ADR50001P003C01-SCONNA
M_D_CPU1_CLK_DN<1>       U1               AN45     SOCKET4677_AZIFS054P001C01-SOCA
M_D_CPU1_CLK_DP<0>       J23              217      SCONN288_ADR50001P013C01-SCONNA
M_D_CPU1_CLK_DP<0>       U1               AL45     SOCKET4677_AZIFS054P001C01-SOCA
M_D_CPU1_CLK_DP<1>       J24              217      SCONN288_ADR50001P003C01-SCONNA
M_D_CPU1_CLK_DP<1>       U1               AR45     SOCKET4677_AZIFS054P001C01-SOCA
M_D_CPU1_SA_CA<0>        J23              66       SCONN288_ADR50001P013C01-SCONNA
M_D_CPU1_SA_CA<0>        J24              66       SCONN288_ADR50001P003C01-SCONNA
M_D_CPU1_SA_CA<0>        U1               AJ52     SOCKET4677_AZIFS054P001C01-SOCA
M_D_CPU1_SA_CA<1>        J23              211      SCONN288_ADR50001P013C01-SCONNA
M_D_CPU1_SA_CA<1>        J24              211      SCONN288_ADR50001P003C01-SCONNA
M_D_CPU1_SA_CA<1>        U1               AR52     SOCKET4677_AZIFS054P001C01-SOCA
M_D_CPU1_SA_CA<2>        J23              68       SCONN288_ADR50001P013C01-SCONNA
M_D_CPU1_SA_CA<2>        J24              68       SCONN288_ADR50001P003C01-SCONNA
M_D_CPU1_SA_CA<2>        U1               AK51     SOCKET4677_AZIFS054P001C01-SOCA
M_D_CPU1_SA_CA<3>        J23              213      SCONN288_ADR50001P013C01-SCONNA
M_D_CPU1_SA_CA<3>        J24              213      SCONN288_ADR50001P003C01-SCONNA
M_D_CPU1_SA_CA<3>        U1               AP51     SOCKET4677_AZIFS054P001C01-SOCA
M_D_CPU1_SA_CA<4>        J23              70       SCONN288_ADR50001P013C01-SCONNA
M_D_CPU1_SA_CA<4>        J24              70       SCONN288_ADR50001P003C01-SCONNA
M_D_CPU1_SA_CA<4>        U1               AL50     SOCKET4677_AZIFS054P001C01-SOCA
M_D_CPU1_SA_CA<5>        J23              215      SCONN288_ADR50001P013C01-SCONNA
M_D_CPU1_SA_CA<5>        J24              215      SCONN288_ADR50001P003C01-SCONNA
M_D_CPU1_SA_CA<5>        U1               AN50     SOCKET4677_AZIFS054P001C01-SOCA
M_D_CPU1_SA_CA<6>        J23              72       SCONN288_ADR50001P013C01-SCONNA
M_D_CPU1_SA_CA<6>        J24              72       SCONN288_ADR50001P003C01-SCONNA
M_D_CPU1_SA_CA<6>        U1               AN43     SOCKET4677_AZIFS054P001C01-SOCA
M_D_CPU1_SA_CB<0>        J23              51       SCONN288_ADR50001P013C01-SCONNA
M_D_CPU1_SA_CB<0>        J24              51       SCONN288_ADR50001P003C01-SCONNA
M_D_CPU1_SA_CB<0>        U1               AL60     SOCKET4677_AZIFS054P001C01-SOCA
M_D_CPU1_SA_CB<1>        J23              53       SCONN288_ADR50001P013C01-SCONNA
M_D_CPU1_SA_CB<1>        J24              53       SCONN288_ADR50001P003C01-SCONNA
M_D_CPU1_SA_CB<1>        U1               AK59     SOCKET4677_AZIFS054P001C01-SOCA
M_D_CPU1_SA_CB<2>        J23              196      SCONN288_ADR50001P013C01-SCONNA
M_D_CPU1_SA_CB<2>        J24              196      SCONN288_ADR50001P003C01-SCONNA
M_D_CPU1_SA_CB<2>        U1               AN60     SOCKET4677_AZIFS054P001C01-SOCA
M_D_CPU1_SA_CB<3>        J23              198      SCONN288_ADR50001P013C01-SCONNA
M_D_CPU1_SA_CB<3>        J24              198      SCONN288_ADR50001P003C01-SCONNA
M_D_CPU1_SA_CB<3>        U1               AP59     SOCKET4677_AZIFS054P001C01-SOCA
M_D_CPU1_SA_CB<4>        J23              58       SCONN288_ADR50001P013C01-SCONNA
M_D_CPU1_SA_CB<4>        J24              58       SCONN288_ADR50001P003C01-SCONNA
M_D_CPU1_SA_CB<4>        U1               AK57     SOCKET4677_AZIFS054P001C01-SOCA
M_D_CPU1_SA_CB<5>        J23              60       SCONN288_ADR50001P013C01-SCONNA
M_D_CPU1_SA_CB<5>        J24              60       SCONN288_ADR50001P003C01-SCONNA
M_D_CPU1_SA_CB<5>        U1               AL56     SOCKET4677_AZIFS054P001C01-SOCA
M_D_CPU1_SA_CB<6>        J23              203      SCONN288_ADR50001P013C01-SCONNA
M_D_CPU1_SA_CB<6>        J24              203      SCONN288_ADR50001P003C01-SCONNA
M_D_CPU1_SA_CB<6>        U1               AP57     SOCKET4677_AZIFS054P001C01-SOCA
M_D_CPU1_SA_CB<7>        J23              205      SCONN288_ADR50001P013C01-SCONNA
M_D_CPU1_SA_CB<7>        J24              205      SCONN288_ADR50001P003C01-SCONNA
M_D_CPU1_SA_CB<7>        U1               AN56     SOCKET4677_AZIFS054P001C01-SOCA
M_D_CPU1_SA_CS_N<0>      J23              64       SCONN288_ADR50001P013C01-SCONNA
M_D_CPU1_SA_CS_N<0>      U1               AL54     SOCKET4677_AZIFS054P001C01-SOCA
M_D_CPU1_SA_CS_N<1>      J23              209      SCONN288_ADR50001P013C01-SCONNA
M_D_CPU1_SA_CS_N<1>      U1               AK53     SOCKET4677_AZIFS054P001C01-SOCA
M_D_CPU1_SA_CS_N<2>      J24              64       SCONN288_ADR50001P003C01-SCONNA
M_D_CPU1_SA_CS_N<2>      U1               AN54     SOCKET4677_AZIFS054P001C01-SOCA
M_D_CPU1_SA_CS_N<3>      J24              209      SCONN288_ADR50001P003C01-SCONNA
M_D_CPU1_SA_CS_N<3>      U1               AP53     SOCKET4677_AZIFS054P001C01-SOCA
M_D_CPU1_SA_DQ<0>        J23              7        SCONN288_ADR50001P013C01-SCONNA
M_D_CPU1_SA_DQ<0>        J24              7        SCONN288_ADR50001P003C01-SCONNA
M_D_CPU1_SA_DQ<0>        U1               AD75     SOCKET4677_AZIFS054P001C01-SOCA
M_D_CPU1_SA_DQ<1>        J23              9        SCONN288_ADR50001P013C01-SCONNA
M_D_CPU1_SA_DQ<1>        J24              9        SCONN288_ADR50001P003C01-SCONNA
M_D_CPU1_SA_DQ<1>        U1               AC74     SOCKET4677_AZIFS054P001C01-SOCA
M_D_CPU1_SA_DQ<2>        J23              152      SCONN288_ADR50001P013C01-SCONNA
M_D_CPU1_SA_DQ<2>        J24              152      SCONN288_ADR50001P003C01-SCONNA
M_D_CPU1_SA_DQ<2>        U1               AF75     SOCKET4677_AZIFS054P001C01-SOCA
M_D_CPU1_SA_DQ<3>        J23              154      SCONN288_ADR50001P013C01-SCONNA
M_D_CPU1_SA_DQ<3>        J24              154      SCONN288_ADR50001P003C01-SCONNA
M_D_CPU1_SA_DQ<3>        U1               AG74     SOCKET4677_AZIFS054P001C01-SOCA
M_D_CPU1_SA_DQ<4>        J23              14       SCONN288_ADR50001P013C01-SCONNA
M_D_CPU1_SA_DQ<4>        J24              14       SCONN288_ADR50001P003C01-SCONNA
M_D_CPU1_SA_DQ<4>        U1               AC72     SOCKET4677_AZIFS054P001C01-SOCA
M_D_CPU1_SA_DQ<5>        J23              16       SCONN288_ADR50001P013C01-SCONNA
M_D_CPU1_SA_DQ<5>        J24              16       SCONN288_ADR50001P003C01-SCONNA
M_D_CPU1_SA_DQ<5>        U1               AD71     SOCKET4677_AZIFS054P001C01-SOCA
M_D_CPU1_SA_DQ<6>        J23              159      SCONN288_ADR50001P013C01-SCONNA
M_D_CPU1_SA_DQ<6>        J24              159      SCONN288_ADR50001P003C01-SCONNA
M_D_CPU1_SA_DQ<6>        U1               AG72     SOCKET4677_AZIFS054P001C01-SOCA
M_D_CPU1_SA_DQ<7>        J23              161      SCONN288_ADR50001P013C01-SCONNA
M_D_CPU1_SA_DQ<7>        J24              161      SCONN288_ADR50001P003C01-SCONNA
M_D_CPU1_SA_DQ<7>        U1               AF71     SOCKET4677_AZIFS054P001C01-SOCA
M_D_CPU1_SA_DQ<8>        J23              18       SCONN288_ADR50001P013C01-SCONNA
M_D_CPU1_SA_DQ<8>        J24              18       SCONN288_ADR50001P003C01-SCONNA
M_D_CPU1_SA_DQ<8>        U1               AL78     SOCKET4677_AZIFS054P001C01-SOCA
M_D_CPU1_SA_DQ<9>        J23              20       SCONN288_ADR50001P013C01-SCONNA
M_D_CPU1_SA_DQ<9>        J24              20       SCONN288_ADR50001P003C01-SCONNA
M_D_CPU1_SA_DQ<9>        U1               AK77     SOCKET4677_AZIFS054P001C01-SOCA
M_D_CPU1_SA_DQ<10>       J23              163      SCONN288_ADR50001P013C01-SCONNA
M_D_CPU1_SA_DQ<10>       J24              163      SCONN288_ADR50001P003C01-SCONNA
M_D_CPU1_SA_DQ<10>       U1               AN78     SOCKET4677_AZIFS054P001C01-SOCA
M_D_CPU1_SA_DQ<11>       J23              165      SCONN288_ADR50001P013C01-SCONNA
M_D_CPU1_SA_DQ<11>       J24              165      SCONN288_ADR50001P003C01-SCONNA
M_D_CPU1_SA_DQ<11>       U1               AP77     SOCKET4677_AZIFS054P001C01-SOCA
M_D_CPU1_SA_DQ<12>       J23              25       SCONN288_ADR50001P013C01-SCONNA
M_D_CPU1_SA_DQ<12>       J24              25       SCONN288_ADR50001P003C01-SCONNA
M_D_CPU1_SA_DQ<12>       U1               AK75     SOCKET4677_AZIFS054P001C01-SOCA
M_D_CPU1_SA_DQ<13>       J23              27       SCONN288_ADR50001P013C01-SCONNA
M_D_CPU1_SA_DQ<13>       J24              27       SCONN288_ADR50001P003C01-SCONNA
M_D_CPU1_SA_DQ<13>       U1               AL74     SOCKET4677_AZIFS054P001C01-SOCA
M_D_CPU1_SA_DQ<14>       J23              170      SCONN288_ADR50001P013C01-SCONNA
M_D_CPU1_SA_DQ<14>       J24              170      SCONN288_ADR50001P003C01-SCONNA
M_D_CPU1_SA_DQ<14>       U1               AP75     SOCKET4677_AZIFS054P001C01-SOCA
M_D_CPU1_SA_DQ<15>       J23              172      SCONN288_ADR50001P013C01-SCONNA
M_D_CPU1_SA_DQ<15>       J24              172      SCONN288_ADR50001P003C01-SCONNA
M_D_CPU1_SA_DQ<15>       U1               AN74     SOCKET4677_AZIFS054P001C01-SOCA
M_D_CPU1_SA_DQ<16>       J23              29       SCONN288_ADR50001P013C01-SCONNA
M_D_CPU1_SA_DQ<16>       J24              29       SCONN288_ADR50001P003C01-SCONNA
M_D_CPU1_SA_DQ<16>       U1               AL72     SOCKET4677_AZIFS054P001C01-SOCA
M_D_CPU1_SA_DQ<17>       J23              31       SCONN288_ADR50001P013C01-SCONNA
M_D_CPU1_SA_DQ<17>       J24              31       SCONN288_ADR50001P003C01-SCONNA
M_D_CPU1_SA_DQ<17>       U1               AK71     SOCKET4677_AZIFS054P001C01-SOCA
M_D_CPU1_SA_DQ<18>       J23              174      SCONN288_ADR50001P013C01-SCONNA
M_D_CPU1_SA_DQ<18>       J24              174      SCONN288_ADR50001P003C01-SCONNA
M_D_CPU1_SA_DQ<18>       U1               AN72     SOCKET4677_AZIFS054P001C01-SOCA
M_D_CPU1_SA_DQ<19>       J23              176      SCONN288_ADR50001P013C01-SCONNA
M_D_CPU1_SA_DQ<19>       J24              176      SCONN288_ADR50001P003C01-SCONNA
M_D_CPU1_SA_DQ<19>       U1               AP71     SOCKET4677_AZIFS054P001C01-SOCA
M_D_CPU1_SA_DQ<20>       J23              36       SCONN288_ADR50001P013C01-SCONNA
M_D_CPU1_SA_DQ<20>       J24              36       SCONN288_ADR50001P003C01-SCONNA
M_D_CPU1_SA_DQ<20>       U1               AK69     SOCKET4677_AZIFS054P001C01-SOCA
M_D_CPU1_SA_DQ<21>       J23              38       SCONN288_ADR50001P013C01-SCONNA
M_D_CPU1_SA_DQ<21>       J24              38       SCONN288_ADR50001P003C01-SCONNA
M_D_CPU1_SA_DQ<21>       U1               AL68     SOCKET4677_AZIFS054P001C01-SOCA
M_D_CPU1_SA_DQ<22>       J23              181      SCONN288_ADR50001P013C01-SCONNA
M_D_CPU1_SA_DQ<22>       J24              181      SCONN288_ADR50001P003C01-SCONNA
M_D_CPU1_SA_DQ<22>       U1               AP69     SOCKET4677_AZIFS054P001C01-SOCA
M_D_CPU1_SA_DQ<23>       J23              183      SCONN288_ADR50001P013C01-SCONNA
M_D_CPU1_SA_DQ<23>       J24              183      SCONN288_ADR50001P003C01-SCONNA
M_D_CPU1_SA_DQ<23>       U1               AN68     SOCKET4677_AZIFS054P001C01-SOCA
M_D_CPU1_SA_DQ<24>       J23              40       SCONN288_ADR50001P013C01-SCONNA
M_D_CPU1_SA_DQ<24>       J24              40       SCONN288_ADR50001P003C01-SCONNA
M_D_CPU1_SA_DQ<24>       U1               AL66     SOCKET4677_AZIFS054P001C01-SOCA
M_D_CPU1_SA_DQ<25>       J23              42       SCONN288_ADR50001P013C01-SCONNA
M_D_CPU1_SA_DQ<25>       J24              42       SCONN288_ADR50001P003C01-SCONNA
M_D_CPU1_SA_DQ<25>       U1               AK65     SOCKET4677_AZIFS054P001C01-SOCA
M_D_CPU1_SA_DQ<26>       J23              185      SCONN288_ADR50001P013C01-SCONNA
M_D_CPU1_SA_DQ<26>       J24              185      SCONN288_ADR50001P003C01-SCONNA
M_D_CPU1_SA_DQ<26>       U1               AN66     SOCKET4677_AZIFS054P001C01-SOCA
M_D_CPU1_SA_DQ<27>       J23              187      SCONN288_ADR50001P013C01-SCONNA
M_D_CPU1_SA_DQ<27>       J24              187      SCONN288_ADR50001P003C01-SCONNA
M_D_CPU1_SA_DQ<27>       U1               AP65     SOCKET4677_AZIFS054P001C01-SOCA
M_D_CPU1_SA_DQ<28>       J23              47       SCONN288_ADR50001P013C01-SCONNA
M_D_CPU1_SA_DQ<28>       J24              47       SCONN288_ADR50001P003C01-SCONNA
M_D_CPU1_SA_DQ<28>       U1               AK63     SOCKET4677_AZIFS054P001C01-SOCA
M_D_CPU1_SA_DQ<29>       J23              49       SCONN288_ADR50001P013C01-SCONNA
M_D_CPU1_SA_DQ<29>       J24              49       SCONN288_ADR50001P003C01-SCONNA
M_D_CPU1_SA_DQ<29>       U1               AL62     SOCKET4677_AZIFS054P001C01-SOCA
M_D_CPU1_SA_DQ<30>       J23              192      SCONN288_ADR50001P013C01-SCONNA
M_D_CPU1_SA_DQ<30>       J24              192      SCONN288_ADR50001P003C01-SCONNA
M_D_CPU1_SA_DQ<30>       U1               AP63     SOCKET4677_AZIFS054P001C01-SOCA
M_D_CPU1_SA_DQ<31>       J23              194      SCONN288_ADR50001P013C01-SCONNA
M_D_CPU1_SA_DQ<31>       J24              194      SCONN288_ADR50001P003C01-SCONNA
M_D_CPU1_SA_DQ<31>       U1               AN62     SOCKET4677_AZIFS054P001C01-SOCA
M_D_CPU1_SA_DQS_DN<0>    J23              12       SCONN288_ADR50001P013C01-SCONNA
M_D_CPU1_SA_DQS_DN<0>    J24              12       SCONN288_ADR50001P003C01-SCONNA
M_D_CPU1_SA_DQS_DN<0>    U1               AB73     SOCKET4677_AZIFS054P001C01-SOCA
M_D_CPU1_SA_DQS_DN<1>    J23              23       SCONN288_ADR50001P013C01-SCONNA
M_D_CPU1_SA_DQS_DN<1>    J24              23       SCONN288_ADR50001P003C01-SCONNA
M_D_CPU1_SA_DQS_DN<1>    U1               AJ76     SOCKET4677_AZIFS054P001C01-SOCA
M_D_CPU1_SA_DQS_DN<2>    J23              34       SCONN288_ADR50001P013C01-SCONNA
M_D_CPU1_SA_DQS_DN<2>    J24              34       SCONN288_ADR50001P003C01-SCONNA
M_D_CPU1_SA_DQS_DN<2>    U1               AJ70     SOCKET4677_AZIFS054P001C01-SOCA
M_D_CPU1_SA_DQS_DN<3>    J23              45       SCONN288_ADR50001P013C01-SCONNA
M_D_CPU1_SA_DQS_DN<3>    J24              45       SCONN288_ADR50001P003C01-SCONNA
M_D_CPU1_SA_DQS_DN<3>    U1               AJ64     SOCKET4677_AZIFS054P001C01-SOCA
M_D_CPU1_SA_DQS_DN<4>    J23              56       SCONN288_ADR50001P013C01-SCONNA
M_D_CPU1_SA_DQS_DN<4>    J24              56       SCONN288_ADR50001P003C01-SCONNA
M_D_CPU1_SA_DQS_DN<4>    U1               AJ58     SOCKET4677_AZIFS054P001C01-SOCA
M_D_CPU1_SA_DQS_DN<5>    J23              156      SCONN288_ADR50001P013C01-SCONNA
M_D_CPU1_SA_DQS_DN<5>    J24              156      SCONN288_ADR50001P003C01-SCONNA
M_D_CPU1_SA_DQS_DN<5>    U1               AH73     SOCKET4677_AZIFS054P001C01-SOCA
M_D_CPU1_SA_DQS_DN<6>    J23              167      SCONN288_ADR50001P013C01-SCONNA
M_D_CPU1_SA_DQS_DN<6>    J24              167      SCONN288_ADR50001P003C01-SCONNA
M_D_CPU1_SA_DQS_DN<6>    U1               AN76     SOCKET4677_AZIFS054P001C01-SOCA
M_D_CPU1_SA_DQS_DN<7>    J23              178      SCONN288_ADR50001P013C01-SCONNA
M_D_CPU1_SA_DQS_DN<7>    J24              178      SCONN288_ADR50001P003C01-SCONNA
M_D_CPU1_SA_DQS_DN<7>    U1               AN70     SOCKET4677_AZIFS054P001C01-SOCA
M_D_CPU1_SA_DQS_DN<8>    J23              189      SCONN288_ADR50001P013C01-SCONNA
M_D_CPU1_SA_DQS_DN<8>    J24              189      SCONN288_ADR50001P003C01-SCONNA
M_D_CPU1_SA_DQS_DN<8>    U1               AN64     SOCKET4677_AZIFS054P001C01-SOCA
M_D_CPU1_SA_DQS_DN<9>    J23              200      SCONN288_ADR50001P013C01-SCONNA
M_D_CPU1_SA_DQS_DN<9>    J24              200      SCONN288_ADR50001P003C01-SCONNA
M_D_CPU1_SA_DQS_DN<9>    U1               AN58     SOCKET4677_AZIFS054P001C01-SOCA
M_D_CPU1_SA_DQS_DP<0>    J23              11       SCONN288_ADR50001P013C01-SCONNA
M_D_CPU1_SA_DQS_DP<0>    J24              11       SCONN288_ADR50001P003C01-SCONNA
M_D_CPU1_SA_DQS_DP<0>    U1               AD73     SOCKET4677_AZIFS054P001C01-SOCA
M_D_CPU1_SA_DQS_DP<1>    J23              22       SCONN288_ADR50001P013C01-SCONNA
M_D_CPU1_SA_DQS_DP<1>    J24              22       SCONN288_ADR50001P003C01-SCONNA
M_D_CPU1_SA_DQS_DP<1>    U1               AL76     SOCKET4677_AZIFS054P001C01-SOCA
M_D_CPU1_SA_DQS_DP<2>    J23              33       SCONN288_ADR50001P013C01-SCONNA
M_D_CPU1_SA_DQS_DP<2>    J24              33       SCONN288_ADR50001P003C01-SCONNA
M_D_CPU1_SA_DQS_DP<2>    U1               AL70     SOCKET4677_AZIFS054P001C01-SOCA
M_D_CPU1_SA_DQS_DP<3>    J23              44       SCONN288_ADR50001P013C01-SCONNA
M_D_CPU1_SA_DQS_DP<3>    J24              44       SCONN288_ADR50001P003C01-SCONNA
M_D_CPU1_SA_DQS_DP<3>    U1               AL64     SOCKET4677_AZIFS054P001C01-SOCA
M_D_CPU1_SA_DQS_DP<4>    J23              55       SCONN288_ADR50001P013C01-SCONNA
M_D_CPU1_SA_DQS_DP<4>    J24              55       SCONN288_ADR50001P003C01-SCONNA
M_D_CPU1_SA_DQS_DP<4>    U1               AL58     SOCKET4677_AZIFS054P001C01-SOCA
M_D_CPU1_SA_DQS_DP<5>    J23              157      SCONN288_ADR50001P013C01-SCONNA
M_D_CPU1_SA_DQS_DP<5>    J24              157      SCONN288_ADR50001P003C01-SCONNA
M_D_CPU1_SA_DQS_DP<5>    U1               AF73     SOCKET4677_AZIFS054P001C01-SOCA
M_D_CPU1_SA_DQS_DP<6>    J23              168      SCONN288_ADR50001P013C01-SCONNA
M_D_CPU1_SA_DQS_DP<6>    J24              168      SCONN288_ADR50001P003C01-SCONNA
M_D_CPU1_SA_DQS_DP<6>    U1               AR76     SOCKET4677_AZIFS054P001C01-SOCA
M_D_CPU1_SA_DQS_DP<7>    J23              179      SCONN288_ADR50001P013C01-SCONNA
M_D_CPU1_SA_DQS_DP<7>    J24              179      SCONN288_ADR50001P003C01-SCONNA
M_D_CPU1_SA_DQS_DP<7>    U1               AR70     SOCKET4677_AZIFS054P001C01-SOCA
M_D_CPU1_SA_DQS_DP<8>    J23              190      SCONN288_ADR50001P013C01-SCONNA
M_D_CPU1_SA_DQS_DP<8>    J24              190      SCONN288_ADR50001P003C01-SCONNA
M_D_CPU1_SA_DQS_DP<8>    U1               AR64     SOCKET4677_AZIFS054P001C01-SOCA
M_D_CPU1_SA_DQS_DP<9>    J23              201      SCONN288_ADR50001P013C01-SCONNA
M_D_CPU1_SA_DQS_DP<9>    J24              201      SCONN288_ADR50001P003C01-SCONNA
M_D_CPU1_SA_DQS_DP<9>    U1               AR58     SOCKET4677_AZIFS054P001C01-SOCA
M_D_CPU1_SA_PAR          J23              74       SCONN288_ADR50001P013C01-SCONNA
M_D_CPU1_SA_PAR          J24              74       SCONN288_ADR50001P003C01-SCONNA
M_D_CPU1_SA_PAR          U1               AP44     SOCKET4677_AZIFS054P001C01-SOCA
M_D_CPU1_SA_RSP<0>       J23              86       SCONN288_ADR50001P013C01-SCONNA
M_D_CPU1_SA_RSP<0>       U1               AD51     SOCKET4677_AZIFS054P001C01-SOCA
M_D_CPU1_SA_RSP<1>       J24              86       SCONN288_ADR50001P003C01-SCONNA
M_D_CPU1_SA_RSP<1>       U1               AC50     SOCKET4677_AZIFS054P001C01-SOCA
M_D_CPU1_SB_CA<0>        J23              76       SCONN288_ADR50001P013C01-SCONNA
M_D_CPU1_SB_CA<0>        J24              76       SCONN288_ADR50001P003C01-SCONNA
M_D_CPU1_SB_CA<0>        U1               AK44     SOCKET4677_AZIFS054P001C01-SOCA
M_D_CPU1_SB_CA<1>        J23              221      SCONN288_ADR50001P013C01-SCONNA
M_D_CPU1_SB_CA<1>        J24              221      SCONN288_ADR50001P003C01-SCONNA
M_D_CPU1_SB_CA<1>        U1               AL43     SOCKET4677_AZIFS054P001C01-SOCA
M_D_CPU1_SB_CA<2>        J23              78       SCONN288_ADR50001P013C01-SCONNA
M_D_CPU1_SB_CA<2>        J24              78       SCONN288_ADR50001P003C01-SCONNA
M_D_CPU1_SB_CA<2>        U1               AD44     SOCKET4677_AZIFS054P001C01-SOCA
M_D_CPU1_SB_CA<3>        J23              223      SCONN288_ADR50001P013C01-SCONNA
M_D_CPU1_SB_CA<3>        J24              223      SCONN288_ADR50001P003C01-SCONNA
M_D_CPU1_SB_CA<3>        U1               AF44     SOCKET4677_AZIFS054P001C01-SOCA
M_D_CPU1_SB_CA<4>        J23              80       SCONN288_ADR50001P013C01-SCONNA
M_D_CPU1_SB_CA<4>        J24              80       SCONN288_ADR50001P003C01-SCONNA
M_D_CPU1_SB_CA<4>        U1               AC43     SOCKET4677_AZIFS054P001C01-SOCA
M_D_CPU1_SB_CA<5>        J23              225      SCONN288_ADR50001P013C01-SCONNA
M_D_CPU1_SB_CA<5>        J24              225      SCONN288_ADR50001P003C01-SCONNA
M_D_CPU1_SB_CA<5>        U1               AG43     SOCKET4677_AZIFS054P001C01-SOCA
M_D_CPU1_SB_CA<6>        J23              82       SCONN288_ADR50001P013C01-SCONNA
M_D_CPU1_SB_CA<6>        J24              82       SCONN288_ADR50001P003C01-SCONNA
M_D_CPU1_SB_CA<6>        U1               AB42     SOCKET4677_AZIFS054P001C01-SOCA
M_D_CPU1_SB_CB<0>        J23              96       SCONN288_ADR50001P013C01-SCONNA
M_D_CPU1_SB_CB<0>        J24              96       SCONN288_ADR50001P003C01-SCONNA
M_D_CPU1_SB_CB<0>        U1               AK38     SOCKET4677_AZIFS054P001C01-SOCA
M_D_CPU1_SB_CB<1>        J23              98       SCONN288_ADR50001P013C01-SCONNA
M_D_CPU1_SB_CB<1>        J24              98       SCONN288_ADR50001P003C01-SCONNA
M_D_CPU1_SB_CB<1>        U1               AL37     SOCKET4677_AZIFS054P001C01-SOCA
M_D_CPU1_SB_CB<2>        J23              241      SCONN288_ADR50001P013C01-SCONNA
M_D_CPU1_SB_CB<2>        J24              241      SCONN288_ADR50001P003C01-SCONNA
M_D_CPU1_SB_CB<2>        U1               AP38     SOCKET4677_AZIFS054P001C01-SOCA
M_D_CPU1_SB_CB<3>        J23              243      SCONN288_ADR50001P013C01-SCONNA
M_D_CPU1_SB_CB<3>        J24              243      SCONN288_ADR50001P003C01-SCONNA
M_D_CPU1_SB_CB<3>        U1               AN37     SOCKET4677_AZIFS054P001C01-SOCA
M_D_CPU1_SB_CB<4>        J23              89       SCONN288_ADR50001P013C01-SCONNA
M_D_CPU1_SB_CB<4>        J24              89       SCONN288_ADR50001P003C01-SCONNA
M_D_CPU1_SB_CB<4>        U1               AL41     SOCKET4677_AZIFS054P001C01-SOCA
M_D_CPU1_SB_CB<5>        J23              91       SCONN288_ADR50001P013C01-SCONNA
M_D_CPU1_SB_CB<5>        J24              91       SCONN288_ADR50001P003C01-SCONNA
M_D_CPU1_SB_CB<5>        U1               AK40     SOCKET4677_AZIFS054P001C01-SOCA
M_D_CPU1_SB_CB<6>        J23              234      SCONN288_ADR50001P013C01-SCONNA
M_D_CPU1_SB_CB<6>        J24              234      SCONN288_ADR50001P003C01-SCONNA
M_D_CPU1_SB_CB<6>        U1               AN41     SOCKET4677_AZIFS054P001C01-SOCA
M_D_CPU1_SB_CB<7>        J23              236      SCONN288_ADR50001P013C01-SCONNA
M_D_CPU1_SB_CB<7>        J24              236      SCONN288_ADR50001P003C01-SCONNA
M_D_CPU1_SB_CB<7>        U1               AP40     SOCKET4677_AZIFS054P001C01-SOCA
M_D_CPU1_SB_CS_N<0>      J23              84       SCONN288_ADR50001P013C01-SCONNA
M_D_CPU1_SB_CS_N<0>      U1               AC41     SOCKET4677_AZIFS054P001C01-SOCA
M_D_CPU1_SB_CS_N<1>      J23              229      SCONN288_ADR50001P013C01-SCONNA
M_D_CPU1_SB_CS_N<1>      U1               AG41     SOCKET4677_AZIFS054P001C01-SOCA
M_D_CPU1_SB_CS_N<2>      J24              84       SCONN288_ADR50001P003C01-SCONNA
M_D_CPU1_SB_CS_N<2>      U1               AF40     SOCKET4677_AZIFS054P001C01-SOCA
M_D_CPU1_SB_CS_N<3>      J24              229      SCONN288_ADR50001P003C01-SCONNA
M_D_CPU1_SB_CS_N<3>      U1               AD40     SOCKET4677_AZIFS054P001C01-SOCA
M_D_CPU1_SB_DQ<0>        J23              100      SCONN288_ADR50001P013C01-SCONNA
M_D_CPU1_SB_DQ<0>        J24              100      SCONN288_ADR50001P003C01-SCONNA
M_D_CPU1_SB_DQ<0>        U1               AL35     SOCKET4677_AZIFS054P001C01-SOCA
M_D_CPU1_SB_DQ<1>        J23              102      SCONN288_ADR50001P013C01-SCONNA
M_D_CPU1_SB_DQ<1>        J24              102      SCONN288_ADR50001P003C01-SCONNA
M_D_CPU1_SB_DQ<1>        U1               AK34     SOCKET4677_AZIFS054P001C01-SOCA
M_D_CPU1_SB_DQ<2>        J23              245      SCONN288_ADR50001P013C01-SCONNA
M_D_CPU1_SB_DQ<2>        J24              245      SCONN288_ADR50001P003C01-SCONNA
M_D_CPU1_SB_DQ<2>        U1               AN35     SOCKET4677_AZIFS054P001C01-SOCA
M_D_CPU1_SB_DQ<3>        J23              247      SCONN288_ADR50001P013C01-SCONNA
M_D_CPU1_SB_DQ<3>        J24              247      SCONN288_ADR50001P003C01-SCONNA
M_D_CPU1_SB_DQ<3>        U1               AP34     SOCKET4677_AZIFS054P001C01-SOCA
M_D_CPU1_SB_DQ<4>        J23              107      SCONN288_ADR50001P013C01-SCONNA
M_D_CPU1_SB_DQ<4>        J24              107      SCONN288_ADR50001P003C01-SCONNA
M_D_CPU1_SB_DQ<4>        U1               AK32     SOCKET4677_AZIFS054P001C01-SOCA
M_D_CPU1_SB_DQ<5>        J23              109      SCONN288_ADR50001P013C01-SCONNA
M_D_CPU1_SB_DQ<5>        J24              109      SCONN288_ADR50001P003C01-SCONNA
M_D_CPU1_SB_DQ<5>        U1               AL31     SOCKET4677_AZIFS054P001C01-SOCA
M_D_CPU1_SB_DQ<6>        J23              252      SCONN288_ADR50001P013C01-SCONNA
M_D_CPU1_SB_DQ<6>        J24              252      SCONN288_ADR50001P003C01-SCONNA
M_D_CPU1_SB_DQ<6>        U1               AP32     SOCKET4677_AZIFS054P001C01-SOCA
M_D_CPU1_SB_DQ<7>        J23              254      SCONN288_ADR50001P013C01-SCONNA
M_D_CPU1_SB_DQ<7>        J24              254      SCONN288_ADR50001P003C01-SCONNA
M_D_CPU1_SB_DQ<7>        U1               AN31     SOCKET4677_AZIFS054P001C01-SOCA
M_D_CPU1_SB_DQ<8>        J23              111      SCONN288_ADR50001P013C01-SCONNA
M_D_CPU1_SB_DQ<8>        J24              111      SCONN288_ADR50001P003C01-SCONNA
M_D_CPU1_SB_DQ<8>        U1               AL29     SOCKET4677_AZIFS054P001C01-SOCA
M_D_CPU1_SB_DQ<9>        J23              113      SCONN288_ADR50001P013C01-SCONNA
M_D_CPU1_SB_DQ<9>        J24              113      SCONN288_ADR50001P003C01-SCONNA
M_D_CPU1_SB_DQ<9>        U1               AK28     SOCKET4677_AZIFS054P001C01-SOCA
M_D_CPU1_SB_DQ<10>       J23              256      SCONN288_ADR50001P013C01-SCONNA
M_D_CPU1_SB_DQ<10>       J24              256      SCONN288_ADR50001P003C01-SCONNA
M_D_CPU1_SB_DQ<10>       U1               AN29     SOCKET4677_AZIFS054P001C01-SOCA
M_D_CPU1_SB_DQ<11>       J23              258      SCONN288_ADR50001P013C01-SCONNA
M_D_CPU1_SB_DQ<11>       J24              258      SCONN288_ADR50001P003C01-SCONNA
M_D_CPU1_SB_DQ<11>       U1               AP28     SOCKET4677_AZIFS054P001C01-SOCA
M_D_CPU1_SB_DQ<12>       J23              118      SCONN288_ADR50001P013C01-SCONNA
M_D_CPU1_SB_DQ<12>       J24              118      SCONN288_ADR50001P003C01-SCONNA
M_D_CPU1_SB_DQ<12>       U1               AK26     SOCKET4677_AZIFS054P001C01-SOCA
M_D_CPU1_SB_DQ<13>       J23              120      SCONN288_ADR50001P013C01-SCONNA
M_D_CPU1_SB_DQ<13>       J24              120      SCONN288_ADR50001P003C01-SCONNA
M_D_CPU1_SB_DQ<13>       U1               AL25     SOCKET4677_AZIFS054P001C01-SOCA
M_D_CPU1_SB_DQ<14>       J23              263      SCONN288_ADR50001P013C01-SCONNA
M_D_CPU1_SB_DQ<14>       J24              263      SCONN288_ADR50001P003C01-SCONNA
M_D_CPU1_SB_DQ<14>       U1               AP26     SOCKET4677_AZIFS054P001C01-SOCA
M_D_CPU1_SB_DQ<15>       J23              265      SCONN288_ADR50001P013C01-SCONNA
M_D_CPU1_SB_DQ<15>       J24              265      SCONN288_ADR50001P003C01-SCONNA
M_D_CPU1_SB_DQ<15>       U1               AN25     SOCKET4677_AZIFS054P001C01-SOCA
M_D_CPU1_SB_DQ<16>       J23              122      SCONN288_ADR50001P013C01-SCONNA
M_D_CPU1_SB_DQ<16>       J24              122      SCONN288_ADR50001P003C01-SCONNA
M_D_CPU1_SB_DQ<16>       U1               AD26     SOCKET4677_AZIFS054P001C01-SOCA
M_D_CPU1_SB_DQ<17>       J23              124      SCONN288_ADR50001P013C01-SCONNA
M_D_CPU1_SB_DQ<17>       J24              124      SCONN288_ADR50001P003C01-SCONNA
M_D_CPU1_SB_DQ<17>       U1               AC25     SOCKET4677_AZIFS054P001C01-SOCA
M_D_CPU1_SB_DQ<18>       J23              267      SCONN288_ADR50001P013C01-SCONNA
M_D_CPU1_SB_DQ<18>       J24              267      SCONN288_ADR50001P003C01-SCONNA
M_D_CPU1_SB_DQ<18>       U1               AF26     SOCKET4677_AZIFS054P001C01-SOCA
M_D_CPU1_SB_DQ<19>       J23              269      SCONN288_ADR50001P013C01-SCONNA
M_D_CPU1_SB_DQ<19>       J24              269      SCONN288_ADR50001P003C01-SCONNA
M_D_CPU1_SB_DQ<19>       U1               AG25     SOCKET4677_AZIFS054P001C01-SOCA
M_D_CPU1_SB_DQ<20>       J23              129      SCONN288_ADR50001P013C01-SCONNA
M_D_CPU1_SB_DQ<20>       J24              129      SCONN288_ADR50001P003C01-SCONNA
M_D_CPU1_SB_DQ<20>       U1               AC23     SOCKET4677_AZIFS054P001C01-SOCA
M_D_CPU1_SB_DQ<21>       J23              131      SCONN288_ADR50001P013C01-SCONNA
M_D_CPU1_SB_DQ<21>       J24              131      SCONN288_ADR50001P003C01-SCONNA
M_D_CPU1_SB_DQ<21>       U1               AD22     SOCKET4677_AZIFS054P001C01-SOCA
M_D_CPU1_SB_DQ<22>       J23              274      SCONN288_ADR50001P013C01-SCONNA
M_D_CPU1_SB_DQ<22>       J24              274      SCONN288_ADR50001P003C01-SCONNA
M_D_CPU1_SB_DQ<22>       U1               AG23     SOCKET4677_AZIFS054P001C01-SOCA
M_D_CPU1_SB_DQ<23>       J23              276      SCONN288_ADR50001P013C01-SCONNA
M_D_CPU1_SB_DQ<23>       J24              276      SCONN288_ADR50001P003C01-SCONNA
M_D_CPU1_SB_DQ<23>       U1               AF22     SOCKET4677_AZIFS054P001C01-SOCA
M_D_CPU1_SB_DQ<24>       J23              133      SCONN288_ADR50001P013C01-SCONNA
M_D_CPU1_SB_DQ<24>       J24              133      SCONN288_ADR50001P003C01-SCONNA
M_D_CPU1_SB_DQ<24>       U1               AL23     SOCKET4677_AZIFS054P001C01-SOCA
M_D_CPU1_SB_DQ<25>       J23              135      SCONN288_ADR50001P013C01-SCONNA
M_D_CPU1_SB_DQ<25>       J24              135      SCONN288_ADR50001P003C01-SCONNA
M_D_CPU1_SB_DQ<25>       U1               AK22     SOCKET4677_AZIFS054P001C01-SOCA
M_D_CPU1_SB_DQ<26>       J23              278      SCONN288_ADR50001P013C01-SCONNA
M_D_CPU1_SB_DQ<26>       J24              278      SCONN288_ADR50001P003C01-SCONNA
M_D_CPU1_SB_DQ<26>       U1               AN23     SOCKET4677_AZIFS054P001C01-SOCA
M_D_CPU1_SB_DQ<27>       J23              280      SCONN288_ADR50001P013C01-SCONNA
M_D_CPU1_SB_DQ<27>       J24              280      SCONN288_ADR50001P003C01-SCONNA
M_D_CPU1_SB_DQ<27>       U1               AP22     SOCKET4677_AZIFS054P001C01-SOCA
M_D_CPU1_SB_DQ<28>       J23              140      SCONN288_ADR50001P013C01-SCONNA
M_D_CPU1_SB_DQ<28>       J24              140      SCONN288_ADR50001P003C01-SCONNA
M_D_CPU1_SB_DQ<28>       U1               AK20     SOCKET4677_AZIFS054P001C01-SOCA
M_D_CPU1_SB_DQ<29>       J23              142      SCONN288_ADR50001P013C01-SCONNA
M_D_CPU1_SB_DQ<29>       J24              142      SCONN288_ADR50001P003C01-SCONNA
M_D_CPU1_SB_DQ<29>       U1               AL19     SOCKET4677_AZIFS054P001C01-SOCA
M_D_CPU1_SB_DQ<30>       J23              285      SCONN288_ADR50001P013C01-SCONNA
M_D_CPU1_SB_DQ<30>       J24              285      SCONN288_ADR50001P003C01-SCONNA
M_D_CPU1_SB_DQ<30>       U1               AP20     SOCKET4677_AZIFS054P001C01-SOCA
M_D_CPU1_SB_DQ<31>       J23              287      SCONN288_ADR50001P013C01-SCONNA
M_D_CPU1_SB_DQ<31>       J24              287      SCONN288_ADR50001P003C01-SCONNA
M_D_CPU1_SB_DQ<31>       U1               AN19     SOCKET4677_AZIFS054P001C01-SOCA
M_D_CPU1_SB_DQS_DN<0>    J23              105      SCONN288_ADR50001P013C01-SCONNA
M_D_CPU1_SB_DQS_DN<0>    J24              105      SCONN288_ADR50001P003C01-SCONNA
M_D_CPU1_SB_DQS_DN<0>    U1               AJ33     SOCKET4677_AZIFS054P001C01-SOCA
M_D_CPU1_SB_DQS_DN<1>    J23              116      SCONN288_ADR50001P013C01-SCONNA
M_D_CPU1_SB_DQS_DN<1>    J24              116      SCONN288_ADR50001P003C01-SCONNA
M_D_CPU1_SB_DQS_DN<1>    U1               AJ27     SOCKET4677_AZIFS054P001C01-SOCA
M_D_CPU1_SB_DQS_DN<2>    J23              127      SCONN288_ADR50001P013C01-SCONNA
M_D_CPU1_SB_DQS_DN<2>    J24              127      SCONN288_ADR50001P003C01-SCONNA
M_D_CPU1_SB_DQS_DN<2>    U1               AB24     SOCKET4677_AZIFS054P001C01-SOCA
M_D_CPU1_SB_DQS_DN<3>    J23              138      SCONN288_ADR50001P013C01-SCONNA
M_D_CPU1_SB_DQS_DN<3>    J24              138      SCONN288_ADR50001P003C01-SCONNA
M_D_CPU1_SB_DQS_DN<3>    U1               AJ21     SOCKET4677_AZIFS054P001C01-SOCA
M_D_CPU1_SB_DQS_DN<4>    J23              238      SCONN288_ADR50001P013C01-SCONNA
M_D_CPU1_SB_DQS_DN<4>    J24              238      SCONN288_ADR50001P003C01-SCONNA
M_D_CPU1_SB_DQS_DN<4>    U1               AR39     SOCKET4677_AZIFS054P001C01-SOCA
M_D_CPU1_SB_DQS_DN<5>    J23              249      SCONN288_ADR50001P013C01-SCONNA
M_D_CPU1_SB_DQS_DN<5>    J24              249      SCONN288_ADR50001P003C01-SCONNA
M_D_CPU1_SB_DQS_DN<5>    U1               AN33     SOCKET4677_AZIFS054P001C01-SOCA
M_D_CPU1_SB_DQS_DN<6>    J23              260      SCONN288_ADR50001P013C01-SCONNA
M_D_CPU1_SB_DQS_DN<6>    J24              260      SCONN288_ADR50001P003C01-SCONNA
M_D_CPU1_SB_DQS_DN<6>    U1               AN27     SOCKET4677_AZIFS054P001C01-SOCA
M_D_CPU1_SB_DQS_DN<7>    J23              271      SCONN288_ADR50001P013C01-SCONNA
M_D_CPU1_SB_DQS_DN<7>    J24              271      SCONN288_ADR50001P003C01-SCONNA
M_D_CPU1_SB_DQS_DN<7>    U1               AF24     SOCKET4677_AZIFS054P001C01-SOCA
M_D_CPU1_SB_DQS_DN<8>    J23              282      SCONN288_ADR50001P013C01-SCONNA
M_D_CPU1_SB_DQS_DN<8>    J24              282      SCONN288_ADR50001P003C01-SCONNA
M_D_CPU1_SB_DQS_DN<8>    U1               AN21     SOCKET4677_AZIFS054P001C01-SOCA
M_D_CPU1_SB_DQS_DN<9>    J23              94       SCONN288_ADR50001P013C01-SCONNA
M_D_CPU1_SB_DQS_DN<9>    J24              94       SCONN288_ADR50001P003C01-SCONNA
M_D_CPU1_SB_DQS_DN<9>    U1               AJ39     SOCKET4677_AZIFS054P001C01-SOCA
M_D_CPU1_SB_DQS_DP<0>    J23              104      SCONN288_ADR50001P013C01-SCONNA
M_D_CPU1_SB_DQS_DP<0>    J24              104      SCONN288_ADR50001P003C01-SCONNA
M_D_CPU1_SB_DQS_DP<0>    U1               AL33     SOCKET4677_AZIFS054P001C01-SOCA
M_D_CPU1_SB_DQS_DP<1>    J23              115      SCONN288_ADR50001P013C01-SCONNA
M_D_CPU1_SB_DQS_DP<1>    J24              115      SCONN288_ADR50001P003C01-SCONNA
M_D_CPU1_SB_DQS_DP<1>    U1               AL27     SOCKET4677_AZIFS054P001C01-SOCA
M_D_CPU1_SB_DQS_DP<2>    J23              126      SCONN288_ADR50001P013C01-SCONNA
M_D_CPU1_SB_DQS_DP<2>    J24              126      SCONN288_ADR50001P003C01-SCONNA
M_D_CPU1_SB_DQS_DP<2>    U1               AD24     SOCKET4677_AZIFS054P001C01-SOCA
M_D_CPU1_SB_DQS_DP<3>    J23              137      SCONN288_ADR50001P013C01-SCONNA
M_D_CPU1_SB_DQS_DP<3>    J24              137      SCONN288_ADR50001P003C01-SCONNA
M_D_CPU1_SB_DQS_DP<3>    U1               AL21     SOCKET4677_AZIFS054P001C01-SOCA
M_D_CPU1_SB_DQS_DP<4>    J23              239      SCONN288_ADR50001P013C01-SCONNA
M_D_CPU1_SB_DQS_DP<4>    J24              239      SCONN288_ADR50001P003C01-SCONNA
M_D_CPU1_SB_DQS_DP<4>    U1               AN39     SOCKET4677_AZIFS054P001C01-SOCA
M_D_CPU1_SB_DQS_DP<5>    J23              250      SCONN288_ADR50001P013C01-SCONNA
M_D_CPU1_SB_DQS_DP<5>    J24              250      SCONN288_ADR50001P003C01-SCONNA
M_D_CPU1_SB_DQS_DP<5>    U1               AR33     SOCKET4677_AZIFS054P001C01-SOCA
M_D_CPU1_SB_DQS_DP<6>    J23              261      SCONN288_ADR50001P013C01-SCONNA
M_D_CPU1_SB_DQS_DP<6>    J24              261      SCONN288_ADR50001P003C01-SCONNA
M_D_CPU1_SB_DQS_DP<6>    U1               AR27     SOCKET4677_AZIFS054P001C01-SOCA
M_D_CPU1_SB_DQS_DP<7>    J23              272      SCONN288_ADR50001P013C01-SCONNA
M_D_CPU1_SB_DQS_DP<7>    J24              272      SCONN288_ADR50001P003C01-SCONNA
M_D_CPU1_SB_DQS_DP<7>    U1               AH24     SOCKET4677_AZIFS054P001C01-SOCA
M_D_CPU1_SB_DQS_DP<8>    J23              283      SCONN288_ADR50001P013C01-SCONNA
M_D_CPU1_SB_DQS_DP<8>    J24              283      SCONN288_ADR50001P003C01-SCONNA
M_D_CPU1_SB_DQS_DP<8>    U1               AR21     SOCKET4677_AZIFS054P001C01-SOCA
M_D_CPU1_SB_DQS_DP<9>    J23              93       SCONN288_ADR50001P013C01-SCONNA
M_D_CPU1_SB_DQS_DP<9>    J24              93       SCONN288_ADR50001P003C01-SCONNA
M_D_CPU1_SB_DQS_DP<9>    U1               AL39     SOCKET4677_AZIFS054P001C01-SOCA
M_D_CPU1_SB_PAR          J23              227      SCONN288_ADR50001P013C01-SCONNA
M_D_CPU1_SB_PAR          J24              227      SCONN288_ADR50001P003C01-SCONNA
M_D_CPU1_SB_PAR          U1               AH42     SOCKET4677_AZIFS054P001C01-SOCA
M_D_CPU1_SB_RSP<0>       J23              87       SCONN288_ADR50001P013C01-SCONNA
M_D_CPU1_SB_RSP<0>       U1               AF51     SOCKET4677_AZIFS054P001C01-SOCA
M_D_CPU1_SB_RSP<1>       J24              87       SCONN288_ADR50001P003C01-SCONNA
M_D_CPU1_SB_RSP<1>       U1               AG50     SOCKET4677_AZIFS054P001C01-SOCA
M_E_CPU0_ALERT_N         J9               62       SCONN288_ADR50001P013C01-SCONNA
M_E_CPU0_ALERT_N         J10              62       SCONN288_ADR50001P003C01-SCONNA
M_E_CPU0_ALERT_N         U2               CY47     SOCKET4677_AZIFS054P001C01-SOCA
M_E_CPU0_CLK_DN<0>       J9               218      SCONN288_ADR50001P013C01-SCONNA
M_E_CPU0_CLK_DN<0>       U2               EJ45     SOCKET4677_AZIFS054P001C01-SOCA
M_E_CPU0_CLK_DN<1>       J10              218      SCONN288_ADR50001P003C01-SCONNA
M_E_CPU0_CLK_DN<1>       U2               EE45     SOCKET4677_AZIFS054P001C01-SOCA
M_E_CPU0_CLK_DP<0>       J9               217      SCONN288_ADR50001P013C01-SCONNA
M_E_CPU0_CLK_DP<0>       U2               EG45     SOCKET4677_AZIFS054P001C01-SOCA
M_E_CPU0_CLK_DP<1>       J10              217      SCONN288_ADR50001P003C01-SCONNA
M_E_CPU0_CLK_DP<1>       U2               EC45     SOCKET4677_AZIFS054P001C01-SOCA
M_E_CPU0_SA_CA<0>        J9               66       SCONN288_ADR50001P013C01-SCONNA
M_E_CPU0_SA_CA<0>        J10              66       SCONN288_ADR50001P003C01-SCONNA
M_E_CPU0_SA_CA<0>        U2               EP49     SOCKET4677_AZIFS054P001C01-SOCA
M_E_CPU0_SA_CA<1>        J9               211      SCONN288_ADR50001P013C01-SCONNA
M_E_CPU0_SA_CA<1>        J10              211      SCONN288_ADR50001P003C01-SCONNA
M_E_CPU0_SA_CA<1>        U2               ET49     SOCKET4677_AZIFS054P001C01-SOCA
M_E_CPU0_SA_CA<2>        J9               68       SCONN288_ADR50001P013C01-SCONNA
M_E_CPU0_SA_CA<2>        J10              68       SCONN288_ADR50001P003C01-SCONNA
M_E_CPU0_SA_CA<2>        U2               EK49     SOCKET4677_AZIFS054P001C01-SOCA
M_E_CPU0_SA_CA<3>        J9               213      SCONN288_ADR50001P013C01-SCONNA
M_E_CPU0_SA_CA<3>        J10              213      SCONN288_ADR50001P003C01-SCONNA
M_E_CPU0_SA_CA<3>        U2               EL48     SOCKET4677_AZIFS054P001C01-SOCA
M_E_CPU0_SA_CA<4>        J9               70       SCONN288_ADR50001P013C01-SCONNA
M_E_CPU0_SA_CA<4>        J10              70       SCONN288_ADR50001P003C01-SCONNA
M_E_CPU0_SA_CA<4>        U2               EM47     SOCKET4677_AZIFS054P001C01-SOCA
M_E_CPU0_SA_CA<5>        J9               215      SCONN288_ADR50001P013C01-SCONNA
M_E_CPU0_SA_CA<5>        J10              215      SCONN288_ADR50001P003C01-SCONNA
M_E_CPU0_SA_CA<5>        U2               EP47     SOCKET4677_AZIFS054P001C01-SOCA
M_E_CPU0_SA_CA<6>        J9               72       SCONN288_ADR50001P013C01-SCONNA
M_E_CPU0_SA_CA<6>        J10              72       SCONN288_ADR50001P003C01-SCONNA
M_E_CPU0_SA_CA<6>        U2               ED44     SOCKET4677_AZIFS054P001C01-SOCA
M_E_CPU0_SA_CB<0>        J9               51       SCONN288_ADR50001P013C01-SCONNA
M_E_CPU0_SA_CB<0>        J10              51       SCONN288_ADR50001P003C01-SCONNA
M_E_CPU0_SA_CB<0>        U2               EM57     SOCKET4677_AZIFS054P001C01-SOCA
M_E_CPU0_SA_CB<1>        J9               53       SCONN288_ADR50001P013C01-SCONNA
M_E_CPU0_SA_CB<1>        J10              53       SCONN288_ADR50001P003C01-SCONNA
M_E_CPU0_SA_CB<1>        U2               EL56     SOCKET4677_AZIFS054P001C01-SOCA
M_E_CPU0_SA_CB<2>        J9               196      SCONN288_ADR50001P013C01-SCONNA
M_E_CPU0_SA_CB<2>        J10              196      SCONN288_ADR50001P003C01-SCONNA
M_E_CPU0_SA_CB<2>        U2               EP57     SOCKET4677_AZIFS054P001C01-SOCA
M_E_CPU0_SA_CB<3>        J9               198      SCONN288_ADR50001P013C01-SCONNA
M_E_CPU0_SA_CB<3>        J10              198      SCONN288_ADR50001P003C01-SCONNA
M_E_CPU0_SA_CB<3>        U2               ER56     SOCKET4677_AZIFS054P001C01-SOCA
M_E_CPU0_SA_CB<4>        J9               58       SCONN288_ADR50001P013C01-SCONNA
M_E_CPU0_SA_CB<4>        J10              58       SCONN288_ADR50001P003C01-SCONNA
M_E_CPU0_SA_CB<4>        U2               EL54     SOCKET4677_AZIFS054P001C01-SOCA
M_E_CPU0_SA_CB<5>        J9               60       SCONN288_ADR50001P013C01-SCONNA
M_E_CPU0_SA_CB<5>        J10              60       SCONN288_ADR50001P003C01-SCONNA
M_E_CPU0_SA_CB<5>        U2               EM53     SOCKET4677_AZIFS054P001C01-SOCA
M_E_CPU0_SA_CB<6>        J9               203      SCONN288_ADR50001P013C01-SCONNA
M_E_CPU0_SA_CB<6>        J10              203      SCONN288_ADR50001P003C01-SCONNA
M_E_CPU0_SA_CB<6>        U2               ER54     SOCKET4677_AZIFS054P001C01-SOCA
M_E_CPU0_SA_CB<7>        J9               205      SCONN288_ADR50001P013C01-SCONNA
M_E_CPU0_SA_CB<7>        J10              205      SCONN288_ADR50001P003C01-SCONNA
M_E_CPU0_SA_CB<7>        U2               EP53     SOCKET4677_AZIFS054P001C01-SOCA
M_E_CPU0_SA_CS_N<0>      J9               64       SCONN288_ADR50001P013C01-SCONNA
M_E_CPU0_SA_CS_N<0>      U2               EP51     SOCKET4677_AZIFS054P001C01-SOCA
M_E_CPU0_SA_CS_N<1>      J9               209      SCONN288_ADR50001P013C01-SCONNA
M_E_CPU0_SA_CS_N<1>      U2               ET51     SOCKET4677_AZIFS054P001C01-SOCA
M_E_CPU0_SA_CS_N<2>      J10              64       SCONN288_ADR50001P003C01-SCONNA
M_E_CPU0_SA_CS_N<2>      U2               EM51     SOCKET4677_AZIFS054P001C01-SOCA
M_E_CPU0_SA_CS_N<3>      J10              209      SCONN288_ADR50001P003C01-SCONNA
M_E_CPU0_SA_CS_N<3>      U2               EL50     SOCKET4677_AZIFS054P001C01-SOCA
M_E_CPU0_SA_DQ<0>        J9               7        SCONN288_ADR50001P013C01-SCONNA
M_E_CPU0_SA_DQ<0>        J10              7        SCONN288_ADR50001P003C01-SCONNA
M_E_CPU0_SA_DQ<0>        U2               EL78     SOCKET4677_AZIFS054P001C01-SOCA
M_E_CPU0_SA_DQ<1>        J9               9        SCONN288_ADR50001P013C01-SCONNA
M_E_CPU0_SA_DQ<1>        J10              9        SCONN288_ADR50001P003C01-SCONNA
M_E_CPU0_SA_DQ<1>        U2               EM77     SOCKET4677_AZIFS054P001C01-SOCA
M_E_CPU0_SA_DQ<2>        J9               152      SCONN288_ADR50001P013C01-SCONNA
M_E_CPU0_SA_DQ<2>        J10              152      SCONN288_ADR50001P003C01-SCONNA
M_E_CPU0_SA_DQ<2>        U2               EP79     SOCKET4677_AZIFS054P001C01-SOCA
M_E_CPU0_SA_DQ<3>        J9               154      SCONN288_ADR50001P013C01-SCONNA
M_E_CPU0_SA_DQ<3>        J10              154      SCONN288_ADR50001P003C01-SCONNA
M_E_CPU0_SA_DQ<3>        U2               ER76     SOCKET4677_AZIFS054P001C01-SOCA
M_E_CPU0_SA_DQ<4>        J9               14       SCONN288_ADR50001P013C01-SCONNA
M_E_CPU0_SA_DQ<4>        J10              14       SCONN288_ADR50001P003C01-SCONNA
M_E_CPU0_SA_DQ<4>        U2               EL74     SOCKET4677_AZIFS054P001C01-SOCA
M_E_CPU0_SA_DQ<5>        J9               16       SCONN288_ADR50001P013C01-SCONNA
M_E_CPU0_SA_DQ<5>        J10              16       SCONN288_ADR50001P003C01-SCONNA
M_E_CPU0_SA_DQ<5>        U2               EK73     SOCKET4677_AZIFS054P001C01-SOCA
M_E_CPU0_SA_DQ<6>        J9               159      SCONN288_ADR50001P013C01-SCONNA
M_E_CPU0_SA_DQ<6>        J10              159      SCONN288_ADR50001P003C01-SCONNA
M_E_CPU0_SA_DQ<6>        U2               EP73     SOCKET4677_AZIFS054P001C01-SOCA
M_E_CPU0_SA_DQ<7>        J9               161      SCONN288_ADR50001P013C01-SCONNA
M_E_CPU0_SA_DQ<7>        J10              161      SCONN288_ADR50001P003C01-SCONNA
M_E_CPU0_SA_DQ<7>        U2               ER72     SOCKET4677_AZIFS054P001C01-SOCA
M_E_CPU0_SA_DQ<8>        J9               18       SCONN288_ADR50001P013C01-SCONNA
M_E_CPU0_SA_DQ<8>        J10              18       SCONN288_ADR50001P003C01-SCONNA
M_E_CPU0_SA_DQ<8>        U2               EE72     SOCKET4677_AZIFS054P001C01-SOCA
M_E_CPU0_SA_DQ<9>        J9               20       SCONN288_ADR50001P013C01-SCONNA
M_E_CPU0_SA_DQ<9>        J10              20       SCONN288_ADR50001P003C01-SCONNA
M_E_CPU0_SA_DQ<9>        U2               ED71     SOCKET4677_AZIFS054P001C01-SOCA
M_E_CPU0_SA_DQ<10>       J9               163      SCONN288_ADR50001P013C01-SCONNA
M_E_CPU0_SA_DQ<10>       J10              163      SCONN288_ADR50001P003C01-SCONNA
M_E_CPU0_SA_DQ<10>       U2               EG72     SOCKET4677_AZIFS054P001C01-SOCA
M_E_CPU0_SA_DQ<11>       J9               165      SCONN288_ADR50001P013C01-SCONNA
M_E_CPU0_SA_DQ<11>       J10              165      SCONN288_ADR50001P003C01-SCONNA
M_E_CPU0_SA_DQ<11>       U2               EH71     SOCKET4677_AZIFS054P001C01-SOCA
M_E_CPU0_SA_DQ<12>       J9               25       SCONN288_ADR50001P013C01-SCONNA
M_E_CPU0_SA_DQ<12>       J10              25       SCONN288_ADR50001P003C01-SCONNA
M_E_CPU0_SA_DQ<12>       U2               ED69     SOCKET4677_AZIFS054P001C01-SOCA
M_E_CPU0_SA_DQ<13>       J9               27       SCONN288_ADR50001P013C01-SCONNA
M_E_CPU0_SA_DQ<13>       J10              27       SCONN288_ADR50001P003C01-SCONNA
M_E_CPU0_SA_DQ<13>       U2               EE68     SOCKET4677_AZIFS054P001C01-SOCA
M_E_CPU0_SA_DQ<14>       J9               170      SCONN288_ADR50001P013C01-SCONNA
M_E_CPU0_SA_DQ<14>       J10              170      SCONN288_ADR50001P003C01-SCONNA
M_E_CPU0_SA_DQ<14>       U2               EH69     SOCKET4677_AZIFS054P001C01-SOCA
M_E_CPU0_SA_DQ<15>       J9               172      SCONN288_ADR50001P013C01-SCONNA
M_E_CPU0_SA_DQ<15>       J10              172      SCONN288_ADR50001P003C01-SCONNA
M_E_CPU0_SA_DQ<15>       U2               EG68     SOCKET4677_AZIFS054P001C01-SOCA
M_E_CPU0_SA_DQ<16>       J9               29       SCONN288_ADR50001P013C01-SCONNA
M_E_CPU0_SA_DQ<16>       J10              29       SCONN288_ADR50001P003C01-SCONNA
M_E_CPU0_SA_DQ<16>       U2               EM71     SOCKET4677_AZIFS054P001C01-SOCA
M_E_CPU0_SA_DQ<17>       J9               31       SCONN288_ADR50001P013C01-SCONNA
M_E_CPU0_SA_DQ<17>       J10              31       SCONN288_ADR50001P003C01-SCONNA
M_E_CPU0_SA_DQ<17>       U2               EM69     SOCKET4677_AZIFS054P001C01-SOCA
M_E_CPU0_SA_DQ<18>       J9               174      SCONN288_ADR50001P013C01-SCONNA
M_E_CPU0_SA_DQ<18>       J10              174      SCONN288_ADR50001P003C01-SCONNA
M_E_CPU0_SA_DQ<18>       U2               EN70     SOCKET4677_AZIFS054P001C01-SOCA
M_E_CPU0_SA_DQ<19>       J9               176      SCONN288_ADR50001P013C01-SCONNA
M_E_CPU0_SA_DQ<19>       J10              176      SCONN288_ADR50001P003C01-SCONNA
M_E_CPU0_SA_DQ<19>       U2               ER68     SOCKET4677_AZIFS054P001C01-SOCA
M_E_CPU0_SA_DQ<20>       J9               36       SCONN288_ADR50001P013C01-SCONNA
M_E_CPU0_SA_DQ<20>       J10              36       SCONN288_ADR50001P003C01-SCONNA
M_E_CPU0_SA_DQ<20>       U2               ER66     SOCKET4677_AZIFS054P001C01-SOCA
M_E_CPU0_SA_DQ<21>       J9               38       SCONN288_ADR50001P013C01-SCONNA
M_E_CPU0_SA_DQ<21>       J10              38       SCONN288_ADR50001P003C01-SCONNA
M_E_CPU0_SA_DQ<21>       U2               EM65     SOCKET4677_AZIFS054P001C01-SOCA
M_E_CPU0_SA_DQ<22>       J9               181      SCONN288_ADR50001P013C01-SCONNA
M_E_CPU0_SA_DQ<22>       J10              181      SCONN288_ADR50001P003C01-SCONNA
M_E_CPU0_SA_DQ<22>       U2               EL66     SOCKET4677_AZIFS054P001C01-SOCA
M_E_CPU0_SA_DQ<23>       J9               183      SCONN288_ADR50001P013C01-SCONNA
M_E_CPU0_SA_DQ<23>       J10              183      SCONN288_ADR50001P003C01-SCONNA
M_E_CPU0_SA_DQ<23>       U2               EP65     SOCKET4677_AZIFS054P001C01-SOCA
M_E_CPU0_SA_DQ<24>       J9               40       SCONN288_ADR50001P013C01-SCONNA
M_E_CPU0_SA_DQ<24>       J10              40       SCONN288_ADR50001P003C01-SCONNA
M_E_CPU0_SA_DQ<24>       U2               EM63     SOCKET4677_AZIFS054P001C01-SOCA
M_E_CPU0_SA_DQ<25>       J9               42       SCONN288_ADR50001P013C01-SCONNA
M_E_CPU0_SA_DQ<25>       J10              42       SCONN288_ADR50001P003C01-SCONNA
M_E_CPU0_SA_DQ<25>       U2               EL62     SOCKET4677_AZIFS054P001C01-SOCA
M_E_CPU0_SA_DQ<26>       J9               185      SCONN288_ADR50001P013C01-SCONNA
M_E_CPU0_SA_DQ<26>       J10              185      SCONN288_ADR50001P003C01-SCONNA
M_E_CPU0_SA_DQ<26>       U2               EP63     SOCKET4677_AZIFS054P001C01-SOCA
M_E_CPU0_SA_DQ<27>       J9               187      SCONN288_ADR50001P013C01-SCONNA
M_E_CPU0_SA_DQ<27>       J10              187      SCONN288_ADR50001P003C01-SCONNA
M_E_CPU0_SA_DQ<27>       U2               ER62     SOCKET4677_AZIFS054P001C01-SOCA
M_E_CPU0_SA_DQ<28>       J9               47       SCONN288_ADR50001P013C01-SCONNA
M_E_CPU0_SA_DQ<28>       J10              47       SCONN288_ADR50001P003C01-SCONNA
M_E_CPU0_SA_DQ<28>       U2               EL60     SOCKET4677_AZIFS054P001C01-SOCA
M_E_CPU0_SA_DQ<29>       J9               49       SCONN288_ADR50001P013C01-SCONNA
M_E_CPU0_SA_DQ<29>       J10              49       SCONN288_ADR50001P003C01-SCONNA
M_E_CPU0_SA_DQ<29>       U2               EM59     SOCKET4677_AZIFS054P001C01-SOCA
M_E_CPU0_SA_DQ<30>       J9               192      SCONN288_ADR50001P013C01-SCONNA
M_E_CPU0_SA_DQ<30>       J10              192      SCONN288_ADR50001P003C01-SCONNA
M_E_CPU0_SA_DQ<30>       U2               ER60     SOCKET4677_AZIFS054P001C01-SOCA
M_E_CPU0_SA_DQ<31>       J9               194      SCONN288_ADR50001P013C01-SCONNA
M_E_CPU0_SA_DQ<31>       J10              194      SCONN288_ADR50001P003C01-SCONNA
M_E_CPU0_SA_DQ<31>       U2               EP59     SOCKET4677_AZIFS054P001C01-SOCA
M_E_CPU0_SA_DQS_DN<0>    J9               12       SCONN288_ADR50001P013C01-SCONNA
M_E_CPU0_SA_DQS_DN<0>    J10              12       SCONN288_ADR50001P003C01-SCONNA
M_E_CPU0_SA_DQS_DN<0>    U2               EP75     SOCKET4677_AZIFS054P001C01-SOCA
M_E_CPU0_SA_DQS_DN<1>    J9               23       SCONN288_ADR50001P013C01-SCONNA
M_E_CPU0_SA_DQS_DN<1>    J10              23       SCONN288_ADR50001P003C01-SCONNA
M_E_CPU0_SA_DQS_DN<1>    U2               EC70     SOCKET4677_AZIFS054P001C01-SOCA
M_E_CPU0_SA_DQS_DN<2>    J9               34       SCONN288_ADR50001P013C01-SCONNA
M_E_CPU0_SA_DQS_DN<2>    J10              34       SCONN288_ADR50001P003C01-SCONNA
M_E_CPU0_SA_DQS_DN<2>    U2               EK67     SOCKET4677_AZIFS054P001C01-SOCA
M_E_CPU0_SA_DQS_DN<3>    J9               45       SCONN288_ADR50001P013C01-SCONNA
M_E_CPU0_SA_DQS_DN<3>    J10              45       SCONN288_ADR50001P003C01-SCONNA
M_E_CPU0_SA_DQS_DN<3>    U2               EK61     SOCKET4677_AZIFS054P001C01-SOCA
M_E_CPU0_SA_DQS_DN<4>    J9               56       SCONN288_ADR50001P013C01-SCONNA
M_E_CPU0_SA_DQS_DN<4>    J10              56       SCONN288_ADR50001P003C01-SCONNA
M_E_CPU0_SA_DQS_DN<4>    U2               EM55     SOCKET4677_AZIFS054P001C01-SOCA
M_E_CPU0_SA_DQS_DN<5>    J9               156      SCONN288_ADR50001P013C01-SCONNA
M_E_CPU0_SA_DQS_DN<5>    J10              156      SCONN288_ADR50001P003C01-SCONNA
M_E_CPU0_SA_DQS_DN<5>    U2               EM75     SOCKET4677_AZIFS054P001C01-SOCA
M_E_CPU0_SA_DQS_DN<6>    J9               167      SCONN288_ADR50001P013C01-SCONNA
M_E_CPU0_SA_DQS_DN<6>    J10              167      SCONN288_ADR50001P003C01-SCONNA
M_E_CPU0_SA_DQS_DN<6>    U2               EJ70     SOCKET4677_AZIFS054P001C01-SOCA
M_E_CPU0_SA_DQS_DN<7>    J9               178      SCONN288_ADR50001P013C01-SCONNA
M_E_CPU0_SA_DQS_DN<7>    J10              178      SCONN288_ADR50001P003C01-SCONNA
M_E_CPU0_SA_DQS_DN<7>    U2               EN68     SOCKET4677_AZIFS054P001C01-SOCA
M_E_CPU0_SA_DQS_DN<8>    J9               189      SCONN288_ADR50001P013C01-SCONNA
M_E_CPU0_SA_DQS_DN<8>    J10              189      SCONN288_ADR50001P003C01-SCONNA
M_E_CPU0_SA_DQS_DN<8>    U2               ET61     SOCKET4677_AZIFS054P001C01-SOCA
M_E_CPU0_SA_DQS_DN<9>    J9               200      SCONN288_ADR50001P013C01-SCONNA
M_E_CPU0_SA_DQS_DN<9>    J10              200      SCONN288_ADR50001P003C01-SCONNA
M_E_CPU0_SA_DQS_DN<9>    U2               ET55     SOCKET4677_AZIFS054P001C01-SOCA
M_E_CPU0_SA_DQS_DP<0>    J9               11       SCONN288_ADR50001P013C01-SCONNA
M_E_CPU0_SA_DQS_DP<0>    J10              11       SCONN288_ADR50001P003C01-SCONNA
M_E_CPU0_SA_DQS_DP<0>    U2               EN76     SOCKET4677_AZIFS054P001C01-SOCA
M_E_CPU0_SA_DQS_DP<1>    J9               22       SCONN288_ADR50001P013C01-SCONNA
M_E_CPU0_SA_DQS_DP<1>    J10              22       SCONN288_ADR50001P003C01-SCONNA
M_E_CPU0_SA_DQS_DP<1>    U2               EE70     SOCKET4677_AZIFS054P001C01-SOCA
M_E_CPU0_SA_DQS_DP<2>    J9               33       SCONN288_ADR50001P013C01-SCONNA
M_E_CPU0_SA_DQS_DP<2>    J10              33       SCONN288_ADR50001P003C01-SCONNA
M_E_CPU0_SA_DQS_DP<2>    U2               EL68     SOCKET4677_AZIFS054P001C01-SOCA
M_E_CPU0_SA_DQS_DP<3>    J9               44       SCONN288_ADR50001P013C01-SCONNA
M_E_CPU0_SA_DQS_DP<3>    J10              44       SCONN288_ADR50001P003C01-SCONNA
M_E_CPU0_SA_DQS_DP<3>    U2               EM61     SOCKET4677_AZIFS054P001C01-SOCA
M_E_CPU0_SA_DQS_DP<4>    J9               55       SCONN288_ADR50001P013C01-SCONNA
M_E_CPU0_SA_DQS_DP<4>    J10              55       SCONN288_ADR50001P003C01-SCONNA
M_E_CPU0_SA_DQS_DP<4>    U2               EK55     SOCKET4677_AZIFS054P001C01-SOCA
M_E_CPU0_SA_DQS_DP<5>    J9               157      SCONN288_ADR50001P013C01-SCONNA
M_E_CPU0_SA_DQS_DP<5>    J10              157      SCONN288_ADR50001P003C01-SCONNA
M_E_CPU0_SA_DQS_DP<5>    U2               EN74     SOCKET4677_AZIFS054P001C01-SOCA
M_E_CPU0_SA_DQS_DP<6>    J9               168      SCONN288_ADR50001P013C01-SCONNA
M_E_CPU0_SA_DQS_DP<6>    J10              168      SCONN288_ADR50001P003C01-SCONNA
M_E_CPU0_SA_DQS_DP<6>    U2               EG70     SOCKET4677_AZIFS054P001C01-SOCA
M_E_CPU0_SA_DQS_DP<7>    J9               179      SCONN288_ADR50001P013C01-SCONNA
M_E_CPU0_SA_DQS_DP<7>    J10              179      SCONN288_ADR50001P003C01-SCONNA
M_E_CPU0_SA_DQS_DP<7>    U2               EM67     SOCKET4677_AZIFS054P001C01-SOCA
M_E_CPU0_SA_DQS_DP<8>    J9               190      SCONN288_ADR50001P013C01-SCONNA
M_E_CPU0_SA_DQS_DP<8>    J10              190      SCONN288_ADR50001P003C01-SCONNA
M_E_CPU0_SA_DQS_DP<8>    U2               EP61     SOCKET4677_AZIFS054P001C01-SOCA
M_E_CPU0_SA_DQS_DP<9>    J9               201      SCONN288_ADR50001P013C01-SCONNA
M_E_CPU0_SA_DQS_DP<9>    J10              201      SCONN288_ADR50001P003C01-SCONNA
M_E_CPU0_SA_DQS_DP<9>    U2               EP55     SOCKET4677_AZIFS054P001C01-SOCA
M_E_CPU0_SA_PAR          J9               74       SCONN288_ADR50001P013C01-SCONNA
M_E_CPU0_SA_PAR          J10              74       SCONN288_ADR50001P003C01-SCONNA
M_E_CPU0_SA_PAR          U2               EE43     SOCKET4677_AZIFS054P001C01-SOCA
M_E_CPU0_SA_RSP<0>       J9               86       SCONN288_ADR50001P013C01-SCONNA
M_E_CPU0_SA_RSP<0>       U2               DD44     SOCKET4677_AZIFS054P001C01-SOCA
M_E_CPU0_SA_RSP<1>       J10              86       SCONN288_ADR50001P003C01-SCONNA
M_E_CPU0_SA_RSP<1>       U2               DC43     SOCKET4677_AZIFS054P001C01-SOCA
M_E_CPU0_SB_CA<0>        J9               76       SCONN288_ADR50001P013C01-SCONNA
M_E_CPU0_SB_CA<0>        J10              76       SCONN288_ADR50001P003C01-SCONNA
M_E_CPU0_SB_CA<0>        U2               EG43     SOCKET4677_AZIFS054P001C01-SOCA
M_E_CPU0_SB_CA<1>        J9               221      SCONN288_ADR50001P013C01-SCONNA
M_E_CPU0_SB_CA<1>        J10              221      SCONN288_ADR50001P003C01-SCONNA
M_E_CPU0_SB_CA<1>        U2               EH44     SOCKET4677_AZIFS054P001C01-SOCA
M_E_CPU0_SB_CA<2>        J9               78       SCONN288_ADR50001P013C01-SCONNA
M_E_CPU0_SB_CA<2>        J10              78       SCONN288_ADR50001P003C01-SCONNA
M_E_CPU0_SB_CA<2>        U2               EM44     SOCKET4677_AZIFS054P001C01-SOCA
M_E_CPU0_SB_CA<3>        J9               223      SCONN288_ADR50001P013C01-SCONNA
M_E_CPU0_SB_CA<3>        J10              223      SCONN288_ADR50001P003C01-SCONNA
M_E_CPU0_SB_CA<3>        U2               EP44     SOCKET4677_AZIFS054P001C01-SOCA
M_E_CPU0_SB_CA<4>        J9               80       SCONN288_ADR50001P013C01-SCONNA
M_E_CPU0_SB_CA<4>        J10              80       SCONN288_ADR50001P003C01-SCONNA
M_E_CPU0_SB_CA<4>        U2               EL43     SOCKET4677_AZIFS054P001C01-SOCA
M_E_CPU0_SB_CA<5>        J9               225      SCONN288_ADR50001P013C01-SCONNA
M_E_CPU0_SB_CA<5>        J10              225      SCONN288_ADR50001P003C01-SCONNA
M_E_CPU0_SB_CA<5>        U2               ET42     SOCKET4677_AZIFS054P001C01-SOCA
M_E_CPU0_SB_CA<6>        J9               82       SCONN288_ADR50001P013C01-SCONNA
M_E_CPU0_SB_CA<6>        J10              82       SCONN288_ADR50001P003C01-SCONNA
M_E_CPU0_SB_CA<6>        U2               EK42     SOCKET4677_AZIFS054P001C01-SOCA
M_E_CPU0_SB_CB<0>        J9               96       SCONN288_ADR50001P013C01-SCONNA
M_E_CPU0_SB_CB<0>        J10              96       SCONN288_ADR50001P003C01-SCONNA
M_E_CPU0_SB_CB<0>        U2               EL35     SOCKET4677_AZIFS054P001C01-SOCA
M_E_CPU0_SB_CB<1>        J9               98       SCONN288_ADR50001P013C01-SCONNA
M_E_CPU0_SB_CB<1>        J10              98       SCONN288_ADR50001P003C01-SCONNA
M_E_CPU0_SB_CB<1>        U2               EM34     SOCKET4677_AZIFS054P001C01-SOCA
M_E_CPU0_SB_CB<2>        J9               241      SCONN288_ADR50001P013C01-SCONNA
M_E_CPU0_SB_CB<2>        J10              241      SCONN288_ADR50001P003C01-SCONNA
M_E_CPU0_SB_CB<2>        U2               ER35     SOCKET4677_AZIFS054P001C01-SOCA
M_E_CPU0_SB_CB<3>        J9               243      SCONN288_ADR50001P013C01-SCONNA
M_E_CPU0_SB_CB<3>        J10              243      SCONN288_ADR50001P003C01-SCONNA
M_E_CPU0_SB_CB<3>        U2               EP34     SOCKET4677_AZIFS054P001C01-SOCA
M_E_CPU0_SB_CB<4>        J9               89       SCONN288_ADR50001P013C01-SCONNA
M_E_CPU0_SB_CB<4>        J10              89       SCONN288_ADR50001P003C01-SCONNA
M_E_CPU0_SB_CB<4>        U2               EM38     SOCKET4677_AZIFS054P001C01-SOCA
M_E_CPU0_SB_CB<5>        J9               91       SCONN288_ADR50001P013C01-SCONNA
M_E_CPU0_SB_CB<5>        J10              91       SCONN288_ADR50001P003C01-SCONNA
M_E_CPU0_SB_CB<5>        U2               EL37     SOCKET4677_AZIFS054P001C01-SOCA
M_E_CPU0_SB_CB<6>        J9               234      SCONN288_ADR50001P013C01-SCONNA
M_E_CPU0_SB_CB<6>        J10              234      SCONN288_ADR50001P003C01-SCONNA
M_E_CPU0_SB_CB<6>        U2               EP38     SOCKET4677_AZIFS054P001C01-SOCA
M_E_CPU0_SB_CB<7>        J9               236      SCONN288_ADR50001P013C01-SCONNA
M_E_CPU0_SB_CB<7>        J10              236      SCONN288_ADR50001P003C01-SCONNA
M_E_CPU0_SB_CB<7>        U2               ER37     SOCKET4677_AZIFS054P001C01-SOCA
M_E_CPU0_SB_CS_N<0>      J9               84       SCONN288_ADR50001P013C01-SCONNA
M_E_CPU0_SB_CS_N<0>      U2               EP40     SOCKET4677_AZIFS054P001C01-SOCA
M_E_CPU0_SB_CS_N<1>      J9               229      SCONN288_ADR50001P013C01-SCONNA
M_E_CPU0_SB_CS_N<1>      U2               ET40     SOCKET4677_AZIFS054P001C01-SOCA
M_E_CPU0_SB_CS_N<2>      J10              84       SCONN288_ADR50001P003C01-SCONNA
M_E_CPU0_SB_CS_N<2>      U2               EM40     SOCKET4677_AZIFS054P001C01-SOCA
M_E_CPU0_SB_CS_N<3>      J10              229      SCONN288_ADR50001P003C01-SCONNA
M_E_CPU0_SB_CS_N<3>      U2               EL41     SOCKET4677_AZIFS054P001C01-SOCA
M_E_CPU0_SB_DQ<0>        J9               100      SCONN288_ADR50001P013C01-SCONNA
M_E_CPU0_SB_DQ<0>        J10              100      SCONN288_ADR50001P003C01-SCONNA
M_E_CPU0_SB_DQ<0>        U2               EE29     SOCKET4677_AZIFS054P001C01-SOCA
M_E_CPU0_SB_DQ<1>        J9               102      SCONN288_ADR50001P013C01-SCONNA
M_E_CPU0_SB_DQ<1>        J10              102      SCONN288_ADR50001P003C01-SCONNA
M_E_CPU0_SB_DQ<1>        U2               ED28     SOCKET4677_AZIFS054P001C01-SOCA
M_E_CPU0_SB_DQ<2>        J9               245      SCONN288_ADR50001P013C01-SCONNA
M_E_CPU0_SB_DQ<2>        J10              245      SCONN288_ADR50001P003C01-SCONNA
M_E_CPU0_SB_DQ<2>        U2               EG29     SOCKET4677_AZIFS054P001C01-SOCA
M_E_CPU0_SB_DQ<3>        J9               247      SCONN288_ADR50001P013C01-SCONNA
M_E_CPU0_SB_DQ<3>        J10              247      SCONN288_ADR50001P003C01-SCONNA
M_E_CPU0_SB_DQ<3>        U2               EH28     SOCKET4677_AZIFS054P001C01-SOCA
M_E_CPU0_SB_DQ<4>        J9               107      SCONN288_ADR50001P013C01-SCONNA
M_E_CPU0_SB_DQ<4>        J10              107      SCONN288_ADR50001P003C01-SCONNA
M_E_CPU0_SB_DQ<4>        U2               ED26     SOCKET4677_AZIFS054P001C01-SOCA
M_E_CPU0_SB_DQ<5>        J9               109      SCONN288_ADR50001P013C01-SCONNA
M_E_CPU0_SB_DQ<5>        J10              109      SCONN288_ADR50001P003C01-SCONNA
M_E_CPU0_SB_DQ<5>        U2               EE25     SOCKET4677_AZIFS054P001C01-SOCA
M_E_CPU0_SB_DQ<6>        J9               252      SCONN288_ADR50001P013C01-SCONNA
M_E_CPU0_SB_DQ<6>        J10              252      SCONN288_ADR50001P003C01-SCONNA
M_E_CPU0_SB_DQ<6>        U2               EH26     SOCKET4677_AZIFS054P001C01-SOCA
M_E_CPU0_SB_DQ<7>        J9               254      SCONN288_ADR50001P013C01-SCONNA
M_E_CPU0_SB_DQ<7>        J10              254      SCONN288_ADR50001P003C01-SCONNA
M_E_CPU0_SB_DQ<7>        U2               EG25     SOCKET4677_AZIFS054P001C01-SOCA
M_E_CPU0_SB_DQ<8>        J9               111      SCONN288_ADR50001P013C01-SCONNA
M_E_CPU0_SB_DQ<8>        J10              111      SCONN288_ADR50001P003C01-SCONNA
M_E_CPU0_SB_DQ<8>        U2               EM32     SOCKET4677_AZIFS054P001C01-SOCA
M_E_CPU0_SB_DQ<9>        J9               113      SCONN288_ADR50001P013C01-SCONNA
M_E_CPU0_SB_DQ<9>        J10              113      SCONN288_ADR50001P003C01-SCONNA
M_E_CPU0_SB_DQ<9>        U2               EL31     SOCKET4677_AZIFS054P001C01-SOCA
M_E_CPU0_SB_DQ<10>       J9               256      SCONN288_ADR50001P013C01-SCONNA
M_E_CPU0_SB_DQ<10>       J10              256      SCONN288_ADR50001P003C01-SCONNA
M_E_CPU0_SB_DQ<10>       U2               EP32     SOCKET4677_AZIFS054P001C01-SOCA
M_E_CPU0_SB_DQ<11>       J9               258      SCONN288_ADR50001P013C01-SCONNA
M_E_CPU0_SB_DQ<11>       J10              258      SCONN288_ADR50001P003C01-SCONNA
M_E_CPU0_SB_DQ<11>       U2               ER31     SOCKET4677_AZIFS054P001C01-SOCA
M_E_CPU0_SB_DQ<12>       J9               118      SCONN288_ADR50001P013C01-SCONNA
M_E_CPU0_SB_DQ<12>       J10              118      SCONN288_ADR50001P003C01-SCONNA
M_E_CPU0_SB_DQ<12>       U2               EL29     SOCKET4677_AZIFS054P001C01-SOCA
M_E_CPU0_SB_DQ<13>       J9               120      SCONN288_ADR50001P013C01-SCONNA
M_E_CPU0_SB_DQ<13>       J10              120      SCONN288_ADR50001P003C01-SCONNA
M_E_CPU0_SB_DQ<13>       U2               EM28     SOCKET4677_AZIFS054P001C01-SOCA
M_E_CPU0_SB_DQ<14>       J9               263      SCONN288_ADR50001P013C01-SCONNA
M_E_CPU0_SB_DQ<14>       J10              263      SCONN288_ADR50001P003C01-SCONNA
M_E_CPU0_SB_DQ<14>       U2               ER29     SOCKET4677_AZIFS054P001C01-SOCA
M_E_CPU0_SB_DQ<15>       J9               265      SCONN288_ADR50001P013C01-SCONNA
M_E_CPU0_SB_DQ<15>       J10              265      SCONN288_ADR50001P003C01-SCONNA
M_E_CPU0_SB_DQ<15>       U2               EP28     SOCKET4677_AZIFS054P001C01-SOCA
M_E_CPU0_SB_DQ<16>       J9               122      SCONN288_ADR50001P013C01-SCONNA
M_E_CPU0_SB_DQ<16>       J10              122      SCONN288_ADR50001P003C01-SCONNA
M_E_CPU0_SB_DQ<16>       U2               EM26     SOCKET4677_AZIFS054P001C01-SOCA
M_E_CPU0_SB_DQ<17>       J9               124      SCONN288_ADR50001P013C01-SCONNA
M_E_CPU0_SB_DQ<17>       J10              124      SCONN288_ADR50001P003C01-SCONNA
M_E_CPU0_SB_DQ<17>       U2               EL25     SOCKET4677_AZIFS054P001C01-SOCA
M_E_CPU0_SB_DQ<18>       J9               267      SCONN288_ADR50001P013C01-SCONNA
M_E_CPU0_SB_DQ<18>       J10              267      SCONN288_ADR50001P003C01-SCONNA
M_E_CPU0_SB_DQ<18>       U2               EP26     SOCKET4677_AZIFS054P001C01-SOCA
M_E_CPU0_SB_DQ<19>       J9               269      SCONN288_ADR50001P013C01-SCONNA
M_E_CPU0_SB_DQ<19>       J10              269      SCONN288_ADR50001P003C01-SCONNA
M_E_CPU0_SB_DQ<19>       U2               ER25     SOCKET4677_AZIFS054P001C01-SOCA
M_E_CPU0_SB_DQ<20>       J9               129      SCONN288_ADR50001P013C01-SCONNA
M_E_CPU0_SB_DQ<20>       J10              129      SCONN288_ADR50001P003C01-SCONNA
M_E_CPU0_SB_DQ<20>       U2               EL23     SOCKET4677_AZIFS054P001C01-SOCA
M_E_CPU0_SB_DQ<21>       J9               131      SCONN288_ADR50001P013C01-SCONNA
M_E_CPU0_SB_DQ<21>       J10              131      SCONN288_ADR50001P003C01-SCONNA
M_E_CPU0_SB_DQ<21>       U2               EM22     SOCKET4677_AZIFS054P001C01-SOCA
M_E_CPU0_SB_DQ<22>       J9               274      SCONN288_ADR50001P013C01-SCONNA
M_E_CPU0_SB_DQ<22>       J10              274      SCONN288_ADR50001P003C01-SCONNA
M_E_CPU0_SB_DQ<22>       U2               ER23     SOCKET4677_AZIFS054P001C01-SOCA
M_E_CPU0_SB_DQ<23>       J9               276      SCONN288_ADR50001P013C01-SCONNA
M_E_CPU0_SB_DQ<23>       J10              276      SCONN288_ADR50001P003C01-SCONNA
M_E_CPU0_SB_DQ<23>       U2               EP22     SOCKET4677_AZIFS054P001C01-SOCA
M_E_CPU0_SB_DQ<24>       J9               133      SCONN288_ADR50001P013C01-SCONNA
M_E_CPU0_SB_DQ<24>       J10              133      SCONN288_ADR50001P003C01-SCONNA
M_E_CPU0_SB_DQ<24>       U2               EM20     SOCKET4677_AZIFS054P001C01-SOCA
M_E_CPU0_SB_DQ<25>       J9               135      SCONN288_ADR50001P013C01-SCONNA
M_E_CPU0_SB_DQ<25>       J10              135      SCONN288_ADR50001P003C01-SCONNA
M_E_CPU0_SB_DQ<25>       U2               EL19     SOCKET4677_AZIFS054P001C01-SOCA
M_E_CPU0_SB_DQ<26>       J9               278      SCONN288_ADR50001P013C01-SCONNA
M_E_CPU0_SB_DQ<26>       J10              278      SCONN288_ADR50001P003C01-SCONNA
M_E_CPU0_SB_DQ<26>       U2               EP20     SOCKET4677_AZIFS054P001C01-SOCA
M_E_CPU0_SB_DQ<27>       J9               280      SCONN288_ADR50001P013C01-SCONNA
M_E_CPU0_SB_DQ<27>       J10              280      SCONN288_ADR50001P003C01-SCONNA
M_E_CPU0_SB_DQ<27>       U2               ER19     SOCKET4677_AZIFS054P001C01-SOCA
M_E_CPU0_SB_DQ<28>       J9               140      SCONN288_ADR50001P013C01-SCONNA
M_E_CPU0_SB_DQ<28>       J10              140      SCONN288_ADR50001P003C01-SCONNA
M_E_CPU0_SB_DQ<28>       U2               EL17     SOCKET4677_AZIFS054P001C01-SOCA
M_E_CPU0_SB_DQ<29>       J9               142      SCONN288_ADR50001P013C01-SCONNA
M_E_CPU0_SB_DQ<29>       J10              142      SCONN288_ADR50001P003C01-SCONNA
M_E_CPU0_SB_DQ<29>       U2               EM16     SOCKET4677_AZIFS054P001C01-SOCA
M_E_CPU0_SB_DQ<30>       J9               285      SCONN288_ADR50001P013C01-SCONNA
M_E_CPU0_SB_DQ<30>       J10              285      SCONN288_ADR50001P003C01-SCONNA
M_E_CPU0_SB_DQ<30>       U2               ER17     SOCKET4677_AZIFS054P001C01-SOCA
M_E_CPU0_SB_DQ<31>       J9               287      SCONN288_ADR50001P013C01-SCONNA
M_E_CPU0_SB_DQ<31>       J10              287      SCONN288_ADR50001P003C01-SCONNA
M_E_CPU0_SB_DQ<31>       U2               EP16     SOCKET4677_AZIFS054P001C01-SOCA
M_E_CPU0_SB_DQS_DN<0>    J9               105      SCONN288_ADR50001P013C01-SCONNA
M_E_CPU0_SB_DQS_DN<0>    J10              105      SCONN288_ADR50001P003C01-SCONNA
M_E_CPU0_SB_DQS_DN<0>    U2               EE27     SOCKET4677_AZIFS054P001C01-SOCA
M_E_CPU0_SB_DQS_DN<1>    J9               116      SCONN288_ADR50001P013C01-SCONNA
M_E_CPU0_SB_DQS_DN<1>    J10              116      SCONN288_ADR50001P003C01-SCONNA
M_E_CPU0_SB_DQS_DN<1>    U2               EK30     SOCKET4677_AZIFS054P001C01-SOCA
M_E_CPU0_SB_DQS_DN<2>    J9               127      SCONN288_ADR50001P013C01-SCONNA
M_E_CPU0_SB_DQS_DN<2>    J10              127      SCONN288_ADR50001P003C01-SCONNA
M_E_CPU0_SB_DQS_DN<2>    U2               EK24     SOCKET4677_AZIFS054P001C01-SOCA
M_E_CPU0_SB_DQS_DN<3>    J9               138      SCONN288_ADR50001P013C01-SCONNA
M_E_CPU0_SB_DQS_DN<3>    J10              138      SCONN288_ADR50001P003C01-SCONNA
M_E_CPU0_SB_DQS_DN<3>    U2               EK18     SOCKET4677_AZIFS054P001C01-SOCA
M_E_CPU0_SB_DQS_DN<4>    J9               238      SCONN288_ADR50001P013C01-SCONNA
M_E_CPU0_SB_DQS_DN<4>    J10              238      SCONN288_ADR50001P003C01-SCONNA
M_E_CPU0_SB_DQS_DN<4>    U2               ET36     SOCKET4677_AZIFS054P001C01-SOCA
M_E_CPU0_SB_DQS_DN<5>    J9               249      SCONN288_ADR50001P013C01-SCONNA
M_E_CPU0_SB_DQS_DN<5>    J10              249      SCONN288_ADR50001P003C01-SCONNA
M_E_CPU0_SB_DQS_DN<5>    U2               EJ27     SOCKET4677_AZIFS054P001C01-SOCA
M_E_CPU0_SB_DQS_DN<6>    J9               260      SCONN288_ADR50001P013C01-SCONNA
M_E_CPU0_SB_DQS_DN<6>    J10              260      SCONN288_ADR50001P003C01-SCONNA
M_E_CPU0_SB_DQS_DN<6>    U2               ET30     SOCKET4677_AZIFS054P001C01-SOCA
M_E_CPU0_SB_DQS_DN<7>    J9               271      SCONN288_ADR50001P013C01-SCONNA
M_E_CPU0_SB_DQS_DN<7>    J10              271      SCONN288_ADR50001P003C01-SCONNA
M_E_CPU0_SB_DQS_DN<7>    U2               ET24     SOCKET4677_AZIFS054P001C01-SOCA
M_E_CPU0_SB_DQS_DN<8>    J9               282      SCONN288_ADR50001P013C01-SCONNA
M_E_CPU0_SB_DQS_DN<8>    J10              282      SCONN288_ADR50001P003C01-SCONNA
M_E_CPU0_SB_DQS_DN<8>    U2               ET18     SOCKET4677_AZIFS054P001C01-SOCA
M_E_CPU0_SB_DQS_DN<9>    J9               94       SCONN288_ADR50001P013C01-SCONNA
M_E_CPU0_SB_DQS_DN<9>    J10              94       SCONN288_ADR50001P003C01-SCONNA
M_E_CPU0_SB_DQS_DN<9>    U2               EK36     SOCKET4677_AZIFS054P001C01-SOCA
M_E_CPU0_SB_DQS_DP<0>    J9               104      SCONN288_ADR50001P013C01-SCONNA
M_E_CPU0_SB_DQS_DP<0>    J10              104      SCONN288_ADR50001P003C01-SCONNA
M_E_CPU0_SB_DQS_DP<0>    U2               EC27     SOCKET4677_AZIFS054P001C01-SOCA
M_E_CPU0_SB_DQS_DP<1>    J9               115      SCONN288_ADR50001P013C01-SCONNA
M_E_CPU0_SB_DQS_DP<1>    J10              115      SCONN288_ADR50001P003C01-SCONNA
M_E_CPU0_SB_DQS_DP<1>    U2               EM30     SOCKET4677_AZIFS054P001C01-SOCA
M_E_CPU0_SB_DQS_DP<2>    J9               126      SCONN288_ADR50001P013C01-SCONNA
M_E_CPU0_SB_DQS_DP<2>    J10              126      SCONN288_ADR50001P003C01-SCONNA
M_E_CPU0_SB_DQS_DP<2>    U2               EM24     SOCKET4677_AZIFS054P001C01-SOCA
M_E_CPU0_SB_DQS_DP<3>    J9               137      SCONN288_ADR50001P013C01-SCONNA
M_E_CPU0_SB_DQS_DP<3>    J10              137      SCONN288_ADR50001P003C01-SCONNA
M_E_CPU0_SB_DQS_DP<3>    U2               EM18     SOCKET4677_AZIFS054P001C01-SOCA
M_E_CPU0_SB_DQS_DP<4>    J9               239      SCONN288_ADR50001P013C01-SCONNA
M_E_CPU0_SB_DQS_DP<4>    J10              239      SCONN288_ADR50001P003C01-SCONNA
M_E_CPU0_SB_DQS_DP<4>    U2               EP36     SOCKET4677_AZIFS054P001C01-SOCA
M_E_CPU0_SB_DQS_DP<5>    J9               250      SCONN288_ADR50001P013C01-SCONNA
M_E_CPU0_SB_DQS_DP<5>    J10              250      SCONN288_ADR50001P003C01-SCONNA
M_E_CPU0_SB_DQS_DP<5>    U2               EG27     SOCKET4677_AZIFS054P001C01-SOCA
M_E_CPU0_SB_DQS_DP<6>    J9               261      SCONN288_ADR50001P013C01-SCONNA
M_E_CPU0_SB_DQS_DP<6>    J10              261      SCONN288_ADR50001P003C01-SCONNA
M_E_CPU0_SB_DQS_DP<6>    U2               EP30     SOCKET4677_AZIFS054P001C01-SOCA
M_E_CPU0_SB_DQS_DP<7>    J9               272      SCONN288_ADR50001P013C01-SCONNA
M_E_CPU0_SB_DQS_DP<7>    J10              272      SCONN288_ADR50001P003C01-SCONNA
M_E_CPU0_SB_DQS_DP<7>    U2               EP24     SOCKET4677_AZIFS054P001C01-SOCA
M_E_CPU0_SB_DQS_DP<8>    J9               283      SCONN288_ADR50001P013C01-SCONNA
M_E_CPU0_SB_DQS_DP<8>    J10              283      SCONN288_ADR50001P003C01-SCONNA
M_E_CPU0_SB_DQS_DP<8>    U2               EP18     SOCKET4677_AZIFS054P001C01-SOCA
M_E_CPU0_SB_DQS_DP<9>    J9               93       SCONN288_ADR50001P013C01-SCONNA
M_E_CPU0_SB_DQS_DP<9>    J10              93       SCONN288_ADR50001P003C01-SCONNA
M_E_CPU0_SB_DQS_DP<9>    U2               EM36     SOCKET4677_AZIFS054P001C01-SOCA
M_E_CPU0_SB_PAR          J9               227      SCONN288_ADR50001P013C01-SCONNA
M_E_CPU0_SB_PAR          J10              227      SCONN288_ADR50001P003C01-SCONNA
M_E_CPU0_SB_PAR          U2               EP42     SOCKET4677_AZIFS054P001C01-SOCA
M_E_CPU0_SB_RSP<0>       J9               87       SCONN288_ADR50001P013C01-SCONNA
M_E_CPU0_SB_RSP<0>       U2               DF44     SOCKET4677_AZIFS054P001C01-SOCA
M_E_CPU0_SB_RSP<1>       J10              87       SCONN288_ADR50001P003C01-SCONNA
M_E_CPU0_SB_RSP<1>       U2               DG43     SOCKET4677_AZIFS054P001C01-SOCA
M_E_CPU1_ALERT_N         J25              62       SCONN288_ADR50001P013C01-SCONNA
M_E_CPU1_ALERT_N         J26              62       SCONN288_ADR50001P003C01-SCONNA
M_E_CPU1_ALERT_N         U1               CY47     SOCKET4677_AZIFS054P001C01-SOCA
M_E_CPU1_CLK_DN<0>       J25              218      SCONN288_ADR50001P013C01-SCONNA
M_E_CPU1_CLK_DN<0>       U1               EJ45     SOCKET4677_AZIFS054P001C01-SOCA
M_E_CPU1_CLK_DN<1>       J26              218      SCONN288_ADR50001P003C01-SCONNA
M_E_CPU1_CLK_DN<1>       U1               EE45     SOCKET4677_AZIFS054P001C01-SOCA
M_E_CPU1_CLK_DP<0>       J25              217      SCONN288_ADR50001P013C01-SCONNA
M_E_CPU1_CLK_DP<0>       U1               EG45     SOCKET4677_AZIFS054P001C01-SOCA
M_E_CPU1_CLK_DP<1>       J26              217      SCONN288_ADR50001P003C01-SCONNA
M_E_CPU1_CLK_DP<1>       U1               EC45     SOCKET4677_AZIFS054P001C01-SOCA
M_E_CPU1_SA_CA<0>        J25              66       SCONN288_ADR50001P013C01-SCONNA
M_E_CPU1_SA_CA<0>        J26              66       SCONN288_ADR50001P003C01-SCONNA
M_E_CPU1_SA_CA<0>        U1               EP49     SOCKET4677_AZIFS054P001C01-SOCA
M_E_CPU1_SA_CA<1>        J25              211      SCONN288_ADR50001P013C01-SCONNA
M_E_CPU1_SA_CA<1>        J26              211      SCONN288_ADR50001P003C01-SCONNA
M_E_CPU1_SA_CA<1>        U1               ET49     SOCKET4677_AZIFS054P001C01-SOCA
M_E_CPU1_SA_CA<2>        J25              68       SCONN288_ADR50001P013C01-SCONNA
M_E_CPU1_SA_CA<2>        J26              68       SCONN288_ADR50001P003C01-SCONNA
M_E_CPU1_SA_CA<2>        U1               EK49     SOCKET4677_AZIFS054P001C01-SOCA
M_E_CPU1_SA_CA<3>        J25              213      SCONN288_ADR50001P013C01-SCONNA
M_E_CPU1_SA_CA<3>        J26              213      SCONN288_ADR50001P003C01-SCONNA
M_E_CPU1_SA_CA<3>        U1               EL48     SOCKET4677_AZIFS054P001C01-SOCA
M_E_CPU1_SA_CA<4>        J25              70       SCONN288_ADR50001P013C01-SCONNA
M_E_CPU1_SA_CA<4>        J26              70       SCONN288_ADR50001P003C01-SCONNA
M_E_CPU1_SA_CA<4>        U1               EM47     SOCKET4677_AZIFS054P001C01-SOCA
M_E_CPU1_SA_CA<5>        J25              215      SCONN288_ADR50001P013C01-SCONNA
M_E_CPU1_SA_CA<5>        J26              215      SCONN288_ADR50001P003C01-SCONNA
M_E_CPU1_SA_CA<5>        U1               EP47     SOCKET4677_AZIFS054P001C01-SOCA
M_E_CPU1_SA_CA<6>        J25              72       SCONN288_ADR50001P013C01-SCONNA
M_E_CPU1_SA_CA<6>        J26              72       SCONN288_ADR50001P003C01-SCONNA
M_E_CPU1_SA_CA<6>        U1               ED44     SOCKET4677_AZIFS054P001C01-SOCA
M_E_CPU1_SA_CB<0>        J25              51       SCONN288_ADR50001P013C01-SCONNA
M_E_CPU1_SA_CB<0>        J26              51       SCONN288_ADR50001P003C01-SCONNA
M_E_CPU1_SA_CB<0>        U1               EM57     SOCKET4677_AZIFS054P001C01-SOCA
M_E_CPU1_SA_CB<1>        J25              53       SCONN288_ADR50001P013C01-SCONNA
M_E_CPU1_SA_CB<1>        J26              53       SCONN288_ADR50001P003C01-SCONNA
M_E_CPU1_SA_CB<1>        U1               EL56     SOCKET4677_AZIFS054P001C01-SOCA
M_E_CPU1_SA_CB<2>        J25              196      SCONN288_ADR50001P013C01-SCONNA
M_E_CPU1_SA_CB<2>        J26              196      SCONN288_ADR50001P003C01-SCONNA
M_E_CPU1_SA_CB<2>        U1               EP57     SOCKET4677_AZIFS054P001C01-SOCA
M_E_CPU1_SA_CB<3>        J25              198      SCONN288_ADR50001P013C01-SCONNA
M_E_CPU1_SA_CB<3>        J26              198      SCONN288_ADR50001P003C01-SCONNA
M_E_CPU1_SA_CB<3>        U1               ER56     SOCKET4677_AZIFS054P001C01-SOCA
M_E_CPU1_SA_CB<4>        J25              58       SCONN288_ADR50001P013C01-SCONNA
M_E_CPU1_SA_CB<4>        J26              58       SCONN288_ADR50001P003C01-SCONNA
M_E_CPU1_SA_CB<4>        U1               EL54     SOCKET4677_AZIFS054P001C01-SOCA
M_E_CPU1_SA_CB<5>        J25              60       SCONN288_ADR50001P013C01-SCONNA
M_E_CPU1_SA_CB<5>        J26              60       SCONN288_ADR50001P003C01-SCONNA
M_E_CPU1_SA_CB<5>        U1               EM53     SOCKET4677_AZIFS054P001C01-SOCA
M_E_CPU1_SA_CB<6>        J25              203      SCONN288_ADR50001P013C01-SCONNA
M_E_CPU1_SA_CB<6>        J26              203      SCONN288_ADR50001P003C01-SCONNA
M_E_CPU1_SA_CB<6>        U1               ER54     SOCKET4677_AZIFS054P001C01-SOCA
M_E_CPU1_SA_CB<7>        J25              205      SCONN288_ADR50001P013C01-SCONNA
M_E_CPU1_SA_CB<7>        J26              205      SCONN288_ADR50001P003C01-SCONNA
M_E_CPU1_SA_CB<7>        U1               EP53     SOCKET4677_AZIFS054P001C01-SOCA
M_E_CPU1_SA_CS_N<0>      J25              64       SCONN288_ADR50001P013C01-SCONNA
M_E_CPU1_SA_CS_N<0>      U1               EP51     SOCKET4677_AZIFS054P001C01-SOCA
M_E_CPU1_SA_CS_N<1>      J25              209      SCONN288_ADR50001P013C01-SCONNA
M_E_CPU1_SA_CS_N<1>      U1               ET51     SOCKET4677_AZIFS054P001C01-SOCA
M_E_CPU1_SA_CS_N<2>      J26              64       SCONN288_ADR50001P003C01-SCONNA
M_E_CPU1_SA_CS_N<2>      U1               EM51     SOCKET4677_AZIFS054P001C01-SOCA
M_E_CPU1_SA_CS_N<3>      J26              209      SCONN288_ADR50001P003C01-SCONNA
M_E_CPU1_SA_CS_N<3>      U1               EL50     SOCKET4677_AZIFS054P001C01-SOCA
M_E_CPU1_SA_DQ<0>        J25              7        SCONN288_ADR50001P013C01-SCONNA
M_E_CPU1_SA_DQ<0>        J26              7        SCONN288_ADR50001P003C01-SCONNA
M_E_CPU1_SA_DQ<0>        U1               EL78     SOCKET4677_AZIFS054P001C01-SOCA
M_E_CPU1_SA_DQ<1>        J25              9        SCONN288_ADR50001P013C01-SCONNA
M_E_CPU1_SA_DQ<1>        J26              9        SCONN288_ADR50001P003C01-SCONNA
M_E_CPU1_SA_DQ<1>        U1               EM77     SOCKET4677_AZIFS054P001C01-SOCA
M_E_CPU1_SA_DQ<2>        J25              152      SCONN288_ADR50001P013C01-SCONNA
M_E_CPU1_SA_DQ<2>        J26              152      SCONN288_ADR50001P003C01-SCONNA
M_E_CPU1_SA_DQ<2>        U1               EP79     SOCKET4677_AZIFS054P001C01-SOCA
M_E_CPU1_SA_DQ<3>        J25              154      SCONN288_ADR50001P013C01-SCONNA
M_E_CPU1_SA_DQ<3>        J26              154      SCONN288_ADR50001P003C01-SCONNA
M_E_CPU1_SA_DQ<3>        U1               ER76     SOCKET4677_AZIFS054P001C01-SOCA
M_E_CPU1_SA_DQ<4>        J25              14       SCONN288_ADR50001P013C01-SCONNA
M_E_CPU1_SA_DQ<4>        J26              14       SCONN288_ADR50001P003C01-SCONNA
M_E_CPU1_SA_DQ<4>        U1               EL74     SOCKET4677_AZIFS054P001C01-SOCA
M_E_CPU1_SA_DQ<5>        J25              16       SCONN288_ADR50001P013C01-SCONNA
M_E_CPU1_SA_DQ<5>        J26              16       SCONN288_ADR50001P003C01-SCONNA
M_E_CPU1_SA_DQ<5>        U1               EK73     SOCKET4677_AZIFS054P001C01-SOCA
M_E_CPU1_SA_DQ<6>        J25              159      SCONN288_ADR50001P013C01-SCONNA
M_E_CPU1_SA_DQ<6>        J26              159      SCONN288_ADR50001P003C01-SCONNA
M_E_CPU1_SA_DQ<6>        U1               EP73     SOCKET4677_AZIFS054P001C01-SOCA
M_E_CPU1_SA_DQ<7>        J25              161      SCONN288_ADR50001P013C01-SCONNA
M_E_CPU1_SA_DQ<7>        J26              161      SCONN288_ADR50001P003C01-SCONNA
M_E_CPU1_SA_DQ<7>        U1               ER72     SOCKET4677_AZIFS054P001C01-SOCA
M_E_CPU1_SA_DQ<8>        J25              18       SCONN288_ADR50001P013C01-SCONNA
M_E_CPU1_SA_DQ<8>        J26              18       SCONN288_ADR50001P003C01-SCONNA
M_E_CPU1_SA_DQ<8>        U1               EE72     SOCKET4677_AZIFS054P001C01-SOCA
M_E_CPU1_SA_DQ<9>        J25              20       SCONN288_ADR50001P013C01-SCONNA
M_E_CPU1_SA_DQ<9>        J26              20       SCONN288_ADR50001P003C01-SCONNA
M_E_CPU1_SA_DQ<9>        U1               ED71     SOCKET4677_AZIFS054P001C01-SOCA
M_E_CPU1_SA_DQ<10>       J25              163      SCONN288_ADR50001P013C01-SCONNA
M_E_CPU1_SA_DQ<10>       J26              163      SCONN288_ADR50001P003C01-SCONNA
M_E_CPU1_SA_DQ<10>       U1               EG72     SOCKET4677_AZIFS054P001C01-SOCA
M_E_CPU1_SA_DQ<11>       J25              165      SCONN288_ADR50001P013C01-SCONNA
M_E_CPU1_SA_DQ<11>       J26              165      SCONN288_ADR50001P003C01-SCONNA
M_E_CPU1_SA_DQ<11>       U1               EH71     SOCKET4677_AZIFS054P001C01-SOCA
M_E_CPU1_SA_DQ<12>       J25              25       SCONN288_ADR50001P013C01-SCONNA
M_E_CPU1_SA_DQ<12>       J26              25       SCONN288_ADR50001P003C01-SCONNA
M_E_CPU1_SA_DQ<12>       U1               ED69     SOCKET4677_AZIFS054P001C01-SOCA
M_E_CPU1_SA_DQ<13>       J25              27       SCONN288_ADR50001P013C01-SCONNA
M_E_CPU1_SA_DQ<13>       J26              27       SCONN288_ADR50001P003C01-SCONNA
M_E_CPU1_SA_DQ<13>       U1               EE68     SOCKET4677_AZIFS054P001C01-SOCA
M_E_CPU1_SA_DQ<14>       J25              170      SCONN288_ADR50001P013C01-SCONNA
M_E_CPU1_SA_DQ<14>       J26              170      SCONN288_ADR50001P003C01-SCONNA
M_E_CPU1_SA_DQ<14>       U1               EH69     SOCKET4677_AZIFS054P001C01-SOCA
M_E_CPU1_SA_DQ<15>       J25              172      SCONN288_ADR50001P013C01-SCONNA
M_E_CPU1_SA_DQ<15>       J26              172      SCONN288_ADR50001P003C01-SCONNA
M_E_CPU1_SA_DQ<15>       U1               EG68     SOCKET4677_AZIFS054P001C01-SOCA
M_E_CPU1_SA_DQ<16>       J25              29       SCONN288_ADR50001P013C01-SCONNA
M_E_CPU1_SA_DQ<16>       J26              29       SCONN288_ADR50001P003C01-SCONNA
M_E_CPU1_SA_DQ<16>       U1               EM71     SOCKET4677_AZIFS054P001C01-SOCA
M_E_CPU1_SA_DQ<17>       J25              31       SCONN288_ADR50001P013C01-SCONNA
M_E_CPU1_SA_DQ<17>       J26              31       SCONN288_ADR50001P003C01-SCONNA
M_E_CPU1_SA_DQ<17>       U1               EM69     SOCKET4677_AZIFS054P001C01-SOCA
M_E_CPU1_SA_DQ<18>       J25              174      SCONN288_ADR50001P013C01-SCONNA
M_E_CPU1_SA_DQ<18>       J26              174      SCONN288_ADR50001P003C01-SCONNA
M_E_CPU1_SA_DQ<18>       U1               EN70     SOCKET4677_AZIFS054P001C01-SOCA
M_E_CPU1_SA_DQ<19>       J25              176      SCONN288_ADR50001P013C01-SCONNA
M_E_CPU1_SA_DQ<19>       J26              176      SCONN288_ADR50001P003C01-SCONNA
M_E_CPU1_SA_DQ<19>       U1               ER68     SOCKET4677_AZIFS054P001C01-SOCA
M_E_CPU1_SA_DQ<20>       J25              36       SCONN288_ADR50001P013C01-SCONNA
M_E_CPU1_SA_DQ<20>       J26              36       SCONN288_ADR50001P003C01-SCONNA
M_E_CPU1_SA_DQ<20>       U1               ER66     SOCKET4677_AZIFS054P001C01-SOCA
M_E_CPU1_SA_DQ<21>       J25              38       SCONN288_ADR50001P013C01-SCONNA
M_E_CPU1_SA_DQ<21>       J26              38       SCONN288_ADR50001P003C01-SCONNA
M_E_CPU1_SA_DQ<21>       U1               EM65     SOCKET4677_AZIFS054P001C01-SOCA
M_E_CPU1_SA_DQ<22>       J25              181      SCONN288_ADR50001P013C01-SCONNA
M_E_CPU1_SA_DQ<22>       J26              181      SCONN288_ADR50001P003C01-SCONNA
M_E_CPU1_SA_DQ<22>       U1               EL66     SOCKET4677_AZIFS054P001C01-SOCA
M_E_CPU1_SA_DQ<23>       J25              183      SCONN288_ADR50001P013C01-SCONNA
M_E_CPU1_SA_DQ<23>       J26              183      SCONN288_ADR50001P003C01-SCONNA
M_E_CPU1_SA_DQ<23>       U1               EP65     SOCKET4677_AZIFS054P001C01-SOCA
M_E_CPU1_SA_DQ<24>       J25              40       SCONN288_ADR50001P013C01-SCONNA
M_E_CPU1_SA_DQ<24>       J26              40       SCONN288_ADR50001P003C01-SCONNA
M_E_CPU1_SA_DQ<24>       U1               EM63     SOCKET4677_AZIFS054P001C01-SOCA
M_E_CPU1_SA_DQ<25>       J25              42       SCONN288_ADR50001P013C01-SCONNA
M_E_CPU1_SA_DQ<25>       J26              42       SCONN288_ADR50001P003C01-SCONNA
M_E_CPU1_SA_DQ<25>       U1               EL62     SOCKET4677_AZIFS054P001C01-SOCA
M_E_CPU1_SA_DQ<26>       J25              185      SCONN288_ADR50001P013C01-SCONNA
M_E_CPU1_SA_DQ<26>       J26              185      SCONN288_ADR50001P003C01-SCONNA
M_E_CPU1_SA_DQ<26>       U1               EP63     SOCKET4677_AZIFS054P001C01-SOCA
M_E_CPU1_SA_DQ<27>       J25              187      SCONN288_ADR50001P013C01-SCONNA
M_E_CPU1_SA_DQ<27>       J26              187      SCONN288_ADR50001P003C01-SCONNA
M_E_CPU1_SA_DQ<27>       U1               ER62     SOCKET4677_AZIFS054P001C01-SOCA
M_E_CPU1_SA_DQ<28>       J25              47       SCONN288_ADR50001P013C01-SCONNA
M_E_CPU1_SA_DQ<28>       J26              47       SCONN288_ADR50001P003C01-SCONNA
M_E_CPU1_SA_DQ<28>       U1               EL60     SOCKET4677_AZIFS054P001C01-SOCA
M_E_CPU1_SA_DQ<29>       J25              49       SCONN288_ADR50001P013C01-SCONNA
M_E_CPU1_SA_DQ<29>       J26              49       SCONN288_ADR50001P003C01-SCONNA
M_E_CPU1_SA_DQ<29>       U1               EM59     SOCKET4677_AZIFS054P001C01-SOCA
M_E_CPU1_SA_DQ<30>       J25              192      SCONN288_ADR50001P013C01-SCONNA
M_E_CPU1_SA_DQ<30>       J26              192      SCONN288_ADR50001P003C01-SCONNA
M_E_CPU1_SA_DQ<30>       U1               ER60     SOCKET4677_AZIFS054P001C01-SOCA
M_E_CPU1_SA_DQ<31>       J25              194      SCONN288_ADR50001P013C01-SCONNA
M_E_CPU1_SA_DQ<31>       J26              194      SCONN288_ADR50001P003C01-SCONNA
M_E_CPU1_SA_DQ<31>       U1               EP59     SOCKET4677_AZIFS054P001C01-SOCA
M_E_CPU1_SA_DQS_DN<0>    J25              12       SCONN288_ADR50001P013C01-SCONNA
M_E_CPU1_SA_DQS_DN<0>    J26              12       SCONN288_ADR50001P003C01-SCONNA
M_E_CPU1_SA_DQS_DN<0>    U1               EP75     SOCKET4677_AZIFS054P001C01-SOCA
M_E_CPU1_SA_DQS_DN<1>    J25              23       SCONN288_ADR50001P013C01-SCONNA
M_E_CPU1_SA_DQS_DN<1>    J26              23       SCONN288_ADR50001P003C01-SCONNA
M_E_CPU1_SA_DQS_DN<1>    U1               EC70     SOCKET4677_AZIFS054P001C01-SOCA
M_E_CPU1_SA_DQS_DN<2>    J25              34       SCONN288_ADR50001P013C01-SCONNA
M_E_CPU1_SA_DQS_DN<2>    J26              34       SCONN288_ADR50001P003C01-SCONNA
M_E_CPU1_SA_DQS_DN<2>    U1               EK67     SOCKET4677_AZIFS054P001C01-SOCA
M_E_CPU1_SA_DQS_DN<3>    J25              45       SCONN288_ADR50001P013C01-SCONNA
M_E_CPU1_SA_DQS_DN<3>    J26              45       SCONN288_ADR50001P003C01-SCONNA
M_E_CPU1_SA_DQS_DN<3>    U1               EK61     SOCKET4677_AZIFS054P001C01-SOCA
M_E_CPU1_SA_DQS_DN<4>    J25              56       SCONN288_ADR50001P013C01-SCONNA
M_E_CPU1_SA_DQS_DN<4>    J26              56       SCONN288_ADR50001P003C01-SCONNA
M_E_CPU1_SA_DQS_DN<4>    U1               EM55     SOCKET4677_AZIFS054P001C01-SOCA
M_E_CPU1_SA_DQS_DN<5>    J25              156      SCONN288_ADR50001P013C01-SCONNA
M_E_CPU1_SA_DQS_DN<5>    J26              156      SCONN288_ADR50001P003C01-SCONNA
M_E_CPU1_SA_DQS_DN<5>    U1               EM75     SOCKET4677_AZIFS054P001C01-SOCA
M_E_CPU1_SA_DQS_DN<6>    J25              167      SCONN288_ADR50001P013C01-SCONNA
M_E_CPU1_SA_DQS_DN<6>    J26              167      SCONN288_ADR50001P003C01-SCONNA
M_E_CPU1_SA_DQS_DN<6>    U1               EJ70     SOCKET4677_AZIFS054P001C01-SOCA
M_E_CPU1_SA_DQS_DN<7>    J25              178      SCONN288_ADR50001P013C01-SCONNA
M_E_CPU1_SA_DQS_DN<7>    J26              178      SCONN288_ADR50001P003C01-SCONNA
M_E_CPU1_SA_DQS_DN<7>    U1               EN68     SOCKET4677_AZIFS054P001C01-SOCA
M_E_CPU1_SA_DQS_DN<8>    J25              189      SCONN288_ADR50001P013C01-SCONNA
M_E_CPU1_SA_DQS_DN<8>    J26              189      SCONN288_ADR50001P003C01-SCONNA
M_E_CPU1_SA_DQS_DN<8>    U1               ET61     SOCKET4677_AZIFS054P001C01-SOCA
M_E_CPU1_SA_DQS_DN<9>    J25              200      SCONN288_ADR50001P013C01-SCONNA
M_E_CPU1_SA_DQS_DN<9>    J26              200      SCONN288_ADR50001P003C01-SCONNA
M_E_CPU1_SA_DQS_DN<9>    U1               ET55     SOCKET4677_AZIFS054P001C01-SOCA
M_E_CPU1_SA_DQS_DP<0>    J25              11       SCONN288_ADR50001P013C01-SCONNA
M_E_CPU1_SA_DQS_DP<0>    J26              11       SCONN288_ADR50001P003C01-SCONNA
M_E_CPU1_SA_DQS_DP<0>    U1               EN76     SOCKET4677_AZIFS054P001C01-SOCA
M_E_CPU1_SA_DQS_DP<1>    J25              22       SCONN288_ADR50001P013C01-SCONNA
M_E_CPU1_SA_DQS_DP<1>    J26              22       SCONN288_ADR50001P003C01-SCONNA
M_E_CPU1_SA_DQS_DP<1>    U1               EE70     SOCKET4677_AZIFS054P001C01-SOCA
M_E_CPU1_SA_DQS_DP<2>    J25              33       SCONN288_ADR50001P013C01-SCONNA
M_E_CPU1_SA_DQS_DP<2>    J26              33       SCONN288_ADR50001P003C01-SCONNA
M_E_CPU1_SA_DQS_DP<2>    U1               EL68     SOCKET4677_AZIFS054P001C01-SOCA
M_E_CPU1_SA_DQS_DP<3>    J25              44       SCONN288_ADR50001P013C01-SCONNA
M_E_CPU1_SA_DQS_DP<3>    J26              44       SCONN288_ADR50001P003C01-SCONNA
M_E_CPU1_SA_DQS_DP<3>    U1               EM61     SOCKET4677_AZIFS054P001C01-SOCA
M_E_CPU1_SA_DQS_DP<4>    J25              55       SCONN288_ADR50001P013C01-SCONNA
M_E_CPU1_SA_DQS_DP<4>    J26              55       SCONN288_ADR50001P003C01-SCONNA
M_E_CPU1_SA_DQS_DP<4>    U1               EK55     SOCKET4677_AZIFS054P001C01-SOCA
M_E_CPU1_SA_DQS_DP<5>    J25              157      SCONN288_ADR50001P013C01-SCONNA
M_E_CPU1_SA_DQS_DP<5>    J26              157      SCONN288_ADR50001P003C01-SCONNA
M_E_CPU1_SA_DQS_DP<5>    U1               EN74     SOCKET4677_AZIFS054P001C01-SOCA
M_E_CPU1_SA_DQS_DP<6>    J25              168      SCONN288_ADR50001P013C01-SCONNA
M_E_CPU1_SA_DQS_DP<6>    J26              168      SCONN288_ADR50001P003C01-SCONNA
M_E_CPU1_SA_DQS_DP<6>    U1               EG70     SOCKET4677_AZIFS054P001C01-SOCA
M_E_CPU1_SA_DQS_DP<7>    J25              179      SCONN288_ADR50001P013C01-SCONNA
M_E_CPU1_SA_DQS_DP<7>    J26              179      SCONN288_ADR50001P003C01-SCONNA
M_E_CPU1_SA_DQS_DP<7>    U1               EM67     SOCKET4677_AZIFS054P001C01-SOCA
M_E_CPU1_SA_DQS_DP<8>    J25              190      SCONN288_ADR50001P013C01-SCONNA
M_E_CPU1_SA_DQS_DP<8>    J26              190      SCONN288_ADR50001P003C01-SCONNA
M_E_CPU1_SA_DQS_DP<8>    U1               EP61     SOCKET4677_AZIFS054P001C01-SOCA
M_E_CPU1_SA_DQS_DP<9>    J25              201      SCONN288_ADR50001P013C01-SCONNA
M_E_CPU1_SA_DQS_DP<9>    J26              201      SCONN288_ADR50001P003C01-SCONNA
M_E_CPU1_SA_DQS_DP<9>    U1               EP55     SOCKET4677_AZIFS054P001C01-SOCA
M_E_CPU1_SA_PAR          J25              74       SCONN288_ADR50001P013C01-SCONNA
M_E_CPU1_SA_PAR          J26              74       SCONN288_ADR50001P003C01-SCONNA
M_E_CPU1_SA_PAR          U1               EE43     SOCKET4677_AZIFS054P001C01-SOCA
M_E_CPU1_SA_RSP<0>       J25              86       SCONN288_ADR50001P013C01-SCONNA
M_E_CPU1_SA_RSP<0>       U1               DD44     SOCKET4677_AZIFS054P001C01-SOCA
M_E_CPU1_SA_RSP<1>       J26              86       SCONN288_ADR50001P003C01-SCONNA
M_E_CPU1_SA_RSP<1>       U1               DC43     SOCKET4677_AZIFS054P001C01-SOCA
M_E_CPU1_SB_CA<0>        J25              76       SCONN288_ADR50001P013C01-SCONNA
M_E_CPU1_SB_CA<0>        J26              76       SCONN288_ADR50001P003C01-SCONNA
M_E_CPU1_SB_CA<0>        U1               EG43     SOCKET4677_AZIFS054P001C01-SOCA
M_E_CPU1_SB_CA<1>        J25              221      SCONN288_ADR50001P013C01-SCONNA
M_E_CPU1_SB_CA<1>        J26              221      SCONN288_ADR50001P003C01-SCONNA
M_E_CPU1_SB_CA<1>        U1               EH44     SOCKET4677_AZIFS054P001C01-SOCA
M_E_CPU1_SB_CA<2>        J25              78       SCONN288_ADR50001P013C01-SCONNA
M_E_CPU1_SB_CA<2>        J26              78       SCONN288_ADR50001P003C01-SCONNA
M_E_CPU1_SB_CA<2>        U1               EM44     SOCKET4677_AZIFS054P001C01-SOCA
M_E_CPU1_SB_CA<3>        J25              223      SCONN288_ADR50001P013C01-SCONNA
M_E_CPU1_SB_CA<3>        J26              223      SCONN288_ADR50001P003C01-SCONNA
M_E_CPU1_SB_CA<3>        U1               EP44     SOCKET4677_AZIFS054P001C01-SOCA
M_E_CPU1_SB_CA<4>        J25              80       SCONN288_ADR50001P013C01-SCONNA
M_E_CPU1_SB_CA<4>        J26              80       SCONN288_ADR50001P003C01-SCONNA
M_E_CPU1_SB_CA<4>        U1               EL43     SOCKET4677_AZIFS054P001C01-SOCA
M_E_CPU1_SB_CA<5>        J25              225      SCONN288_ADR50001P013C01-SCONNA
M_E_CPU1_SB_CA<5>        J26              225      SCONN288_ADR50001P003C01-SCONNA
M_E_CPU1_SB_CA<5>        U1               ET42     SOCKET4677_AZIFS054P001C01-SOCA
M_E_CPU1_SB_CA<6>        J25              82       SCONN288_ADR50001P013C01-SCONNA
M_E_CPU1_SB_CA<6>        J26              82       SCONN288_ADR50001P003C01-SCONNA
M_E_CPU1_SB_CA<6>        U1               EK42     SOCKET4677_AZIFS054P001C01-SOCA
M_E_CPU1_SB_CB<0>        J25              96       SCONN288_ADR50001P013C01-SCONNA
M_E_CPU1_SB_CB<0>        J26              96       SCONN288_ADR50001P003C01-SCONNA
M_E_CPU1_SB_CB<0>        U1               EL35     SOCKET4677_AZIFS054P001C01-SOCA
M_E_CPU1_SB_CB<1>        J25              98       SCONN288_ADR50001P013C01-SCONNA
M_E_CPU1_SB_CB<1>        J26              98       SCONN288_ADR50001P003C01-SCONNA
M_E_CPU1_SB_CB<1>        U1               EM34     SOCKET4677_AZIFS054P001C01-SOCA
M_E_CPU1_SB_CB<2>        J25              241      SCONN288_ADR50001P013C01-SCONNA
M_E_CPU1_SB_CB<2>        J26              241      SCONN288_ADR50001P003C01-SCONNA
M_E_CPU1_SB_CB<2>        U1               ER35     SOCKET4677_AZIFS054P001C01-SOCA
M_E_CPU1_SB_CB<3>        J25              243      SCONN288_ADR50001P013C01-SCONNA
M_E_CPU1_SB_CB<3>        J26              243      SCONN288_ADR50001P003C01-SCONNA
M_E_CPU1_SB_CB<3>        U1               EP34     SOCKET4677_AZIFS054P001C01-SOCA
M_E_CPU1_SB_CB<4>        J25              89       SCONN288_ADR50001P013C01-SCONNA
M_E_CPU1_SB_CB<4>        J26              89       SCONN288_ADR50001P003C01-SCONNA
M_E_CPU1_SB_CB<4>        U1               EM38     SOCKET4677_AZIFS054P001C01-SOCA
M_E_CPU1_SB_CB<5>        J25              91       SCONN288_ADR50001P013C01-SCONNA
M_E_CPU1_SB_CB<5>        J26              91       SCONN288_ADR50001P003C01-SCONNA
M_E_CPU1_SB_CB<5>        U1               EL37     SOCKET4677_AZIFS054P001C01-SOCA
M_E_CPU1_SB_CB<6>        J25              234      SCONN288_ADR50001P013C01-SCONNA
M_E_CPU1_SB_CB<6>        J26              234      SCONN288_ADR50001P003C01-SCONNA
M_E_CPU1_SB_CB<6>        U1               EP38     SOCKET4677_AZIFS054P001C01-SOCA
M_E_CPU1_SB_CB<7>        J25              236      SCONN288_ADR50001P013C01-SCONNA
M_E_CPU1_SB_CB<7>        J26              236      SCONN288_ADR50001P003C01-SCONNA
M_E_CPU1_SB_CB<7>        U1               ER37     SOCKET4677_AZIFS054P001C01-SOCA
M_E_CPU1_SB_CS_N<0>      J25              84       SCONN288_ADR50001P013C01-SCONNA
M_E_CPU1_SB_CS_N<0>      U1               EP40     SOCKET4677_AZIFS054P001C01-SOCA
M_E_CPU1_SB_CS_N<1>      J25              229      SCONN288_ADR50001P013C01-SCONNA
M_E_CPU1_SB_CS_N<1>      U1               ET40     SOCKET4677_AZIFS054P001C01-SOCA
M_E_CPU1_SB_CS_N<2>      J26              84       SCONN288_ADR50001P003C01-SCONNA
M_E_CPU1_SB_CS_N<2>      U1               EM40     SOCKET4677_AZIFS054P001C01-SOCA
M_E_CPU1_SB_CS_N<3>      J26              229      SCONN288_ADR50001P003C01-SCONNA
M_E_CPU1_SB_CS_N<3>      U1               EL41     SOCKET4677_AZIFS054P001C01-SOCA
M_E_CPU1_SB_DQ<0>        J25              100      SCONN288_ADR50001P013C01-SCONNA
M_E_CPU1_SB_DQ<0>        J26              100      SCONN288_ADR50001P003C01-SCONNA
M_E_CPU1_SB_DQ<0>        U1               EE29     SOCKET4677_AZIFS054P001C01-SOCA
M_E_CPU1_SB_DQ<1>        J25              102      SCONN288_ADR50001P013C01-SCONNA
M_E_CPU1_SB_DQ<1>        J26              102      SCONN288_ADR50001P003C01-SCONNA
M_E_CPU1_SB_DQ<1>        U1               ED28     SOCKET4677_AZIFS054P001C01-SOCA
M_E_CPU1_SB_DQ<2>        J25              245      SCONN288_ADR50001P013C01-SCONNA
M_E_CPU1_SB_DQ<2>        J26              245      SCONN288_ADR50001P003C01-SCONNA
M_E_CPU1_SB_DQ<2>        U1               EG29     SOCKET4677_AZIFS054P001C01-SOCA
M_E_CPU1_SB_DQ<3>        J25              247      SCONN288_ADR50001P013C01-SCONNA
M_E_CPU1_SB_DQ<3>        J26              247      SCONN288_ADR50001P003C01-SCONNA
M_E_CPU1_SB_DQ<3>        U1               EH28     SOCKET4677_AZIFS054P001C01-SOCA
M_E_CPU1_SB_DQ<4>        J25              107      SCONN288_ADR50001P013C01-SCONNA
M_E_CPU1_SB_DQ<4>        J26              107      SCONN288_ADR50001P003C01-SCONNA
M_E_CPU1_SB_DQ<4>        U1               ED26     SOCKET4677_AZIFS054P001C01-SOCA
M_E_CPU1_SB_DQ<5>        J25              109      SCONN288_ADR50001P013C01-SCONNA
M_E_CPU1_SB_DQ<5>        J26              109      SCONN288_ADR50001P003C01-SCONNA
M_E_CPU1_SB_DQ<5>        U1               EE25     SOCKET4677_AZIFS054P001C01-SOCA
M_E_CPU1_SB_DQ<6>        J25              252      SCONN288_ADR50001P013C01-SCONNA
M_E_CPU1_SB_DQ<6>        J26              252      SCONN288_ADR50001P003C01-SCONNA
M_E_CPU1_SB_DQ<6>        U1               EH26     SOCKET4677_AZIFS054P001C01-SOCA
M_E_CPU1_SB_DQ<7>        J25              254      SCONN288_ADR50001P013C01-SCONNA
M_E_CPU1_SB_DQ<7>        J26              254      SCONN288_ADR50001P003C01-SCONNA
M_E_CPU1_SB_DQ<7>        U1               EG25     SOCKET4677_AZIFS054P001C01-SOCA
M_E_CPU1_SB_DQ<8>        J25              111      SCONN288_ADR50001P013C01-SCONNA
M_E_CPU1_SB_DQ<8>        J26              111      SCONN288_ADR50001P003C01-SCONNA
M_E_CPU1_SB_DQ<8>        U1               EM32     SOCKET4677_AZIFS054P001C01-SOCA
M_E_CPU1_SB_DQ<9>        J25              113      SCONN288_ADR50001P013C01-SCONNA
M_E_CPU1_SB_DQ<9>        J26              113      SCONN288_ADR50001P003C01-SCONNA
M_E_CPU1_SB_DQ<9>        U1               EL31     SOCKET4677_AZIFS054P001C01-SOCA
M_E_CPU1_SB_DQ<10>       J25              256      SCONN288_ADR50001P013C01-SCONNA
M_E_CPU1_SB_DQ<10>       J26              256      SCONN288_ADR50001P003C01-SCONNA
M_E_CPU1_SB_DQ<10>       U1               EP32     SOCKET4677_AZIFS054P001C01-SOCA
M_E_CPU1_SB_DQ<11>       J25              258      SCONN288_ADR50001P013C01-SCONNA
M_E_CPU1_SB_DQ<11>       J26              258      SCONN288_ADR50001P003C01-SCONNA
M_E_CPU1_SB_DQ<11>       U1               ER31     SOCKET4677_AZIFS054P001C01-SOCA
M_E_CPU1_SB_DQ<12>       J25              118      SCONN288_ADR50001P013C01-SCONNA
M_E_CPU1_SB_DQ<12>       J26              118      SCONN288_ADR50001P003C01-SCONNA
M_E_CPU1_SB_DQ<12>       U1               EL29     SOCKET4677_AZIFS054P001C01-SOCA
M_E_CPU1_SB_DQ<13>       J25              120      SCONN288_ADR50001P013C01-SCONNA
M_E_CPU1_SB_DQ<13>       J26              120      SCONN288_ADR50001P003C01-SCONNA
M_E_CPU1_SB_DQ<13>       U1               EM28     SOCKET4677_AZIFS054P001C01-SOCA
M_E_CPU1_SB_DQ<14>       J25              263      SCONN288_ADR50001P013C01-SCONNA
M_E_CPU1_SB_DQ<14>       J26              263      SCONN288_ADR50001P003C01-SCONNA
M_E_CPU1_SB_DQ<14>       U1               ER29     SOCKET4677_AZIFS054P001C01-SOCA
M_E_CPU1_SB_DQ<15>       J25              265      SCONN288_ADR50001P013C01-SCONNA
M_E_CPU1_SB_DQ<15>       J26              265      SCONN288_ADR50001P003C01-SCONNA
M_E_CPU1_SB_DQ<15>       U1               EP28     SOCKET4677_AZIFS054P001C01-SOCA
M_E_CPU1_SB_DQ<16>       J25              122      SCONN288_ADR50001P013C01-SCONNA
M_E_CPU1_SB_DQ<16>       J26              122      SCONN288_ADR50001P003C01-SCONNA
M_E_CPU1_SB_DQ<16>       U1               EM26     SOCKET4677_AZIFS054P001C01-SOCA
M_E_CPU1_SB_DQ<17>       J25              124      SCONN288_ADR50001P013C01-SCONNA
M_E_CPU1_SB_DQ<17>       J26              124      SCONN288_ADR50001P003C01-SCONNA
M_E_CPU1_SB_DQ<17>       U1               EL25     SOCKET4677_AZIFS054P001C01-SOCA
M_E_CPU1_SB_DQ<18>       J25              267      SCONN288_ADR50001P013C01-SCONNA
M_E_CPU1_SB_DQ<18>       J26              267      SCONN288_ADR50001P003C01-SCONNA
M_E_CPU1_SB_DQ<18>       U1               EP26     SOCKET4677_AZIFS054P001C01-SOCA
M_E_CPU1_SB_DQ<19>       J25              269      SCONN288_ADR50001P013C01-SCONNA
M_E_CPU1_SB_DQ<19>       J26              269      SCONN288_ADR50001P003C01-SCONNA
M_E_CPU1_SB_DQ<19>       U1               ER25     SOCKET4677_AZIFS054P001C01-SOCA
M_E_CPU1_SB_DQ<20>       J25              129      SCONN288_ADR50001P013C01-SCONNA
M_E_CPU1_SB_DQ<20>       J26              129      SCONN288_ADR50001P003C01-SCONNA
M_E_CPU1_SB_DQ<20>       U1               EL23     SOCKET4677_AZIFS054P001C01-SOCA
M_E_CPU1_SB_DQ<21>       J25              131      SCONN288_ADR50001P013C01-SCONNA
M_E_CPU1_SB_DQ<21>       J26              131      SCONN288_ADR50001P003C01-SCONNA
M_E_CPU1_SB_DQ<21>       U1               EM22     SOCKET4677_AZIFS054P001C01-SOCA
M_E_CPU1_SB_DQ<22>       J25              274      SCONN288_ADR50001P013C01-SCONNA
M_E_CPU1_SB_DQ<22>       J26              274      SCONN288_ADR50001P003C01-SCONNA
M_E_CPU1_SB_DQ<22>       U1               ER23     SOCKET4677_AZIFS054P001C01-SOCA
M_E_CPU1_SB_DQ<23>       J25              276      SCONN288_ADR50001P013C01-SCONNA
M_E_CPU1_SB_DQ<23>       J26              276      SCONN288_ADR50001P003C01-SCONNA
M_E_CPU1_SB_DQ<23>       U1               EP22     SOCKET4677_AZIFS054P001C01-SOCA
M_E_CPU1_SB_DQ<24>       J25              133      SCONN288_ADR50001P013C01-SCONNA
M_E_CPU1_SB_DQ<24>       J26              133      SCONN288_ADR50001P003C01-SCONNA
M_E_CPU1_SB_DQ<24>       U1               EM20     SOCKET4677_AZIFS054P001C01-SOCA
M_E_CPU1_SB_DQ<25>       J25              135      SCONN288_ADR50001P013C01-SCONNA
M_E_CPU1_SB_DQ<25>       J26              135      SCONN288_ADR50001P003C01-SCONNA
M_E_CPU1_SB_DQ<25>       U1               EL19     SOCKET4677_AZIFS054P001C01-SOCA
M_E_CPU1_SB_DQ<26>       J25              278      SCONN288_ADR50001P013C01-SCONNA
M_E_CPU1_SB_DQ<26>       J26              278      SCONN288_ADR50001P003C01-SCONNA
M_E_CPU1_SB_DQ<26>       U1               EP20     SOCKET4677_AZIFS054P001C01-SOCA
M_E_CPU1_SB_DQ<27>       J25              280      SCONN288_ADR50001P013C01-SCONNA
M_E_CPU1_SB_DQ<27>       J26              280      SCONN288_ADR50001P003C01-SCONNA
M_E_CPU1_SB_DQ<27>       U1               ER19     SOCKET4677_AZIFS054P001C01-SOCA
M_E_CPU1_SB_DQ<28>       J25              140      SCONN288_ADR50001P013C01-SCONNA
M_E_CPU1_SB_DQ<28>       J26              140      SCONN288_ADR50001P003C01-SCONNA
M_E_CPU1_SB_DQ<28>       U1               EL17     SOCKET4677_AZIFS054P001C01-SOCA
M_E_CPU1_SB_DQ<29>       J25              142      SCONN288_ADR50001P013C01-SCONNA
M_E_CPU1_SB_DQ<29>       J26              142      SCONN288_ADR50001P003C01-SCONNA
M_E_CPU1_SB_DQ<29>       U1               EM16     SOCKET4677_AZIFS054P001C01-SOCA
M_E_CPU1_SB_DQ<30>       J25              285      SCONN288_ADR50001P013C01-SCONNA
M_E_CPU1_SB_DQ<30>       J26              285      SCONN288_ADR50001P003C01-SCONNA
M_E_CPU1_SB_DQ<30>       U1               ER17     SOCKET4677_AZIFS054P001C01-SOCA
M_E_CPU1_SB_DQ<31>       J25              287      SCONN288_ADR50001P013C01-SCONNA
M_E_CPU1_SB_DQ<31>       J26              287      SCONN288_ADR50001P003C01-SCONNA
M_E_CPU1_SB_DQ<31>       U1               EP16     SOCKET4677_AZIFS054P001C01-SOCA
M_E_CPU1_SB_DQS_DN<0>    J25              105      SCONN288_ADR50001P013C01-SCONNA
M_E_CPU1_SB_DQS_DN<0>    J26              105      SCONN288_ADR50001P003C01-SCONNA
M_E_CPU1_SB_DQS_DN<0>    U1               EE27     SOCKET4677_AZIFS054P001C01-SOCA
M_E_CPU1_SB_DQS_DN<1>    J25              116      SCONN288_ADR50001P013C01-SCONNA
M_E_CPU1_SB_DQS_DN<1>    J26              116      SCONN288_ADR50001P003C01-SCONNA
M_E_CPU1_SB_DQS_DN<1>    U1               EK30     SOCKET4677_AZIFS054P001C01-SOCA
M_E_CPU1_SB_DQS_DN<2>    J25              127      SCONN288_ADR50001P013C01-SCONNA
M_E_CPU1_SB_DQS_DN<2>    J26              127      SCONN288_ADR50001P003C01-SCONNA
M_E_CPU1_SB_DQS_DN<2>    U1               EK24     SOCKET4677_AZIFS054P001C01-SOCA
M_E_CPU1_SB_DQS_DN<3>    J25              138      SCONN288_ADR50001P013C01-SCONNA
M_E_CPU1_SB_DQS_DN<3>    J26              138      SCONN288_ADR50001P003C01-SCONNA
M_E_CPU1_SB_DQS_DN<3>    U1               EK18     SOCKET4677_AZIFS054P001C01-SOCA
M_E_CPU1_SB_DQS_DN<4>    J25              238      SCONN288_ADR50001P013C01-SCONNA
M_E_CPU1_SB_DQS_DN<4>    J26              238      SCONN288_ADR50001P003C01-SCONNA
M_E_CPU1_SB_DQS_DN<4>    U1               ET36     SOCKET4677_AZIFS054P001C01-SOCA
M_E_CPU1_SB_DQS_DN<5>    J25              249      SCONN288_ADR50001P013C01-SCONNA
M_E_CPU1_SB_DQS_DN<5>    J26              249      SCONN288_ADR50001P003C01-SCONNA
M_E_CPU1_SB_DQS_DN<5>    U1               EJ27     SOCKET4677_AZIFS054P001C01-SOCA
M_E_CPU1_SB_DQS_DN<6>    J25              260      SCONN288_ADR50001P013C01-SCONNA
M_E_CPU1_SB_DQS_DN<6>    J26              260      SCONN288_ADR50001P003C01-SCONNA
M_E_CPU1_SB_DQS_DN<6>    U1               ET30     SOCKET4677_AZIFS054P001C01-SOCA
M_E_CPU1_SB_DQS_DN<7>    J25              271      SCONN288_ADR50001P013C01-SCONNA
M_E_CPU1_SB_DQS_DN<7>    J26              271      SCONN288_ADR50001P003C01-SCONNA
M_E_CPU1_SB_DQS_DN<7>    U1               ET24     SOCKET4677_AZIFS054P001C01-SOCA
M_E_CPU1_SB_DQS_DN<8>    J25              282      SCONN288_ADR50001P013C01-SCONNA
M_E_CPU1_SB_DQS_DN<8>    J26              282      SCONN288_ADR50001P003C01-SCONNA
M_E_CPU1_SB_DQS_DN<8>    U1               ET18     SOCKET4677_AZIFS054P001C01-SOCA
M_E_CPU1_SB_DQS_DN<9>    J25              94       SCONN288_ADR50001P013C01-SCONNA
M_E_CPU1_SB_DQS_DN<9>    J26              94       SCONN288_ADR50001P003C01-SCONNA
M_E_CPU1_SB_DQS_DN<9>    U1               EK36     SOCKET4677_AZIFS054P001C01-SOCA
M_E_CPU1_SB_DQS_DP<0>    J25              104      SCONN288_ADR50001P013C01-SCONNA
M_E_CPU1_SB_DQS_DP<0>    J26              104      SCONN288_ADR50001P003C01-SCONNA
M_E_CPU1_SB_DQS_DP<0>    U1               EC27     SOCKET4677_AZIFS054P001C01-SOCA
M_E_CPU1_SB_DQS_DP<1>    J25              115      SCONN288_ADR50001P013C01-SCONNA
M_E_CPU1_SB_DQS_DP<1>    J26              115      SCONN288_ADR50001P003C01-SCONNA
M_E_CPU1_SB_DQS_DP<1>    U1               EM30     SOCKET4677_AZIFS054P001C01-SOCA
M_E_CPU1_SB_DQS_DP<2>    J25              126      SCONN288_ADR50001P013C01-SCONNA
M_E_CPU1_SB_DQS_DP<2>    J26              126      SCONN288_ADR50001P003C01-SCONNA
M_E_CPU1_SB_DQS_DP<2>    U1               EM24     SOCKET4677_AZIFS054P001C01-SOCA
M_E_CPU1_SB_DQS_DP<3>    J25              137      SCONN288_ADR50001P013C01-SCONNA
M_E_CPU1_SB_DQS_DP<3>    J26              137      SCONN288_ADR50001P003C01-SCONNA
M_E_CPU1_SB_DQS_DP<3>    U1               EM18     SOCKET4677_AZIFS054P001C01-SOCA
M_E_CPU1_SB_DQS_DP<4>    J25              239      SCONN288_ADR50001P013C01-SCONNA
M_E_CPU1_SB_DQS_DP<4>    J26              239      SCONN288_ADR50001P003C01-SCONNA
M_E_CPU1_SB_DQS_DP<4>    U1               EP36     SOCKET4677_AZIFS054P001C01-SOCA
M_E_CPU1_SB_DQS_DP<5>    J25              250      SCONN288_ADR50001P013C01-SCONNA
M_E_CPU1_SB_DQS_DP<5>    J26              250      SCONN288_ADR50001P003C01-SCONNA
M_E_CPU1_SB_DQS_DP<5>    U1               EG27     SOCKET4677_AZIFS054P001C01-SOCA
M_E_CPU1_SB_DQS_DP<6>    J25              261      SCONN288_ADR50001P013C01-SCONNA
M_E_CPU1_SB_DQS_DP<6>    J26              261      SCONN288_ADR50001P003C01-SCONNA
M_E_CPU1_SB_DQS_DP<6>    U1               EP30     SOCKET4677_AZIFS054P001C01-SOCA
M_E_CPU1_SB_DQS_DP<7>    J25              272      SCONN288_ADR50001P013C01-SCONNA
M_E_CPU1_SB_DQS_DP<7>    J26              272      SCONN288_ADR50001P003C01-SCONNA
M_E_CPU1_SB_DQS_DP<7>    U1               EP24     SOCKET4677_AZIFS054P001C01-SOCA
M_E_CPU1_SB_DQS_DP<8>    J25              283      SCONN288_ADR50001P013C01-SCONNA
M_E_CPU1_SB_DQS_DP<8>    J26              283      SCONN288_ADR50001P003C01-SCONNA
M_E_CPU1_SB_DQS_DP<8>    U1               EP18     SOCKET4677_AZIFS054P001C01-SOCA
M_E_CPU1_SB_DQS_DP<9>    J25              93       SCONN288_ADR50001P013C01-SCONNA
M_E_CPU1_SB_DQS_DP<9>    J26              93       SCONN288_ADR50001P003C01-SCONNA
M_E_CPU1_SB_DQS_DP<9>    U1               EM36     SOCKET4677_AZIFS054P001C01-SOCA
M_E_CPU1_SB_PAR          J25              227      SCONN288_ADR50001P013C01-SCONNA
M_E_CPU1_SB_PAR          J26              227      SCONN288_ADR50001P003C01-SCONNA
M_E_CPU1_SB_PAR          U1               EP42     SOCKET4677_AZIFS054P001C01-SOCA
M_E_CPU1_SB_RSP<0>       J25              87       SCONN288_ADR50001P013C01-SCONNA
M_E_CPU1_SB_RSP<0>       U1               DF44     SOCKET4677_AZIFS054P001C01-SOCA
M_E_CPU1_SB_RSP<1>       J26              87       SCONN288_ADR50001P003C01-SCONNA
M_E_CPU1_SB_RSP<1>       U1               DG43     SOCKET4677_AZIFS054P001C01-SOCA
M_F_CPU0_ALERT_N         J11              62       SCONN288_ADR50001P013C01-SCONNA
M_F_CPU0_ALERT_N         J12              62       SCONN288_ADR50001P003C01-SCONNA
M_F_CPU0_ALERT_N         U2               CW48     SOCKET4677_AZIFS054P001C01-SOCA
M_F_CPU0_CLK_DN<0>       J11              218      SCONN288_ADR50001P013C01-SCONNA
M_F_CPU0_CLK_DN<0>       U2               DY49     SOCKET4677_AZIFS054P001C01-SOCA
M_F_CPU0_CLK_DN<1>       J12              218      SCONN288_ADR50001P003C01-SCONNA
M_F_CPU0_CLK_DN<1>       U2               DV49     SOCKET4677_AZIFS054P001C01-SOCA
M_F_CPU0_CLK_DP<0>       J11              217      SCONN288_ADR50001P013C01-SCONNA
M_F_CPU0_CLK_DP<0>       U2               EB49     SOCKET4677_AZIFS054P001C01-SOCA
M_F_CPU0_CLK_DP<1>       J12              217      SCONN288_ADR50001P003C01-SCONNA
M_F_CPU0_CLK_DP<1>       U2               DT49     SOCKET4677_AZIFS054P001C01-SOCA
M_F_CPU0_SA_CA<0>        J11              66       SCONN288_ADR50001P013C01-SCONNA
M_F_CPU0_SA_CA<0>        J12              66       SCONN288_ADR50001P003C01-SCONNA
M_F_CPU0_SA_CA<0>        U2               EC52     SOCKET4677_AZIFS054P001C01-SOCA
M_F_CPU0_SA_CA<1>        J11              211      SCONN288_ADR50001P013C01-SCONNA
M_F_CPU0_SA_CA<1>        J12              211      SCONN288_ADR50001P003C01-SCONNA
M_F_CPU0_SA_CA<1>        U2               EJ52     SOCKET4677_AZIFS054P001C01-SOCA
M_F_CPU0_SA_CA<2>        J11              68       SCONN288_ADR50001P013C01-SCONNA
M_F_CPU0_SA_CA<2>        J12              68       SCONN288_ADR50001P003C01-SCONNA
M_F_CPU0_SA_CA<2>        U2               ED51     SOCKET4677_AZIFS054P001C01-SOCA
M_F_CPU0_SA_CA<3>        J11              213      SCONN288_ADR50001P013C01-SCONNA
M_F_CPU0_SA_CA<3>        J12              213      SCONN288_ADR50001P003C01-SCONNA
M_F_CPU0_SA_CA<3>        U2               EH51     SOCKET4677_AZIFS054P001C01-SOCA
M_F_CPU0_SA_CA<4>        J11              70       SCONN288_ADR50001P013C01-SCONNA
M_F_CPU0_SA_CA<4>        J12              70       SCONN288_ADR50001P003C01-SCONNA
M_F_CPU0_SA_CA<4>        U2               EE50     SOCKET4677_AZIFS054P001C01-SOCA
M_F_CPU0_SA_CA<5>        J11              215      SCONN288_ADR50001P013C01-SCONNA
M_F_CPU0_SA_CA<5>        J12              215      SCONN288_ADR50001P003C01-SCONNA
M_F_CPU0_SA_CA<5>        U2               EG50     SOCKET4677_AZIFS054P001C01-SOCA
M_F_CPU0_SA_CA<6>        J11              72       SCONN288_ADR50001P013C01-SCONNA
M_F_CPU0_SA_CA<6>        J12              72       SCONN288_ADR50001P003C01-SCONNA
M_F_CPU0_SA_CA<6>        U2               DY51     SOCKET4677_AZIFS054P001C01-SOCA
M_F_CPU0_SA_CB<0>        J11              51       SCONN288_ADR50001P013C01-SCONNA
M_F_CPU0_SA_CB<0>        J12              51       SCONN288_ADR50001P003C01-SCONNA
M_F_CPU0_SA_CB<0>        U2               EE60     SOCKET4677_AZIFS054P001C01-SOCA
M_F_CPU0_SA_CB<1>        J11              53       SCONN288_ADR50001P013C01-SCONNA
M_F_CPU0_SA_CB<1>        J12              53       SCONN288_ADR50001P003C01-SCONNA
M_F_CPU0_SA_CB<1>        U2               ED59     SOCKET4677_AZIFS054P001C01-SOCA
M_F_CPU0_SA_CB<2>        J11              196      SCONN288_ADR50001P013C01-SCONNA
M_F_CPU0_SA_CB<2>        J12              196      SCONN288_ADR50001P003C01-SCONNA
M_F_CPU0_SA_CB<2>        U2               EG60     SOCKET4677_AZIFS054P001C01-SOCA
M_F_CPU0_SA_CB<3>        J11              198      SCONN288_ADR50001P013C01-SCONNA
M_F_CPU0_SA_CB<3>        J12              198      SCONN288_ADR50001P003C01-SCONNA
M_F_CPU0_SA_CB<3>        U2               EH59     SOCKET4677_AZIFS054P001C01-SOCA
M_F_CPU0_SA_CB<4>        J11              58       SCONN288_ADR50001P013C01-SCONNA
M_F_CPU0_SA_CB<4>        J12              58       SCONN288_ADR50001P003C01-SCONNA
M_F_CPU0_SA_CB<4>        U2               ED57     SOCKET4677_AZIFS054P001C01-SOCA
M_F_CPU0_SA_CB<5>        J11              60       SCONN288_ADR50001P013C01-SCONNA
M_F_CPU0_SA_CB<5>        J12              60       SCONN288_ADR50001P003C01-SCONNA
M_F_CPU0_SA_CB<5>        U2               EE56     SOCKET4677_AZIFS054P001C01-SOCA
M_F_CPU0_SA_CB<6>        J11              203      SCONN288_ADR50001P013C01-SCONNA
M_F_CPU0_SA_CB<6>        J12              203      SCONN288_ADR50001P003C01-SCONNA
M_F_CPU0_SA_CB<6>        U2               EH57     SOCKET4677_AZIFS054P001C01-SOCA
M_F_CPU0_SA_CB<7>        J11              205      SCONN288_ADR50001P013C01-SCONNA
M_F_CPU0_SA_CB<7>        J12              205      SCONN288_ADR50001P003C01-SCONNA
M_F_CPU0_SA_CB<7>        U2               EG56     SOCKET4677_AZIFS054P001C01-SOCA
M_F_CPU0_SA_CS_N<0>      J11              64       SCONN288_ADR50001P013C01-SCONNA
M_F_CPU0_SA_CS_N<0>      U2               EG54     SOCKET4677_AZIFS054P001C01-SOCA
M_F_CPU0_SA_CS_N<1>      J11              209      SCONN288_ADR50001P013C01-SCONNA
M_F_CPU0_SA_CS_N<1>      U2               EH53     SOCKET4677_AZIFS054P001C01-SOCA
M_F_CPU0_SA_CS_N<2>      J12              64       SCONN288_ADR50001P003C01-SCONNA
M_F_CPU0_SA_CS_N<2>      U2               EE54     SOCKET4677_AZIFS054P001C01-SOCA
M_F_CPU0_SA_CS_N<3>      J12              209      SCONN288_ADR50001P003C01-SCONNA
M_F_CPU0_SA_CS_N<3>      U2               ED53     SOCKET4677_AZIFS054P001C01-SOCA
M_F_CPU0_SA_DQ<0>        J11              7        SCONN288_ADR50001P013C01-SCONNA
M_F_CPU0_SA_DQ<0>        J12              7        SCONN288_ADR50001P003C01-SCONNA
M_F_CPU0_SA_DQ<0>        U2               EB77     SOCKET4677_AZIFS054P001C01-SOCA
M_F_CPU0_SA_DQ<1>        J11              9        SCONN288_ADR50001P013C01-SCONNA
M_F_CPU0_SA_DQ<1>        J12              9        SCONN288_ADR50001P003C01-SCONNA
M_F_CPU0_SA_DQ<1>        U2               EH77     SOCKET4677_AZIFS054P001C01-SOCA
M_F_CPU0_SA_DQ<2>        J11              152      SCONN288_ADR50001P013C01-SCONNA
M_F_CPU0_SA_DQ<2>        J12              152      SCONN288_ADR50001P003C01-SCONNA
M_F_CPU0_SA_DQ<2>        U2               ED77     SOCKET4677_AZIFS054P001C01-SOCA
M_F_CPU0_SA_DQ<3>        J11              154      SCONN288_ADR50001P013C01-SCONNA
M_F_CPU0_SA_DQ<3>        J12              154      SCONN288_ADR50001P003C01-SCONNA
M_F_CPU0_SA_DQ<3>        U2               EG78     SOCKET4677_AZIFS054P001C01-SOCA
M_F_CPU0_SA_DQ<4>        J11              14       SCONN288_ADR50001P013C01-SCONNA
M_F_CPU0_SA_DQ<4>        J12              14       SCONN288_ADR50001P003C01-SCONNA
M_F_CPU0_SA_DQ<4>        U2               ED75     SOCKET4677_AZIFS054P001C01-SOCA
M_F_CPU0_SA_DQ<5>        J11              16       SCONN288_ADR50001P013C01-SCONNA
M_F_CPU0_SA_DQ<5>        J12              16       SCONN288_ADR50001P003C01-SCONNA
M_F_CPU0_SA_DQ<5>        U2               EE74     SOCKET4677_AZIFS054P001C01-SOCA
M_F_CPU0_SA_DQ<6>        J11              159      SCONN288_ADR50001P013C01-SCONNA
M_F_CPU0_SA_DQ<6>        J12              159      SCONN288_ADR50001P003C01-SCONNA
M_F_CPU0_SA_DQ<6>        U2               EH75     SOCKET4677_AZIFS054P001C01-SOCA
M_F_CPU0_SA_DQ<7>        J11              161      SCONN288_ADR50001P013C01-SCONNA
M_F_CPU0_SA_DQ<7>        J12              161      SCONN288_ADR50001P003C01-SCONNA
M_F_CPU0_SA_DQ<7>        U2               EG74     SOCKET4677_AZIFS054P001C01-SOCA
M_F_CPU0_SA_DQ<8>        J11              18       SCONN288_ADR50001P013C01-SCONNA
M_F_CPU0_SA_DQ<8>        J12              18       SCONN288_ADR50001P003C01-SCONNA
M_F_CPU0_SA_DQ<8>        U2               DV69     SOCKET4677_AZIFS054P001C01-SOCA
M_F_CPU0_SA_DQ<9>        J11              20       SCONN288_ADR50001P013C01-SCONNA
M_F_CPU0_SA_DQ<9>        J12              20       SCONN288_ADR50001P003C01-SCONNA
M_F_CPU0_SA_DQ<9>        U2               DU68     SOCKET4677_AZIFS054P001C01-SOCA
M_F_CPU0_SA_DQ<10>       J11              163      SCONN288_ADR50001P013C01-SCONNA
M_F_CPU0_SA_DQ<10>       J12              163      SCONN288_ADR50001P003C01-SCONNA
M_F_CPU0_SA_DQ<10>       U2               DY69     SOCKET4677_AZIFS054P001C01-SOCA
M_F_CPU0_SA_DQ<11>       J11              165      SCONN288_ADR50001P013C01-SCONNA
M_F_CPU0_SA_DQ<11>       J12              165      SCONN288_ADR50001P003C01-SCONNA
M_F_CPU0_SA_DQ<11>       U2               EA68     SOCKET4677_AZIFS054P001C01-SOCA
M_F_CPU0_SA_DQ<12>       J11              25       SCONN288_ADR50001P013C01-SCONNA
M_F_CPU0_SA_DQ<12>       J12              25       SCONN288_ADR50001P003C01-SCONNA
M_F_CPU0_SA_DQ<12>       U2               DU66     SOCKET4677_AZIFS054P001C01-SOCA
M_F_CPU0_SA_DQ<13>       J11              27       SCONN288_ADR50001P013C01-SCONNA
M_F_CPU0_SA_DQ<13>       J12              27       SCONN288_ADR50001P003C01-SCONNA
M_F_CPU0_SA_DQ<13>       U2               DV65     SOCKET4677_AZIFS054P001C01-SOCA
M_F_CPU0_SA_DQ<14>       J11              170      SCONN288_ADR50001P013C01-SCONNA
M_F_CPU0_SA_DQ<14>       J12              170      SCONN288_ADR50001P003C01-SCONNA
M_F_CPU0_SA_DQ<14>       U2               EA66     SOCKET4677_AZIFS054P001C01-SOCA
M_F_CPU0_SA_DQ<15>       J11              172      SCONN288_ADR50001P013C01-SCONNA
M_F_CPU0_SA_DQ<15>       J12              172      SCONN288_ADR50001P003C01-SCONNA
M_F_CPU0_SA_DQ<15>       U2               DY65     SOCKET4677_AZIFS054P001C01-SOCA
M_F_CPU0_SA_DQ<16>       J11              29       SCONN288_ADR50001P013C01-SCONNA
M_F_CPU0_SA_DQ<16>       J12              29       SCONN288_ADR50001P003C01-SCONNA
M_F_CPU0_SA_DQ<16>       U2               EE66     SOCKET4677_AZIFS054P001C01-SOCA
M_F_CPU0_SA_DQ<17>       J11              31       SCONN288_ADR50001P013C01-SCONNA
M_F_CPU0_SA_DQ<17>       J12              31       SCONN288_ADR50001P003C01-SCONNA
M_F_CPU0_SA_DQ<17>       U2               ED65     SOCKET4677_AZIFS054P001C01-SOCA
M_F_CPU0_SA_DQ<18>       J11              174      SCONN288_ADR50001P013C01-SCONNA
M_F_CPU0_SA_DQ<18>       J12              174      SCONN288_ADR50001P003C01-SCONNA
M_F_CPU0_SA_DQ<18>       U2               EG66     SOCKET4677_AZIFS054P001C01-SOCA
M_F_CPU0_SA_DQ<19>       J11              176      SCONN288_ADR50001P013C01-SCONNA
M_F_CPU0_SA_DQ<19>       J12              176      SCONN288_ADR50001P003C01-SCONNA
M_F_CPU0_SA_DQ<19>       U2               EH65     SOCKET4677_AZIFS054P001C01-SOCA
M_F_CPU0_SA_DQ<20>       J11              36       SCONN288_ADR50001P013C01-SCONNA
M_F_CPU0_SA_DQ<20>       J12              36       SCONN288_ADR50001P003C01-SCONNA
M_F_CPU0_SA_DQ<20>       U2               ED63     SOCKET4677_AZIFS054P001C01-SOCA
M_F_CPU0_SA_DQ<21>       J11              38       SCONN288_ADR50001P013C01-SCONNA
M_F_CPU0_SA_DQ<21>       J12              38       SCONN288_ADR50001P003C01-SCONNA
M_F_CPU0_SA_DQ<21>       U2               EE62     SOCKET4677_AZIFS054P001C01-SOCA
M_F_CPU0_SA_DQ<22>       J11              181      SCONN288_ADR50001P013C01-SCONNA
M_F_CPU0_SA_DQ<22>       J12              181      SCONN288_ADR50001P003C01-SCONNA
M_F_CPU0_SA_DQ<22>       U2               EH63     SOCKET4677_AZIFS054P001C01-SOCA
M_F_CPU0_SA_DQ<23>       J11              183      SCONN288_ADR50001P013C01-SCONNA
M_F_CPU0_SA_DQ<23>       J12              183      SCONN288_ADR50001P003C01-SCONNA
M_F_CPU0_SA_DQ<23>       U2               EG62     SOCKET4677_AZIFS054P001C01-SOCA
M_F_CPU0_SA_DQ<24>       J11              40       SCONN288_ADR50001P013C01-SCONNA
M_F_CPU0_SA_DQ<24>       J12              40       SCONN288_ADR50001P003C01-SCONNA
M_F_CPU0_SA_DQ<24>       U2               DV57     SOCKET4677_AZIFS054P001C01-SOCA
M_F_CPU0_SA_DQ<25>       J11              42       SCONN288_ADR50001P013C01-SCONNA
M_F_CPU0_SA_DQ<25>       J12              42       SCONN288_ADR50001P003C01-SCONNA
M_F_CPU0_SA_DQ<25>       U2               DU56     SOCKET4677_AZIFS054P001C01-SOCA
M_F_CPU0_SA_DQ<26>       J11              185      SCONN288_ADR50001P013C01-SCONNA
M_F_CPU0_SA_DQ<26>       J12              185      SCONN288_ADR50001P003C01-SCONNA
M_F_CPU0_SA_DQ<26>       U2               DY57     SOCKET4677_AZIFS054P001C01-SOCA
M_F_CPU0_SA_DQ<27>       J11              187      SCONN288_ADR50001P013C01-SCONNA
M_F_CPU0_SA_DQ<27>       J12              187      SCONN288_ADR50001P003C01-SCONNA
M_F_CPU0_SA_DQ<27>       U2               EA56     SOCKET4677_AZIFS054P001C01-SOCA
M_F_CPU0_SA_DQ<28>       J11              47       SCONN288_ADR50001P013C01-SCONNA
M_F_CPU0_SA_DQ<28>       J12              47       SCONN288_ADR50001P003C01-SCONNA
M_F_CPU0_SA_DQ<28>       U2               DU54     SOCKET4677_AZIFS054P001C01-SOCA
M_F_CPU0_SA_DQ<29>       J11              49       SCONN288_ADR50001P013C01-SCONNA
M_F_CPU0_SA_DQ<29>       J12              49       SCONN288_ADR50001P003C01-SCONNA
M_F_CPU0_SA_DQ<29>       U2               DV53     SOCKET4677_AZIFS054P001C01-SOCA
M_F_CPU0_SA_DQ<30>       J11              192      SCONN288_ADR50001P013C01-SCONNA
M_F_CPU0_SA_DQ<30>       J12              192      SCONN288_ADR50001P003C01-SCONNA
M_F_CPU0_SA_DQ<30>       U2               EA54     SOCKET4677_AZIFS054P001C01-SOCA
M_F_CPU0_SA_DQ<31>       J11              194      SCONN288_ADR50001P013C01-SCONNA
M_F_CPU0_SA_DQ<31>       J12              194      SCONN288_ADR50001P003C01-SCONNA
M_F_CPU0_SA_DQ<31>       U2               DY53     SOCKET4677_AZIFS054P001C01-SOCA
M_F_CPU0_SA_DQS_DN<0>    J11              12       SCONN288_ADR50001P013C01-SCONNA
M_F_CPU0_SA_DQS_DN<0>    J12              12       SCONN288_ADR50001P003C01-SCONNA
M_F_CPU0_SA_DQS_DN<0>    U2               EE76     SOCKET4677_AZIFS054P001C01-SOCA
M_F_CPU0_SA_DQS_DN<1>    J11              23       SCONN288_ADR50001P013C01-SCONNA
M_F_CPU0_SA_DQS_DN<1>    J12              23       SCONN288_ADR50001P003C01-SCONNA
M_F_CPU0_SA_DQS_DN<1>    U2               DT67     SOCKET4677_AZIFS054P001C01-SOCA
M_F_CPU0_SA_DQS_DN<2>    J11              34       SCONN288_ADR50001P013C01-SCONNA
M_F_CPU0_SA_DQS_DN<2>    J12              34       SCONN288_ADR50001P003C01-SCONNA
M_F_CPU0_SA_DQS_DN<2>    U2               EC64     SOCKET4677_AZIFS054P001C01-SOCA
M_F_CPU0_SA_DQS_DN<3>    J11              45       SCONN288_ADR50001P013C01-SCONNA
M_F_CPU0_SA_DQS_DN<3>    J12              45       SCONN288_ADR50001P003C01-SCONNA
M_F_CPU0_SA_DQS_DN<3>    U2               DV55     SOCKET4677_AZIFS054P001C01-SOCA
M_F_CPU0_SA_DQS_DN<4>    J11              56       SCONN288_ADR50001P013C01-SCONNA
M_F_CPU0_SA_DQS_DN<4>    J12              56       SCONN288_ADR50001P003C01-SCONNA
M_F_CPU0_SA_DQS_DN<4>    U2               EE58     SOCKET4677_AZIFS054P001C01-SOCA
M_F_CPU0_SA_DQS_DN<5>    J11              156      SCONN288_ADR50001P013C01-SCONNA
M_F_CPU0_SA_DQS_DN<5>    J12              156      SCONN288_ADR50001P003C01-SCONNA
M_F_CPU0_SA_DQS_DN<5>    U2               EJ76     SOCKET4677_AZIFS054P001C01-SOCA
M_F_CPU0_SA_DQS_DN<6>    J11              167      SCONN288_ADR50001P013C01-SCONNA
M_F_CPU0_SA_DQS_DN<6>    J12              167      SCONN288_ADR50001P003C01-SCONNA
M_F_CPU0_SA_DQS_DN<6>    U2               EB67     SOCKET4677_AZIFS054P001C01-SOCA
M_F_CPU0_SA_DQS_DN<7>    J11              178      SCONN288_ADR50001P013C01-SCONNA
M_F_CPU0_SA_DQS_DN<7>    J12              178      SCONN288_ADR50001P003C01-SCONNA
M_F_CPU0_SA_DQS_DN<7>    U2               EJ64     SOCKET4677_AZIFS054P001C01-SOCA
M_F_CPU0_SA_DQS_DN<8>    J11              189      SCONN288_ADR50001P013C01-SCONNA
M_F_CPU0_SA_DQS_DN<8>    J12              189      SCONN288_ADR50001P003C01-SCONNA
M_F_CPU0_SA_DQS_DN<8>    U2               EB55     SOCKET4677_AZIFS054P001C01-SOCA
M_F_CPU0_SA_DQS_DN<9>    J11              200      SCONN288_ADR50001P013C01-SCONNA
M_F_CPU0_SA_DQS_DN<9>    J12              200      SCONN288_ADR50001P003C01-SCONNA
M_F_CPU0_SA_DQS_DN<9>    U2               EJ58     SOCKET4677_AZIFS054P001C01-SOCA
M_F_CPU0_SA_DQS_DP<0>    J11              11       SCONN288_ADR50001P013C01-SCONNA
M_F_CPU0_SA_DQS_DP<0>    J12              11       SCONN288_ADR50001P003C01-SCONNA
M_F_CPU0_SA_DQS_DP<0>    U2               EC76     SOCKET4677_AZIFS054P001C01-SOCA
M_F_CPU0_SA_DQS_DP<1>    J11              22       SCONN288_ADR50001P013C01-SCONNA
M_F_CPU0_SA_DQS_DP<1>    J12              22       SCONN288_ADR50001P003C01-SCONNA
M_F_CPU0_SA_DQS_DP<1>    U2               DV67     SOCKET4677_AZIFS054P001C01-SOCA
M_F_CPU0_SA_DQS_DP<2>    J11              33       SCONN288_ADR50001P013C01-SCONNA
M_F_CPU0_SA_DQS_DP<2>    J12              33       SCONN288_ADR50001P003C01-SCONNA
M_F_CPU0_SA_DQS_DP<2>    U2               EE64     SOCKET4677_AZIFS054P001C01-SOCA
M_F_CPU0_SA_DQS_DP<3>    J11              44       SCONN288_ADR50001P013C01-SCONNA
M_F_CPU0_SA_DQS_DP<3>    J12              44       SCONN288_ADR50001P003C01-SCONNA
M_F_CPU0_SA_DQS_DP<3>    U2               DT55     SOCKET4677_AZIFS054P001C01-SOCA
M_F_CPU0_SA_DQS_DP<4>    J11              55       SCONN288_ADR50001P013C01-SCONNA
M_F_CPU0_SA_DQS_DP<4>    J12              55       SCONN288_ADR50001P003C01-SCONNA
M_F_CPU0_SA_DQS_DP<4>    U2               EC58     SOCKET4677_AZIFS054P001C01-SOCA
M_F_CPU0_SA_DQS_DP<5>    J11              157      SCONN288_ADR50001P013C01-SCONNA
M_F_CPU0_SA_DQS_DP<5>    J12              157      SCONN288_ADR50001P003C01-SCONNA
M_F_CPU0_SA_DQS_DP<5>    U2               EG76     SOCKET4677_AZIFS054P001C01-SOCA
M_F_CPU0_SA_DQS_DP<6>    J11              168      SCONN288_ADR50001P013C01-SCONNA
M_F_CPU0_SA_DQS_DP<6>    J12              168      SCONN288_ADR50001P003C01-SCONNA
M_F_CPU0_SA_DQS_DP<6>    U2               DY67     SOCKET4677_AZIFS054P001C01-SOCA
M_F_CPU0_SA_DQS_DP<7>    J11              179      SCONN288_ADR50001P013C01-SCONNA
M_F_CPU0_SA_DQS_DP<7>    J12              179      SCONN288_ADR50001P003C01-SCONNA
M_F_CPU0_SA_DQS_DP<7>    U2               EG64     SOCKET4677_AZIFS054P001C01-SOCA
M_F_CPU0_SA_DQS_DP<8>    J11              190      SCONN288_ADR50001P013C01-SCONNA
M_F_CPU0_SA_DQS_DP<8>    J12              190      SCONN288_ADR50001P003C01-SCONNA
M_F_CPU0_SA_DQS_DP<8>    U2               DY55     SOCKET4677_AZIFS054P001C01-SOCA
M_F_CPU0_SA_DQS_DP<9>    J11              201      SCONN288_ADR50001P013C01-SCONNA
M_F_CPU0_SA_DQS_DP<9>    J12              201      SCONN288_ADR50001P003C01-SCONNA
M_F_CPU0_SA_DQS_DP<9>    U2               EG58     SOCKET4677_AZIFS054P001C01-SOCA
M_F_CPU0_SA_PAR          J11              74       SCONN288_ADR50001P013C01-SCONNA
M_F_CPU0_SA_PAR          J12              74       SCONN288_ADR50001P003C01-SCONNA
M_F_CPU0_SA_PAR          U2               EA50     SOCKET4677_AZIFS054P001C01-SOCA
M_F_CPU0_SA_RSP<0>       J11              86       SCONN288_ADR50001P013C01-SCONNA
M_F_CPU0_SA_RSP<0>       U2               DN48     SOCKET4677_AZIFS054P001C01-SOCA
M_F_CPU0_SA_RSP<1>       J12              86       SCONN288_ADR50001P003C01-SCONNA
M_F_CPU0_SA_RSP<1>       U2               DP47     SOCKET4677_AZIFS054P001C01-SOCA
M_F_CPU0_SB_CA<0>        J11              76       SCONN288_ADR50001P013C01-SCONNA
M_F_CPU0_SB_CA<0>        J12              76       SCONN288_ADR50001P003C01-SCONNA
M_F_CPU0_SB_CA<0>        U2               DV51     SOCKET4677_AZIFS054P001C01-SOCA
M_F_CPU0_SB_CA<1>        J11              221      SCONN288_ADR50001P013C01-SCONNA
M_F_CPU0_SB_CA<1>        J12              221      SCONN288_ADR50001P003C01-SCONNA
M_F_CPU0_SB_CA<1>        U2               DU50     SOCKET4677_AZIFS054P001C01-SOCA
M_F_CPU0_SB_CA<2>        J11              78       SCONN288_ADR50001P013C01-SCONNA
M_F_CPU0_SB_CA<2>        J12              78       SCONN288_ADR50001P003C01-SCONNA
M_F_CPU0_SB_CA<2>        U2               EE41     SOCKET4677_AZIFS054P001C01-SOCA
M_F_CPU0_SB_CA<3>        J11              223      SCONN288_ADR50001P013C01-SCONNA
M_F_CPU0_SB_CA<3>        J12              223      SCONN288_ADR50001P003C01-SCONNA
M_F_CPU0_SB_CA<3>        U2               EG41     SOCKET4677_AZIFS054P001C01-SOCA
M_F_CPU0_SB_CA<4>        J11              80       SCONN288_ADR50001P013C01-SCONNA
M_F_CPU0_SB_CA<4>        J12              80       SCONN288_ADR50001P003C01-SCONNA
M_F_CPU0_SB_CA<4>        U2               ED40     SOCKET4677_AZIFS054P001C01-SOCA
M_F_CPU0_SB_CA<5>        J11              225      SCONN288_ADR50001P013C01-SCONNA
M_F_CPU0_SB_CA<5>        J12              225      SCONN288_ADR50001P003C01-SCONNA
M_F_CPU0_SB_CA<5>        U2               EH40     SOCKET4677_AZIFS054P001C01-SOCA
M_F_CPU0_SB_CA<6>        J11              82       SCONN288_ADR50001P013C01-SCONNA
M_F_CPU0_SB_CA<6>        J12              82       SCONN288_ADR50001P003C01-SCONNA
M_F_CPU0_SB_CA<6>        U2               EC39     SOCKET4677_AZIFS054P001C01-SOCA
M_F_CPU0_SB_CB<0>        J11              96       SCONN288_ADR50001P013C01-SCONNA
M_F_CPU0_SB_CB<0>        J12              96       SCONN288_ADR50001P003C01-SCONNA
M_F_CPU0_SB_CB<0>        U2               ED32     SOCKET4677_AZIFS054P001C01-SOCA
M_F_CPU0_SB_CB<1>        J11              98       SCONN288_ADR50001P013C01-SCONNA
M_F_CPU0_SB_CB<1>        J12              98       SCONN288_ADR50001P003C01-SCONNA
M_F_CPU0_SB_CB<1>        U2               EE31     SOCKET4677_AZIFS054P001C01-SOCA
M_F_CPU0_SB_CB<2>        J11              241      SCONN288_ADR50001P013C01-SCONNA
M_F_CPU0_SB_CB<2>        J12              241      SCONN288_ADR50001P003C01-SCONNA
M_F_CPU0_SB_CB<2>        U2               EH32     SOCKET4677_AZIFS054P001C01-SOCA
M_F_CPU0_SB_CB<3>        J11              243      SCONN288_ADR50001P013C01-SCONNA
M_F_CPU0_SB_CB<3>        J12              243      SCONN288_ADR50001P003C01-SCONNA
M_F_CPU0_SB_CB<3>        U2               EG31     SOCKET4677_AZIFS054P001C01-SOCA
M_F_CPU0_SB_CB<4>        J11              89       SCONN288_ADR50001P013C01-SCONNA
M_F_CPU0_SB_CB<4>        J12              89       SCONN288_ADR50001P003C01-SCONNA
M_F_CPU0_SB_CB<4>        U2               EE35     SOCKET4677_AZIFS054P001C01-SOCA
M_F_CPU0_SB_CB<5>        J11              91       SCONN288_ADR50001P013C01-SCONNA
M_F_CPU0_SB_CB<5>        J12              91       SCONN288_ADR50001P003C01-SCONNA
M_F_CPU0_SB_CB<5>        U2               ED34     SOCKET4677_AZIFS054P001C01-SOCA
M_F_CPU0_SB_CB<6>        J11              234      SCONN288_ADR50001P013C01-SCONNA
M_F_CPU0_SB_CB<6>        J12              234      SCONN288_ADR50001P003C01-SCONNA
M_F_CPU0_SB_CB<6>        U2               EG35     SOCKET4677_AZIFS054P001C01-SOCA
M_F_CPU0_SB_CB<7>        J11              236      SCONN288_ADR50001P013C01-SCONNA
M_F_CPU0_SB_CB<7>        J12              236      SCONN288_ADR50001P003C01-SCONNA
M_F_CPU0_SB_CB<7>        U2               EH34     SOCKET4677_AZIFS054P001C01-SOCA
M_F_CPU0_SB_CS_N<0>      J11              84       SCONN288_ADR50001P013C01-SCONNA
M_F_CPU0_SB_CS_N<0>      U2               EH38     SOCKET4677_AZIFS054P001C01-SOCA
M_F_CPU0_SB_CS_N<1>      J11              229      SCONN288_ADR50001P013C01-SCONNA
M_F_CPU0_SB_CS_N<1>      U2               EG37     SOCKET4677_AZIFS054P001C01-SOCA
M_F_CPU0_SB_CS_N<2>      J12              84       SCONN288_ADR50001P003C01-SCONNA
M_F_CPU0_SB_CS_N<2>      U2               ED38     SOCKET4677_AZIFS054P001C01-SOCA
M_F_CPU0_SB_CS_N<3>      J12              229      SCONN288_ADR50001P003C01-SCONNA
M_F_CPU0_SB_CS_N<3>      U2               EE37     SOCKET4677_AZIFS054P001C01-SOCA
M_F_CPU0_SB_DQ<0>        J11              100      SCONN288_ADR50001P013C01-SCONNA
M_F_CPU0_SB_DQ<0>        J12              100      SCONN288_ADR50001P003C01-SCONNA
M_F_CPU0_SB_DQ<0>        U2               DV32     SOCKET4677_AZIFS054P001C01-SOCA
M_F_CPU0_SB_DQ<1>        J11              102      SCONN288_ADR50001P013C01-SCONNA
M_F_CPU0_SB_DQ<1>        J12              102      SCONN288_ADR50001P003C01-SCONNA
M_F_CPU0_SB_DQ<1>        U2               DU31     SOCKET4677_AZIFS054P001C01-SOCA
M_F_CPU0_SB_DQ<2>        J11              245      SCONN288_ADR50001P013C01-SCONNA
M_F_CPU0_SB_DQ<2>        J12              245      SCONN288_ADR50001P003C01-SCONNA
M_F_CPU0_SB_DQ<2>        U2               DY32     SOCKET4677_AZIFS054P001C01-SOCA
M_F_CPU0_SB_DQ<3>        J11              247      SCONN288_ADR50001P013C01-SCONNA
M_F_CPU0_SB_DQ<3>        J12              247      SCONN288_ADR50001P003C01-SCONNA
M_F_CPU0_SB_DQ<3>        U2               EA31     SOCKET4677_AZIFS054P001C01-SOCA
M_F_CPU0_SB_DQ<4>        J11              107      SCONN288_ADR50001P013C01-SCONNA
M_F_CPU0_SB_DQ<4>        J12              107      SCONN288_ADR50001P003C01-SCONNA
M_F_CPU0_SB_DQ<4>        U2               DU29     SOCKET4677_AZIFS054P001C01-SOCA
M_F_CPU0_SB_DQ<5>        J11              109      SCONN288_ADR50001P013C01-SCONNA
M_F_CPU0_SB_DQ<5>        J12              109      SCONN288_ADR50001P003C01-SCONNA
M_F_CPU0_SB_DQ<5>        U2               DV28     SOCKET4677_AZIFS054P001C01-SOCA
M_F_CPU0_SB_DQ<6>        J11              252      SCONN288_ADR50001P013C01-SCONNA
M_F_CPU0_SB_DQ<6>        J12              252      SCONN288_ADR50001P003C01-SCONNA
M_F_CPU0_SB_DQ<6>        U2               EA29     SOCKET4677_AZIFS054P001C01-SOCA
M_F_CPU0_SB_DQ<7>        J11              254      SCONN288_ADR50001P013C01-SCONNA
M_F_CPU0_SB_DQ<7>        J12              254      SCONN288_ADR50001P003C01-SCONNA
M_F_CPU0_SB_DQ<7>        U2               DY28     SOCKET4677_AZIFS054P001C01-SOCA
M_F_CPU0_SB_DQ<8>        J11              111      SCONN288_ADR50001P013C01-SCONNA
M_F_CPU0_SB_DQ<8>        J12              111      SCONN288_ADR50001P003C01-SCONNA
M_F_CPU0_SB_DQ<8>        U2               EE23     SOCKET4677_AZIFS054P001C01-SOCA
M_F_CPU0_SB_DQ<9>        J11              113      SCONN288_ADR50001P013C01-SCONNA
M_F_CPU0_SB_DQ<9>        J12              113      SCONN288_ADR50001P003C01-SCONNA
M_F_CPU0_SB_DQ<9>        U2               ED22     SOCKET4677_AZIFS054P001C01-SOCA
M_F_CPU0_SB_DQ<10>       J11              256      SCONN288_ADR50001P013C01-SCONNA
M_F_CPU0_SB_DQ<10>       J12              256      SCONN288_ADR50001P003C01-SCONNA
M_F_CPU0_SB_DQ<10>       U2               EG23     SOCKET4677_AZIFS054P001C01-SOCA
M_F_CPU0_SB_DQ<11>       J11              258      SCONN288_ADR50001P013C01-SCONNA
M_F_CPU0_SB_DQ<11>       J12              258      SCONN288_ADR50001P003C01-SCONNA
M_F_CPU0_SB_DQ<11>       U2               EH22     SOCKET4677_AZIFS054P001C01-SOCA
M_F_CPU0_SB_DQ<12>       J11              118      SCONN288_ADR50001P013C01-SCONNA
M_F_CPU0_SB_DQ<12>       J12              118      SCONN288_ADR50001P003C01-SCONNA
M_F_CPU0_SB_DQ<12>       U2               ED20     SOCKET4677_AZIFS054P001C01-SOCA
M_F_CPU0_SB_DQ<13>       J11              120      SCONN288_ADR50001P013C01-SCONNA
M_F_CPU0_SB_DQ<13>       J12              120      SCONN288_ADR50001P003C01-SCONNA
M_F_CPU0_SB_DQ<13>       U2               EE19     SOCKET4677_AZIFS054P001C01-SOCA
M_F_CPU0_SB_DQ<14>       J11              263      SCONN288_ADR50001P013C01-SCONNA
M_F_CPU0_SB_DQ<14>       J12              263      SCONN288_ADR50001P003C01-SCONNA
M_F_CPU0_SB_DQ<14>       U2               EH20     SOCKET4677_AZIFS054P001C01-SOCA
M_F_CPU0_SB_DQ<15>       J11              265      SCONN288_ADR50001P013C01-SCONNA
M_F_CPU0_SB_DQ<15>       J12              265      SCONN288_ADR50001P003C01-SCONNA
M_F_CPU0_SB_DQ<15>       U2               EG19     SOCKET4677_AZIFS054P001C01-SOCA
M_F_CPU0_SB_DQ<16>       J11              122      SCONN288_ADR50001P013C01-SCONNA
M_F_CPU0_SB_DQ<16>       J12              122      SCONN288_ADR50001P003C01-SCONNA
M_F_CPU0_SB_DQ<16>       U2               EM14     SOCKET4677_AZIFS054P001C01-SOCA
M_F_CPU0_SB_DQ<17>       J11              124      SCONN288_ADR50001P013C01-SCONNA
M_F_CPU0_SB_DQ<17>       J12              124      SCONN288_ADR50001P003C01-SCONNA
M_F_CPU0_SB_DQ<17>       U2               EL13     SOCKET4677_AZIFS054P001C01-SOCA
M_F_CPU0_SB_DQ<18>       J11              267      SCONN288_ADR50001P013C01-SCONNA
M_F_CPU0_SB_DQ<18>       J12              267      SCONN288_ADR50001P003C01-SCONNA
M_F_CPU0_SB_DQ<18>       U2               EP14     SOCKET4677_AZIFS054P001C01-SOCA
M_F_CPU0_SB_DQ<19>       J11              269      SCONN288_ADR50001P013C01-SCONNA
M_F_CPU0_SB_DQ<19>       J12              269      SCONN288_ADR50001P003C01-SCONNA
M_F_CPU0_SB_DQ<19>       U2               ER13     SOCKET4677_AZIFS054P001C01-SOCA
M_F_CPU0_SB_DQ<20>       J11              129      SCONN288_ADR50001P013C01-SCONNA
M_F_CPU0_SB_DQ<20>       J12              129      SCONN288_ADR50001P003C01-SCONNA
M_F_CPU0_SB_DQ<20>       U2               EL11     SOCKET4677_AZIFS054P001C01-SOCA
M_F_CPU0_SB_DQ<21>       J11              131      SCONN288_ADR50001P013C01-SCONNA
M_F_CPU0_SB_DQ<21>       J12              131      SCONN288_ADR50001P003C01-SCONNA
M_F_CPU0_SB_DQ<21>       U2               EM10     SOCKET4677_AZIFS054P001C01-SOCA
M_F_CPU0_SB_DQ<22>       J11              274      SCONN288_ADR50001P013C01-SCONNA
M_F_CPU0_SB_DQ<22>       J12              274      SCONN288_ADR50001P003C01-SCONNA
M_F_CPU0_SB_DQ<22>       U2               ER11     SOCKET4677_AZIFS054P001C01-SOCA
M_F_CPU0_SB_DQ<23>       J11              276      SCONN288_ADR50001P013C01-SCONNA
M_F_CPU0_SB_DQ<23>       J12              276      SCONN288_ADR50001P003C01-SCONNA
M_F_CPU0_SB_DQ<23>       U2               EP10     SOCKET4677_AZIFS054P001C01-SOCA
M_F_CPU0_SB_DQ<24>       J11              133      SCONN288_ADR50001P013C01-SCONNA
M_F_CPU0_SB_DQ<24>       J12              133      SCONN288_ADR50001P003C01-SCONNA
M_F_CPU0_SB_DQ<24>       U2               DV20     SOCKET4677_AZIFS054P001C01-SOCA
M_F_CPU0_SB_DQ<25>       J11              135      SCONN288_ADR50001P013C01-SCONNA
M_F_CPU0_SB_DQ<25>       J12              135      SCONN288_ADR50001P003C01-SCONNA
M_F_CPU0_SB_DQ<25>       U2               DU19     SOCKET4677_AZIFS054P001C01-SOCA
M_F_CPU0_SB_DQ<26>       J11              278      SCONN288_ADR50001P013C01-SCONNA
M_F_CPU0_SB_DQ<26>       J12              278      SCONN288_ADR50001P003C01-SCONNA
M_F_CPU0_SB_DQ<26>       U2               DY20     SOCKET4677_AZIFS054P001C01-SOCA
M_F_CPU0_SB_DQ<27>       J11              280      SCONN288_ADR50001P013C01-SCONNA
M_F_CPU0_SB_DQ<27>       J12              280      SCONN288_ADR50001P003C01-SCONNA
M_F_CPU0_SB_DQ<27>       U2               EA19     SOCKET4677_AZIFS054P001C01-SOCA
M_F_CPU0_SB_DQ<28>       J11              140      SCONN288_ADR50001P013C01-SCONNA
M_F_CPU0_SB_DQ<28>       J12              140      SCONN288_ADR50001P003C01-SCONNA
M_F_CPU0_SB_DQ<28>       U2               EA17     SOCKET4677_AZIFS054P001C01-SOCA
M_F_CPU0_SB_DQ<29>       J11              142      SCONN288_ADR50001P013C01-SCONNA
M_F_CPU0_SB_DQ<29>       J12              142      SCONN288_ADR50001P003C01-SCONNA
M_F_CPU0_SB_DQ<29>       U2               DU17     SOCKET4677_AZIFS054P001C01-SOCA
M_F_CPU0_SB_DQ<30>       J11              285      SCONN288_ADR50001P013C01-SCONNA
M_F_CPU0_SB_DQ<30>       J12              285      SCONN288_ADR50001P003C01-SCONNA
M_F_CPU0_SB_DQ<30>       U2               EC17     SOCKET4677_AZIFS054P001C01-SOCA
M_F_CPU0_SB_DQ<31>       J11              287      SCONN288_ADR50001P013C01-SCONNA
M_F_CPU0_SB_DQ<31>       J12              287      SCONN288_ADR50001P003C01-SCONNA
M_F_CPU0_SB_DQ<31>       U2               DR17     SOCKET4677_AZIFS054P001C01-SOCA
M_F_CPU0_SB_DQS_DN<0>    J11              105      SCONN288_ADR50001P013C01-SCONNA
M_F_CPU0_SB_DQS_DN<0>    J12              105      SCONN288_ADR50001P003C01-SCONNA
M_F_CPU0_SB_DQS_DN<0>    U2               DV30     SOCKET4677_AZIFS054P001C01-SOCA
M_F_CPU0_SB_DQS_DN<1>    J11              116      SCONN288_ADR50001P013C01-SCONNA
M_F_CPU0_SB_DQS_DN<1>    J12              116      SCONN288_ADR50001P003C01-SCONNA
M_F_CPU0_SB_DQS_DN<1>    U2               EE21     SOCKET4677_AZIFS054P001C01-SOCA
M_F_CPU0_SB_DQS_DN<2>    J11              127      SCONN288_ADR50001P013C01-SCONNA
M_F_CPU0_SB_DQS_DN<2>    J12              127      SCONN288_ADR50001P003C01-SCONNA
M_F_CPU0_SB_DQS_DN<2>    U2               EM12     SOCKET4677_AZIFS054P001C01-SOCA
M_F_CPU0_SB_DQS_DN<3>    J11              138      SCONN288_ADR50001P013C01-SCONNA
M_F_CPU0_SB_DQS_DN<3>    J12              138      SCONN288_ADR50001P003C01-SCONNA
M_F_CPU0_SB_DQS_DN<3>    U2               DT18     SOCKET4677_AZIFS054P001C01-SOCA
M_F_CPU0_SB_DQS_DN<4>    J11              238      SCONN288_ADR50001P013C01-SCONNA
M_F_CPU0_SB_DQS_DN<4>    J12              238      SCONN288_ADR50001P003C01-SCONNA
M_F_CPU0_SB_DQS_DN<4>    U2               EJ33     SOCKET4677_AZIFS054P001C01-SOCA
M_F_CPU0_SB_DQS_DN<5>    J11              249      SCONN288_ADR50001P013C01-SCONNA
M_F_CPU0_SB_DQS_DN<5>    J12              249      SCONN288_ADR50001P003C01-SCONNA
M_F_CPU0_SB_DQS_DN<5>    U2               EB30     SOCKET4677_AZIFS054P001C01-SOCA
M_F_CPU0_SB_DQS_DN<6>    J11              260      SCONN288_ADR50001P013C01-SCONNA
M_F_CPU0_SB_DQS_DN<6>    J12              260      SCONN288_ADR50001P003C01-SCONNA
M_F_CPU0_SB_DQS_DN<6>    U2               EJ21     SOCKET4677_AZIFS054P001C01-SOCA
M_F_CPU0_SB_DQS_DN<7>    J11              271      SCONN288_ADR50001P013C01-SCONNA
M_F_CPU0_SB_DQS_DN<7>    J12              271      SCONN288_ADR50001P003C01-SCONNA
M_F_CPU0_SB_DQS_DN<7>    U2               ET12     SOCKET4677_AZIFS054P001C01-SOCA
M_F_CPU0_SB_DQS_DN<8>    J11              282      SCONN288_ADR50001P013C01-SCONNA
M_F_CPU0_SB_DQS_DN<8>    J12              282      SCONN288_ADR50001P003C01-SCONNA
M_F_CPU0_SB_DQS_DN<8>    U2               DY18     SOCKET4677_AZIFS054P001C01-SOCA
M_F_CPU0_SB_DQS_DN<9>    J11              94       SCONN288_ADR50001P013C01-SCONNA
M_F_CPU0_SB_DQS_DN<9>    J12              94       SCONN288_ADR50001P003C01-SCONNA
M_F_CPU0_SB_DQS_DN<9>    U2               EE33     SOCKET4677_AZIFS054P001C01-SOCA
M_F_CPU0_SB_DQS_DP<0>    J11              104      SCONN288_ADR50001P013C01-SCONNA
M_F_CPU0_SB_DQS_DP<0>    J12              104      SCONN288_ADR50001P003C01-SCONNA
M_F_CPU0_SB_DQS_DP<0>    U2               DT30     SOCKET4677_AZIFS054P001C01-SOCA
M_F_CPU0_SB_DQS_DP<1>    J11              115      SCONN288_ADR50001P013C01-SCONNA
M_F_CPU0_SB_DQS_DP<1>    J12              115      SCONN288_ADR50001P003C01-SCONNA
M_F_CPU0_SB_DQS_DP<1>    U2               EC21     SOCKET4677_AZIFS054P001C01-SOCA
M_F_CPU0_SB_DQS_DP<2>    J11              126      SCONN288_ADR50001P013C01-SCONNA
M_F_CPU0_SB_DQS_DP<2>    J12              126      SCONN288_ADR50001P003C01-SCONNA
M_F_CPU0_SB_DQS_DP<2>    U2               EK12     SOCKET4677_AZIFS054P001C01-SOCA
M_F_CPU0_SB_DQS_DP<3>    J11              137      SCONN288_ADR50001P013C01-SCONNA
M_F_CPU0_SB_DQS_DP<3>    J12              137      SCONN288_ADR50001P003C01-SCONNA
M_F_CPU0_SB_DQS_DP<3>    U2               DV18     SOCKET4677_AZIFS054P001C01-SOCA
M_F_CPU0_SB_DQS_DP<4>    J11              239      SCONN288_ADR50001P013C01-SCONNA
M_F_CPU0_SB_DQS_DP<4>    J12              239      SCONN288_ADR50001P003C01-SCONNA
M_F_CPU0_SB_DQS_DP<4>    U2               EG33     SOCKET4677_AZIFS054P001C01-SOCA
M_F_CPU0_SB_DQS_DP<5>    J11              250      SCONN288_ADR50001P013C01-SCONNA
M_F_CPU0_SB_DQS_DP<5>    J12              250      SCONN288_ADR50001P003C01-SCONNA
M_F_CPU0_SB_DQS_DP<5>    U2               DY30     SOCKET4677_AZIFS054P001C01-SOCA
M_F_CPU0_SB_DQS_DP<6>    J11              261      SCONN288_ADR50001P013C01-SCONNA
M_F_CPU0_SB_DQS_DP<6>    J12              261      SCONN288_ADR50001P003C01-SCONNA
M_F_CPU0_SB_DQS_DP<6>    U2               EG21     SOCKET4677_AZIFS054P001C01-SOCA
M_F_CPU0_SB_DQS_DP<7>    J11              272      SCONN288_ADR50001P013C01-SCONNA
M_F_CPU0_SB_DQS_DP<7>    J12              272      SCONN288_ADR50001P003C01-SCONNA
M_F_CPU0_SB_DQS_DP<7>    U2               EP12     SOCKET4677_AZIFS054P001C01-SOCA
M_F_CPU0_SB_DQS_DP<8>    J11              283      SCONN288_ADR50001P013C01-SCONNA
M_F_CPU0_SB_DQS_DP<8>    J12              283      SCONN288_ADR50001P003C01-SCONNA
M_F_CPU0_SB_DQS_DP<8>    U2               EB18     SOCKET4677_AZIFS054P001C01-SOCA
M_F_CPU0_SB_DQS_DP<9>    J11              93       SCONN288_ADR50001P013C01-SCONNA
M_F_CPU0_SB_DQS_DP<9>    J12              93       SCONN288_ADR50001P003C01-SCONNA
M_F_CPU0_SB_DQS_DP<9>    U2               EC33     SOCKET4677_AZIFS054P001C01-SOCA
M_F_CPU0_SB_PAR          J11              227      SCONN288_ADR50001P013C01-SCONNA
M_F_CPU0_SB_PAR          J12              227      SCONN288_ADR50001P003C01-SCONNA
M_F_CPU0_SB_PAR          U2               EJ39     SOCKET4677_AZIFS054P001C01-SOCA
M_F_CPU0_SB_RSP<0>       J11              87       SCONN288_ADR50001P013C01-SCONNA
M_F_CPU0_SB_RSP<0>       U2               DL48     SOCKET4677_AZIFS054P001C01-SOCA
M_F_CPU0_SB_RSP<1>       J12              87       SCONN288_ADR50001P003C01-SCONNA
M_F_CPU0_SB_RSP<1>       U2               DK47     SOCKET4677_AZIFS054P001C01-SOCA
M_F_CPU1_ALERT_N         J27              62       SCONN288_ADR50001P013C01-SCONNA
M_F_CPU1_ALERT_N         J28              62       SCONN288_ADR50001P003C01-SCONNA
M_F_CPU1_ALERT_N         U1               CW48     SOCKET4677_AZIFS054P001C01-SOCA
M_F_CPU1_CLK_DN<0>       J27              218      SCONN288_ADR50001P013C01-SCONNA
M_F_CPU1_CLK_DN<0>       U1               DY49     SOCKET4677_AZIFS054P001C01-SOCA
M_F_CPU1_CLK_DN<1>       J28              218      SCONN288_ADR50001P003C01-SCONNA
M_F_CPU1_CLK_DN<1>       U1               DV49     SOCKET4677_AZIFS054P001C01-SOCA
M_F_CPU1_CLK_DP<0>       J27              217      SCONN288_ADR50001P013C01-SCONNA
M_F_CPU1_CLK_DP<0>       U1               EB49     SOCKET4677_AZIFS054P001C01-SOCA
M_F_CPU1_CLK_DP<1>       J28              217      SCONN288_ADR50001P003C01-SCONNA
M_F_CPU1_CLK_DP<1>       U1               DT49     SOCKET4677_AZIFS054P001C01-SOCA
M_F_CPU1_SA_CA<0>        J27              66       SCONN288_ADR50001P013C01-SCONNA
M_F_CPU1_SA_CA<0>        J28              66       SCONN288_ADR50001P003C01-SCONNA
M_F_CPU1_SA_CA<0>        U1               EC52     SOCKET4677_AZIFS054P001C01-SOCA
M_F_CPU1_SA_CA<1>        J27              211      SCONN288_ADR50001P013C01-SCONNA
M_F_CPU1_SA_CA<1>        J28              211      SCONN288_ADR50001P003C01-SCONNA
M_F_CPU1_SA_CA<1>        U1               EJ52     SOCKET4677_AZIFS054P001C01-SOCA
M_F_CPU1_SA_CA<2>        J27              68       SCONN288_ADR50001P013C01-SCONNA
M_F_CPU1_SA_CA<2>        J28              68       SCONN288_ADR50001P003C01-SCONNA
M_F_CPU1_SA_CA<2>        U1               ED51     SOCKET4677_AZIFS054P001C01-SOCA
M_F_CPU1_SA_CA<3>        J27              213      SCONN288_ADR50001P013C01-SCONNA
M_F_CPU1_SA_CA<3>        J28              213      SCONN288_ADR50001P003C01-SCONNA
M_F_CPU1_SA_CA<3>        U1               EH51     SOCKET4677_AZIFS054P001C01-SOCA
M_F_CPU1_SA_CA<4>        J27              70       SCONN288_ADR50001P013C01-SCONNA
M_F_CPU1_SA_CA<4>        J28              70       SCONN288_ADR50001P003C01-SCONNA
M_F_CPU1_SA_CA<4>        U1               EE50     SOCKET4677_AZIFS054P001C01-SOCA
M_F_CPU1_SA_CA<5>        J27              215      SCONN288_ADR50001P013C01-SCONNA
M_F_CPU1_SA_CA<5>        J28              215      SCONN288_ADR50001P003C01-SCONNA
M_F_CPU1_SA_CA<5>        U1               EG50     SOCKET4677_AZIFS054P001C01-SOCA
M_F_CPU1_SA_CA<6>        J27              72       SCONN288_ADR50001P013C01-SCONNA
M_F_CPU1_SA_CA<6>        J28              72       SCONN288_ADR50001P003C01-SCONNA
M_F_CPU1_SA_CA<6>        U1               DY51     SOCKET4677_AZIFS054P001C01-SOCA
M_F_CPU1_SA_CB<0>        J27              51       SCONN288_ADR50001P013C01-SCONNA
M_F_CPU1_SA_CB<0>        J28              51       SCONN288_ADR50001P003C01-SCONNA
M_F_CPU1_SA_CB<0>        U1               EE60     SOCKET4677_AZIFS054P001C01-SOCA
M_F_CPU1_SA_CB<1>        J27              53       SCONN288_ADR50001P013C01-SCONNA
M_F_CPU1_SA_CB<1>        J28              53       SCONN288_ADR50001P003C01-SCONNA
M_F_CPU1_SA_CB<1>        U1               ED59     SOCKET4677_AZIFS054P001C01-SOCA
M_F_CPU1_SA_CB<2>        J27              196      SCONN288_ADR50001P013C01-SCONNA
M_F_CPU1_SA_CB<2>        J28              196      SCONN288_ADR50001P003C01-SCONNA
M_F_CPU1_SA_CB<2>        U1               EG60     SOCKET4677_AZIFS054P001C01-SOCA
M_F_CPU1_SA_CB<3>        J27              198      SCONN288_ADR50001P013C01-SCONNA
M_F_CPU1_SA_CB<3>        J28              198      SCONN288_ADR50001P003C01-SCONNA
M_F_CPU1_SA_CB<3>        U1               EH59     SOCKET4677_AZIFS054P001C01-SOCA
M_F_CPU1_SA_CB<4>        J27              58       SCONN288_ADR50001P013C01-SCONNA
M_F_CPU1_SA_CB<4>        J28              58       SCONN288_ADR50001P003C01-SCONNA
M_F_CPU1_SA_CB<4>        U1               ED57     SOCKET4677_AZIFS054P001C01-SOCA
M_F_CPU1_SA_CB<5>        J27              60       SCONN288_ADR50001P013C01-SCONNA
M_F_CPU1_SA_CB<5>        J28              60       SCONN288_ADR50001P003C01-SCONNA
M_F_CPU1_SA_CB<5>        U1               EE56     SOCKET4677_AZIFS054P001C01-SOCA
M_F_CPU1_SA_CB<6>        J27              203      SCONN288_ADR50001P013C01-SCONNA
M_F_CPU1_SA_CB<6>        J28              203      SCONN288_ADR50001P003C01-SCONNA
M_F_CPU1_SA_CB<6>        U1               EH57     SOCKET4677_AZIFS054P001C01-SOCA
M_F_CPU1_SA_CB<7>        J27              205      SCONN288_ADR50001P013C01-SCONNA
M_F_CPU1_SA_CB<7>        J28              205      SCONN288_ADR50001P003C01-SCONNA
M_F_CPU1_SA_CB<7>        U1               EG56     SOCKET4677_AZIFS054P001C01-SOCA
M_F_CPU1_SA_CS_N<0>      J27              64       SCONN288_ADR50001P013C01-SCONNA
M_F_CPU1_SA_CS_N<0>      U1               EG54     SOCKET4677_AZIFS054P001C01-SOCA
M_F_CPU1_SA_CS_N<1>      J27              209      SCONN288_ADR50001P013C01-SCONNA
M_F_CPU1_SA_CS_N<1>      U1               EH53     SOCKET4677_AZIFS054P001C01-SOCA
M_F_CPU1_SA_CS_N<2>      J28              64       SCONN288_ADR50001P003C01-SCONNA
M_F_CPU1_SA_CS_N<2>      U1               EE54     SOCKET4677_AZIFS054P001C01-SOCA
M_F_CPU1_SA_CS_N<3>      J28              209      SCONN288_ADR50001P003C01-SCONNA
M_F_CPU1_SA_CS_N<3>      U1               ED53     SOCKET4677_AZIFS054P001C01-SOCA
M_F_CPU1_SA_DQ<0>        J27              7        SCONN288_ADR50001P013C01-SCONNA
M_F_CPU1_SA_DQ<0>        J28              7        SCONN288_ADR50001P003C01-SCONNA
M_F_CPU1_SA_DQ<0>        U1               EB77     SOCKET4677_AZIFS054P001C01-SOCA
M_F_CPU1_SA_DQ<1>        J27              9        SCONN288_ADR50001P013C01-SCONNA
M_F_CPU1_SA_DQ<1>        J28              9        SCONN288_ADR50001P003C01-SCONNA
M_F_CPU1_SA_DQ<1>        U1               EH77     SOCKET4677_AZIFS054P001C01-SOCA
M_F_CPU1_SA_DQ<2>        J27              152      SCONN288_ADR50001P013C01-SCONNA
M_F_CPU1_SA_DQ<2>        J28              152      SCONN288_ADR50001P003C01-SCONNA
M_F_CPU1_SA_DQ<2>        U1               ED77     SOCKET4677_AZIFS054P001C01-SOCA
M_F_CPU1_SA_DQ<3>        J27              154      SCONN288_ADR50001P013C01-SCONNA
M_F_CPU1_SA_DQ<3>        J28              154      SCONN288_ADR50001P003C01-SCONNA
M_F_CPU1_SA_DQ<3>        U1               EG78     SOCKET4677_AZIFS054P001C01-SOCA
M_F_CPU1_SA_DQ<4>        J27              14       SCONN288_ADR50001P013C01-SCONNA
M_F_CPU1_SA_DQ<4>        J28              14       SCONN288_ADR50001P003C01-SCONNA
M_F_CPU1_SA_DQ<4>        U1               ED75     SOCKET4677_AZIFS054P001C01-SOCA
M_F_CPU1_SA_DQ<5>        J27              16       SCONN288_ADR50001P013C01-SCONNA
M_F_CPU1_SA_DQ<5>        J28              16       SCONN288_ADR50001P003C01-SCONNA
M_F_CPU1_SA_DQ<5>        U1               EE74     SOCKET4677_AZIFS054P001C01-SOCA
M_F_CPU1_SA_DQ<6>        J27              159      SCONN288_ADR50001P013C01-SCONNA
M_F_CPU1_SA_DQ<6>        J28              159      SCONN288_ADR50001P003C01-SCONNA
M_F_CPU1_SA_DQ<6>        U1               EH75     SOCKET4677_AZIFS054P001C01-SOCA
M_F_CPU1_SA_DQ<7>        J27              161      SCONN288_ADR50001P013C01-SCONNA
M_F_CPU1_SA_DQ<7>        J28              161      SCONN288_ADR50001P003C01-SCONNA
M_F_CPU1_SA_DQ<7>        U1               EG74     SOCKET4677_AZIFS054P001C01-SOCA
M_F_CPU1_SA_DQ<8>        J27              18       SCONN288_ADR50001P013C01-SCONNA
M_F_CPU1_SA_DQ<8>        J28              18       SCONN288_ADR50001P003C01-SCONNA
M_F_CPU1_SA_DQ<8>        U1               DV69     SOCKET4677_AZIFS054P001C01-SOCA
M_F_CPU1_SA_DQ<9>        J27              20       SCONN288_ADR50001P013C01-SCONNA
M_F_CPU1_SA_DQ<9>        J28              20       SCONN288_ADR50001P003C01-SCONNA
M_F_CPU1_SA_DQ<9>        U1               DU68     SOCKET4677_AZIFS054P001C01-SOCA
M_F_CPU1_SA_DQ<10>       J27              163      SCONN288_ADR50001P013C01-SCONNA
M_F_CPU1_SA_DQ<10>       J28              163      SCONN288_ADR50001P003C01-SCONNA
M_F_CPU1_SA_DQ<10>       U1               DY69     SOCKET4677_AZIFS054P001C01-SOCA
M_F_CPU1_SA_DQ<11>       J27              165      SCONN288_ADR50001P013C01-SCONNA
M_F_CPU1_SA_DQ<11>       J28              165      SCONN288_ADR50001P003C01-SCONNA
M_F_CPU1_SA_DQ<11>       U1               EA68     SOCKET4677_AZIFS054P001C01-SOCA
M_F_CPU1_SA_DQ<12>       J27              25       SCONN288_ADR50001P013C01-SCONNA
M_F_CPU1_SA_DQ<12>       J28              25       SCONN288_ADR50001P003C01-SCONNA
M_F_CPU1_SA_DQ<12>       U1               DU66     SOCKET4677_AZIFS054P001C01-SOCA
M_F_CPU1_SA_DQ<13>       J27              27       SCONN288_ADR50001P013C01-SCONNA
M_F_CPU1_SA_DQ<13>       J28              27       SCONN288_ADR50001P003C01-SCONNA
M_F_CPU1_SA_DQ<13>       U1               DV65     SOCKET4677_AZIFS054P001C01-SOCA
M_F_CPU1_SA_DQ<14>       J27              170      SCONN288_ADR50001P013C01-SCONNA
M_F_CPU1_SA_DQ<14>       J28              170      SCONN288_ADR50001P003C01-SCONNA
M_F_CPU1_SA_DQ<14>       U1               EA66     SOCKET4677_AZIFS054P001C01-SOCA
M_F_CPU1_SA_DQ<15>       J27              172      SCONN288_ADR50001P013C01-SCONNA
M_F_CPU1_SA_DQ<15>       J28              172      SCONN288_ADR50001P003C01-SCONNA
M_F_CPU1_SA_DQ<15>       U1               DY65     SOCKET4677_AZIFS054P001C01-SOCA
M_F_CPU1_SA_DQ<16>       J27              29       SCONN288_ADR50001P013C01-SCONNA
M_F_CPU1_SA_DQ<16>       J28              29       SCONN288_ADR50001P003C01-SCONNA
M_F_CPU1_SA_DQ<16>       U1               EE66     SOCKET4677_AZIFS054P001C01-SOCA
M_F_CPU1_SA_DQ<17>       J27              31       SCONN288_ADR50001P013C01-SCONNA
M_F_CPU1_SA_DQ<17>       J28              31       SCONN288_ADR50001P003C01-SCONNA
M_F_CPU1_SA_DQ<17>       U1               ED65     SOCKET4677_AZIFS054P001C01-SOCA
M_F_CPU1_SA_DQ<18>       J27              174      SCONN288_ADR50001P013C01-SCONNA
M_F_CPU1_SA_DQ<18>       J28              174      SCONN288_ADR50001P003C01-SCONNA
M_F_CPU1_SA_DQ<18>       U1               EG66     SOCKET4677_AZIFS054P001C01-SOCA
M_F_CPU1_SA_DQ<19>       J27              176      SCONN288_ADR50001P013C01-SCONNA
M_F_CPU1_SA_DQ<19>       J28              176      SCONN288_ADR50001P003C01-SCONNA
M_F_CPU1_SA_DQ<19>       U1               EH65     SOCKET4677_AZIFS054P001C01-SOCA
M_F_CPU1_SA_DQ<20>       J27              36       SCONN288_ADR50001P013C01-SCONNA
M_F_CPU1_SA_DQ<20>       J28              36       SCONN288_ADR50001P003C01-SCONNA
M_F_CPU1_SA_DQ<20>       U1               ED63     SOCKET4677_AZIFS054P001C01-SOCA
M_F_CPU1_SA_DQ<21>       J27              38       SCONN288_ADR50001P013C01-SCONNA
M_F_CPU1_SA_DQ<21>       J28              38       SCONN288_ADR50001P003C01-SCONNA
M_F_CPU1_SA_DQ<21>       U1               EE62     SOCKET4677_AZIFS054P001C01-SOCA
M_F_CPU1_SA_DQ<22>       J27              181      SCONN288_ADR50001P013C01-SCONNA
M_F_CPU1_SA_DQ<22>       J28              181      SCONN288_ADR50001P003C01-SCONNA
M_F_CPU1_SA_DQ<22>       U1               EH63     SOCKET4677_AZIFS054P001C01-SOCA
M_F_CPU1_SA_DQ<23>       J27              183      SCONN288_ADR50001P013C01-SCONNA
M_F_CPU1_SA_DQ<23>       J28              183      SCONN288_ADR50001P003C01-SCONNA
M_F_CPU1_SA_DQ<23>       U1               EG62     SOCKET4677_AZIFS054P001C01-SOCA
M_F_CPU1_SA_DQ<24>       J27              40       SCONN288_ADR50001P013C01-SCONNA
M_F_CPU1_SA_DQ<24>       J28              40       SCONN288_ADR50001P003C01-SCONNA
M_F_CPU1_SA_DQ<24>       U1               DV57     SOCKET4677_AZIFS054P001C01-SOCA
M_F_CPU1_SA_DQ<25>       J27              42       SCONN288_ADR50001P013C01-SCONNA
M_F_CPU1_SA_DQ<25>       J28              42       SCONN288_ADR50001P003C01-SCONNA
M_F_CPU1_SA_DQ<25>       U1               DU56     SOCKET4677_AZIFS054P001C01-SOCA
M_F_CPU1_SA_DQ<26>       J27              185      SCONN288_ADR50001P013C01-SCONNA
M_F_CPU1_SA_DQ<26>       J28              185      SCONN288_ADR50001P003C01-SCONNA
M_F_CPU1_SA_DQ<26>       U1               DY57     SOCKET4677_AZIFS054P001C01-SOCA
M_F_CPU1_SA_DQ<27>       J27              187      SCONN288_ADR50001P013C01-SCONNA
M_F_CPU1_SA_DQ<27>       J28              187      SCONN288_ADR50001P003C01-SCONNA
M_F_CPU1_SA_DQ<27>       U1               EA56     SOCKET4677_AZIFS054P001C01-SOCA
M_F_CPU1_SA_DQ<28>       J27              47       SCONN288_ADR50001P013C01-SCONNA
M_F_CPU1_SA_DQ<28>       J28              47       SCONN288_ADR50001P003C01-SCONNA
M_F_CPU1_SA_DQ<28>       U1               DU54     SOCKET4677_AZIFS054P001C01-SOCA
M_F_CPU1_SA_DQ<29>       J27              49       SCONN288_ADR50001P013C01-SCONNA
M_F_CPU1_SA_DQ<29>       J28              49       SCONN288_ADR50001P003C01-SCONNA
M_F_CPU1_SA_DQ<29>       U1               DV53     SOCKET4677_AZIFS054P001C01-SOCA
M_F_CPU1_SA_DQ<30>       J27              192      SCONN288_ADR50001P013C01-SCONNA
M_F_CPU1_SA_DQ<30>       J28              192      SCONN288_ADR50001P003C01-SCONNA
M_F_CPU1_SA_DQ<30>       U1               EA54     SOCKET4677_AZIFS054P001C01-SOCA
M_F_CPU1_SA_DQ<31>       J27              194      SCONN288_ADR50001P013C01-SCONNA
M_F_CPU1_SA_DQ<31>       J28              194      SCONN288_ADR50001P003C01-SCONNA
M_F_CPU1_SA_DQ<31>       U1               DY53     SOCKET4677_AZIFS054P001C01-SOCA
M_F_CPU1_SA_DQS_DN<0>    J27              12       SCONN288_ADR50001P013C01-SCONNA
M_F_CPU1_SA_DQS_DN<0>    J28              12       SCONN288_ADR50001P003C01-SCONNA
M_F_CPU1_SA_DQS_DN<0>    U1               EE76     SOCKET4677_AZIFS054P001C01-SOCA
M_F_CPU1_SA_DQS_DN<1>    J27              23       SCONN288_ADR50001P013C01-SCONNA
M_F_CPU1_SA_DQS_DN<1>    J28              23       SCONN288_ADR50001P003C01-SCONNA
M_F_CPU1_SA_DQS_DN<1>    U1               DT67     SOCKET4677_AZIFS054P001C01-SOCA
M_F_CPU1_SA_DQS_DN<2>    J27              34       SCONN288_ADR50001P013C01-SCONNA
M_F_CPU1_SA_DQS_DN<2>    J28              34       SCONN288_ADR50001P003C01-SCONNA
M_F_CPU1_SA_DQS_DN<2>    U1               EC64     SOCKET4677_AZIFS054P001C01-SOCA
M_F_CPU1_SA_DQS_DN<3>    J27              45       SCONN288_ADR50001P013C01-SCONNA
M_F_CPU1_SA_DQS_DN<3>    J28              45       SCONN288_ADR50001P003C01-SCONNA
M_F_CPU1_SA_DQS_DN<3>    U1               DV55     SOCKET4677_AZIFS054P001C01-SOCA
M_F_CPU1_SA_DQS_DN<4>    J27              56       SCONN288_ADR50001P013C01-SCONNA
M_F_CPU1_SA_DQS_DN<4>    J28              56       SCONN288_ADR50001P003C01-SCONNA
M_F_CPU1_SA_DQS_DN<4>    U1               EE58     SOCKET4677_AZIFS054P001C01-SOCA
M_F_CPU1_SA_DQS_DN<5>    J27              156      SCONN288_ADR50001P013C01-SCONNA
M_F_CPU1_SA_DQS_DN<5>    J28              156      SCONN288_ADR50001P003C01-SCONNA
M_F_CPU1_SA_DQS_DN<5>    U1               EJ76     SOCKET4677_AZIFS054P001C01-SOCA
M_F_CPU1_SA_DQS_DN<6>    J27              167      SCONN288_ADR50001P013C01-SCONNA
M_F_CPU1_SA_DQS_DN<6>    J28              167      SCONN288_ADR50001P003C01-SCONNA
M_F_CPU1_SA_DQS_DN<6>    U1               EB67     SOCKET4677_AZIFS054P001C01-SOCA
M_F_CPU1_SA_DQS_DN<7>    J27              178      SCONN288_ADR50001P013C01-SCONNA
M_F_CPU1_SA_DQS_DN<7>    J28              178      SCONN288_ADR50001P003C01-SCONNA
M_F_CPU1_SA_DQS_DN<7>    U1               EJ64     SOCKET4677_AZIFS054P001C01-SOCA
M_F_CPU1_SA_DQS_DN<8>    J27              189      SCONN288_ADR50001P013C01-SCONNA
M_F_CPU1_SA_DQS_DN<8>    J28              189      SCONN288_ADR50001P003C01-SCONNA
M_F_CPU1_SA_DQS_DN<8>    U1               EB55     SOCKET4677_AZIFS054P001C01-SOCA
M_F_CPU1_SA_DQS_DN<9>    J27              200      SCONN288_ADR50001P013C01-SCONNA
M_F_CPU1_SA_DQS_DN<9>    J28              200      SCONN288_ADR50001P003C01-SCONNA
M_F_CPU1_SA_DQS_DN<9>    U1               EJ58     SOCKET4677_AZIFS054P001C01-SOCA
M_F_CPU1_SA_DQS_DP<0>    J27              11       SCONN288_ADR50001P013C01-SCONNA
M_F_CPU1_SA_DQS_DP<0>    J28              11       SCONN288_ADR50001P003C01-SCONNA
M_F_CPU1_SA_DQS_DP<0>    U1               EC76     SOCKET4677_AZIFS054P001C01-SOCA
M_F_CPU1_SA_DQS_DP<1>    J27              22       SCONN288_ADR50001P013C01-SCONNA
M_F_CPU1_SA_DQS_DP<1>    J28              22       SCONN288_ADR50001P003C01-SCONNA
M_F_CPU1_SA_DQS_DP<1>    U1               DV67     SOCKET4677_AZIFS054P001C01-SOCA
M_F_CPU1_SA_DQS_DP<2>    J27              33       SCONN288_ADR50001P013C01-SCONNA
M_F_CPU1_SA_DQS_DP<2>    J28              33       SCONN288_ADR50001P003C01-SCONNA
M_F_CPU1_SA_DQS_DP<2>    U1               EE64     SOCKET4677_AZIFS054P001C01-SOCA
M_F_CPU1_SA_DQS_DP<3>    J27              44       SCONN288_ADR50001P013C01-SCONNA
M_F_CPU1_SA_DQS_DP<3>    J28              44       SCONN288_ADR50001P003C01-SCONNA
M_F_CPU1_SA_DQS_DP<3>    U1               DT55     SOCKET4677_AZIFS054P001C01-SOCA
M_F_CPU1_SA_DQS_DP<4>    J27              55       SCONN288_ADR50001P013C01-SCONNA
M_F_CPU1_SA_DQS_DP<4>    J28              55       SCONN288_ADR50001P003C01-SCONNA
M_F_CPU1_SA_DQS_DP<4>    U1               EC58     SOCKET4677_AZIFS054P001C01-SOCA
M_F_CPU1_SA_DQS_DP<5>    J27              157      SCONN288_ADR50001P013C01-SCONNA
M_F_CPU1_SA_DQS_DP<5>    J28              157      SCONN288_ADR50001P003C01-SCONNA
M_F_CPU1_SA_DQS_DP<5>    U1               EG76     SOCKET4677_AZIFS054P001C01-SOCA
M_F_CPU1_SA_DQS_DP<6>    J27              168      SCONN288_ADR50001P013C01-SCONNA
M_F_CPU1_SA_DQS_DP<6>    J28              168      SCONN288_ADR50001P003C01-SCONNA
M_F_CPU1_SA_DQS_DP<6>    U1               DY67     SOCKET4677_AZIFS054P001C01-SOCA
M_F_CPU1_SA_DQS_DP<7>    J27              179      SCONN288_ADR50001P013C01-SCONNA
M_F_CPU1_SA_DQS_DP<7>    J28              179      SCONN288_ADR50001P003C01-SCONNA
M_F_CPU1_SA_DQS_DP<7>    U1               EG64     SOCKET4677_AZIFS054P001C01-SOCA
M_F_CPU1_SA_DQS_DP<8>    J27              190      SCONN288_ADR50001P013C01-SCONNA
M_F_CPU1_SA_DQS_DP<8>    J28              190      SCONN288_ADR50001P003C01-SCONNA
M_F_CPU1_SA_DQS_DP<8>    U1               DY55     SOCKET4677_AZIFS054P001C01-SOCA
M_F_CPU1_SA_DQS_DP<9>    J27              201      SCONN288_ADR50001P013C01-SCONNA
M_F_CPU1_SA_DQS_DP<9>    J28              201      SCONN288_ADR50001P003C01-SCONNA
M_F_CPU1_SA_DQS_DP<9>    U1               EG58     SOCKET4677_AZIFS054P001C01-SOCA
M_F_CPU1_SA_PAR          J27              74       SCONN288_ADR50001P013C01-SCONNA
M_F_CPU1_SA_PAR          J28              74       SCONN288_ADR50001P003C01-SCONNA
M_F_CPU1_SA_PAR          U1               EA50     SOCKET4677_AZIFS054P001C01-SOCA
M_F_CPU1_SA_RSP<0>       J27              86       SCONN288_ADR50001P013C01-SCONNA
M_F_CPU1_SA_RSP<0>       U1               DN48     SOCKET4677_AZIFS054P001C01-SOCA
M_F_CPU1_SA_RSP<1>       J28              86       SCONN288_ADR50001P003C01-SCONNA
M_F_CPU1_SA_RSP<1>       U1               DP47     SOCKET4677_AZIFS054P001C01-SOCA
M_F_CPU1_SB_CA<0>        J27              76       SCONN288_ADR50001P013C01-SCONNA
M_F_CPU1_SB_CA<0>        J28              76       SCONN288_ADR50001P003C01-SCONNA
M_F_CPU1_SB_CA<0>        U1               DV51     SOCKET4677_AZIFS054P001C01-SOCA
M_F_CPU1_SB_CA<1>        J27              221      SCONN288_ADR50001P013C01-SCONNA
M_F_CPU1_SB_CA<1>        J28              221      SCONN288_ADR50001P003C01-SCONNA
M_F_CPU1_SB_CA<1>        U1               DU50     SOCKET4677_AZIFS054P001C01-SOCA
M_F_CPU1_SB_CA<2>        J27              78       SCONN288_ADR50001P013C01-SCONNA
M_F_CPU1_SB_CA<2>        J28              78       SCONN288_ADR50001P003C01-SCONNA
M_F_CPU1_SB_CA<2>        U1               EE41     SOCKET4677_AZIFS054P001C01-SOCA
M_F_CPU1_SB_CA<3>        J27              223      SCONN288_ADR50001P013C01-SCONNA
M_F_CPU1_SB_CA<3>        J28              223      SCONN288_ADR50001P003C01-SCONNA
M_F_CPU1_SB_CA<3>        U1               EG41     SOCKET4677_AZIFS054P001C01-SOCA
M_F_CPU1_SB_CA<4>        J27              80       SCONN288_ADR50001P013C01-SCONNA
M_F_CPU1_SB_CA<4>        J28              80       SCONN288_ADR50001P003C01-SCONNA
M_F_CPU1_SB_CA<4>        U1               ED40     SOCKET4677_AZIFS054P001C01-SOCA
M_F_CPU1_SB_CA<5>        J27              225      SCONN288_ADR50001P013C01-SCONNA
M_F_CPU1_SB_CA<5>        J28              225      SCONN288_ADR50001P003C01-SCONNA
M_F_CPU1_SB_CA<5>        U1               EH40     SOCKET4677_AZIFS054P001C01-SOCA
M_F_CPU1_SB_CA<6>        J27              82       SCONN288_ADR50001P013C01-SCONNA
M_F_CPU1_SB_CA<6>        J28              82       SCONN288_ADR50001P003C01-SCONNA
M_F_CPU1_SB_CA<6>        U1               EC39     SOCKET4677_AZIFS054P001C01-SOCA
M_F_CPU1_SB_CB<0>        J27              96       SCONN288_ADR50001P013C01-SCONNA
M_F_CPU1_SB_CB<0>        J28              96       SCONN288_ADR50001P003C01-SCONNA
M_F_CPU1_SB_CB<0>        U1               ED32     SOCKET4677_AZIFS054P001C01-SOCA
M_F_CPU1_SB_CB<1>        J27              98       SCONN288_ADR50001P013C01-SCONNA
M_F_CPU1_SB_CB<1>        J28              98       SCONN288_ADR50001P003C01-SCONNA
M_F_CPU1_SB_CB<1>        U1               EE31     SOCKET4677_AZIFS054P001C01-SOCA
M_F_CPU1_SB_CB<2>        J27              241      SCONN288_ADR50001P013C01-SCONNA
M_F_CPU1_SB_CB<2>        J28              241      SCONN288_ADR50001P003C01-SCONNA
M_F_CPU1_SB_CB<2>        U1               EH32     SOCKET4677_AZIFS054P001C01-SOCA
M_F_CPU1_SB_CB<3>        J27              243      SCONN288_ADR50001P013C01-SCONNA
M_F_CPU1_SB_CB<3>        J28              243      SCONN288_ADR50001P003C01-SCONNA
M_F_CPU1_SB_CB<3>        U1               EG31     SOCKET4677_AZIFS054P001C01-SOCA
M_F_CPU1_SB_CB<4>        J27              89       SCONN288_ADR50001P013C01-SCONNA
M_F_CPU1_SB_CB<4>        J28              89       SCONN288_ADR50001P003C01-SCONNA
M_F_CPU1_SB_CB<4>        U1               EE35     SOCKET4677_AZIFS054P001C01-SOCA
M_F_CPU1_SB_CB<5>        J27              91       SCONN288_ADR50001P013C01-SCONNA
M_F_CPU1_SB_CB<5>        J28              91       SCONN288_ADR50001P003C01-SCONNA
M_F_CPU1_SB_CB<5>        U1               ED34     SOCKET4677_AZIFS054P001C01-SOCA
M_F_CPU1_SB_CB<6>        J27              234      SCONN288_ADR50001P013C01-SCONNA
M_F_CPU1_SB_CB<6>        J28              234      SCONN288_ADR50001P003C01-SCONNA
M_F_CPU1_SB_CB<6>        U1               EG35     SOCKET4677_AZIFS054P001C01-SOCA
M_F_CPU1_SB_CB<7>        J27              236      SCONN288_ADR50001P013C01-SCONNA
M_F_CPU1_SB_CB<7>        J28              236      SCONN288_ADR50001P003C01-SCONNA
M_F_CPU1_SB_CB<7>        U1               EH34     SOCKET4677_AZIFS054P001C01-SOCA
M_F_CPU1_SB_CS_N<0>      J27              84       SCONN288_ADR50001P013C01-SCONNA
M_F_CPU1_SB_CS_N<0>      U1               EH38     SOCKET4677_AZIFS054P001C01-SOCA
M_F_CPU1_SB_CS_N<1>      J27              229      SCONN288_ADR50001P013C01-SCONNA
M_F_CPU1_SB_CS_N<1>      U1               EG37     SOCKET4677_AZIFS054P001C01-SOCA
M_F_CPU1_SB_CS_N<2>      J28              84       SCONN288_ADR50001P003C01-SCONNA
M_F_CPU1_SB_CS_N<2>      U1               ED38     SOCKET4677_AZIFS054P001C01-SOCA
M_F_CPU1_SB_CS_N<3>      J28              229      SCONN288_ADR50001P003C01-SCONNA
M_F_CPU1_SB_CS_N<3>      U1               EE37     SOCKET4677_AZIFS054P001C01-SOCA
M_F_CPU1_SB_DQ<0>        J27              100      SCONN288_ADR50001P013C01-SCONNA
M_F_CPU1_SB_DQ<0>        J28              100      SCONN288_ADR50001P003C01-SCONNA
M_F_CPU1_SB_DQ<0>        U1               DV32     SOCKET4677_AZIFS054P001C01-SOCA
M_F_CPU1_SB_DQ<1>        J27              102      SCONN288_ADR50001P013C01-SCONNA
M_F_CPU1_SB_DQ<1>        J28              102      SCONN288_ADR50001P003C01-SCONNA
M_F_CPU1_SB_DQ<1>        U1               DU31     SOCKET4677_AZIFS054P001C01-SOCA
M_F_CPU1_SB_DQ<2>        J27              245      SCONN288_ADR50001P013C01-SCONNA
M_F_CPU1_SB_DQ<2>        J28              245      SCONN288_ADR50001P003C01-SCONNA
M_F_CPU1_SB_DQ<2>        U1               DY32     SOCKET4677_AZIFS054P001C01-SOCA
M_F_CPU1_SB_DQ<3>        J27              247      SCONN288_ADR50001P013C01-SCONNA
M_F_CPU1_SB_DQ<3>        J28              247      SCONN288_ADR50001P003C01-SCONNA
M_F_CPU1_SB_DQ<3>        U1               EA31     SOCKET4677_AZIFS054P001C01-SOCA
M_F_CPU1_SB_DQ<4>        J27              107      SCONN288_ADR50001P013C01-SCONNA
M_F_CPU1_SB_DQ<4>        J28              107      SCONN288_ADR50001P003C01-SCONNA
M_F_CPU1_SB_DQ<4>        U1               DU29     SOCKET4677_AZIFS054P001C01-SOCA
M_F_CPU1_SB_DQ<5>        J27              109      SCONN288_ADR50001P013C01-SCONNA
M_F_CPU1_SB_DQ<5>        J28              109      SCONN288_ADR50001P003C01-SCONNA
M_F_CPU1_SB_DQ<5>        U1               DV28     SOCKET4677_AZIFS054P001C01-SOCA
M_F_CPU1_SB_DQ<6>        J27              252      SCONN288_ADR50001P013C01-SCONNA
M_F_CPU1_SB_DQ<6>        J28              252      SCONN288_ADR50001P003C01-SCONNA
M_F_CPU1_SB_DQ<6>        U1               EA29     SOCKET4677_AZIFS054P001C01-SOCA
M_F_CPU1_SB_DQ<7>        J27              254      SCONN288_ADR50001P013C01-SCONNA
M_F_CPU1_SB_DQ<7>        J28              254      SCONN288_ADR50001P003C01-SCONNA
M_F_CPU1_SB_DQ<7>        U1               DY28     SOCKET4677_AZIFS054P001C01-SOCA
M_F_CPU1_SB_DQ<8>        J27              111      SCONN288_ADR50001P013C01-SCONNA
M_F_CPU1_SB_DQ<8>        J28              111      SCONN288_ADR50001P003C01-SCONNA
M_F_CPU1_SB_DQ<8>        U1               EE23     SOCKET4677_AZIFS054P001C01-SOCA
M_F_CPU1_SB_DQ<9>        J27              113      SCONN288_ADR50001P013C01-SCONNA
M_F_CPU1_SB_DQ<9>        J28              113      SCONN288_ADR50001P003C01-SCONNA
M_F_CPU1_SB_DQ<9>        U1               ED22     SOCKET4677_AZIFS054P001C01-SOCA
M_F_CPU1_SB_DQ<10>       J27              256      SCONN288_ADR50001P013C01-SCONNA
M_F_CPU1_SB_DQ<10>       J28              256      SCONN288_ADR50001P003C01-SCONNA
M_F_CPU1_SB_DQ<10>       U1               EG23     SOCKET4677_AZIFS054P001C01-SOCA
M_F_CPU1_SB_DQ<11>       J27              258      SCONN288_ADR50001P013C01-SCONNA
M_F_CPU1_SB_DQ<11>       J28              258      SCONN288_ADR50001P003C01-SCONNA
M_F_CPU1_SB_DQ<11>       U1               EH22     SOCKET4677_AZIFS054P001C01-SOCA
M_F_CPU1_SB_DQ<12>       J27              118      SCONN288_ADR50001P013C01-SCONNA
M_F_CPU1_SB_DQ<12>       J28              118      SCONN288_ADR50001P003C01-SCONNA
M_F_CPU1_SB_DQ<12>       U1               ED20     SOCKET4677_AZIFS054P001C01-SOCA
M_F_CPU1_SB_DQ<13>       J27              120      SCONN288_ADR50001P013C01-SCONNA
M_F_CPU1_SB_DQ<13>       J28              120      SCONN288_ADR50001P003C01-SCONNA
M_F_CPU1_SB_DQ<13>       U1               EE19     SOCKET4677_AZIFS054P001C01-SOCA
M_F_CPU1_SB_DQ<14>       J27              263      SCONN288_ADR50001P013C01-SCONNA
M_F_CPU1_SB_DQ<14>       J28              263      SCONN288_ADR50001P003C01-SCONNA
M_F_CPU1_SB_DQ<14>       U1               EH20     SOCKET4677_AZIFS054P001C01-SOCA
M_F_CPU1_SB_DQ<15>       J27              265      SCONN288_ADR50001P013C01-SCONNA
M_F_CPU1_SB_DQ<15>       J28              265      SCONN288_ADR50001P003C01-SCONNA
M_F_CPU1_SB_DQ<15>       U1               EG19     SOCKET4677_AZIFS054P001C01-SOCA
M_F_CPU1_SB_DQ<16>       J27              122      SCONN288_ADR50001P013C01-SCONNA
M_F_CPU1_SB_DQ<16>       J28              122      SCONN288_ADR50001P003C01-SCONNA
M_F_CPU1_SB_DQ<16>       U1               EM14     SOCKET4677_AZIFS054P001C01-SOCA
M_F_CPU1_SB_DQ<17>       J27              124      SCONN288_ADR50001P013C01-SCONNA
M_F_CPU1_SB_DQ<17>       J28              124      SCONN288_ADR50001P003C01-SCONNA
M_F_CPU1_SB_DQ<17>       U1               EL13     SOCKET4677_AZIFS054P001C01-SOCA
M_F_CPU1_SB_DQ<18>       J27              267      SCONN288_ADR50001P013C01-SCONNA
M_F_CPU1_SB_DQ<18>       J28              267      SCONN288_ADR50001P003C01-SCONNA
M_F_CPU1_SB_DQ<18>       U1               EP14     SOCKET4677_AZIFS054P001C01-SOCA
M_F_CPU1_SB_DQ<19>       J27              269      SCONN288_ADR50001P013C01-SCONNA
M_F_CPU1_SB_DQ<19>       J28              269      SCONN288_ADR50001P003C01-SCONNA
M_F_CPU1_SB_DQ<19>       U1               ER13     SOCKET4677_AZIFS054P001C01-SOCA
M_F_CPU1_SB_DQ<20>       J27              129      SCONN288_ADR50001P013C01-SCONNA
M_F_CPU1_SB_DQ<20>       J28              129      SCONN288_ADR50001P003C01-SCONNA
M_F_CPU1_SB_DQ<20>       U1               EL11     SOCKET4677_AZIFS054P001C01-SOCA
M_F_CPU1_SB_DQ<21>       J27              131      SCONN288_ADR50001P013C01-SCONNA
M_F_CPU1_SB_DQ<21>       J28              131      SCONN288_ADR50001P003C01-SCONNA
M_F_CPU1_SB_DQ<21>       U1               EM10     SOCKET4677_AZIFS054P001C01-SOCA
M_F_CPU1_SB_DQ<22>       J27              274      SCONN288_ADR50001P013C01-SCONNA
M_F_CPU1_SB_DQ<22>       J28              274      SCONN288_ADR50001P003C01-SCONNA
M_F_CPU1_SB_DQ<22>       U1               ER11     SOCKET4677_AZIFS054P001C01-SOCA
M_F_CPU1_SB_DQ<23>       J27              276      SCONN288_ADR50001P013C01-SCONNA
M_F_CPU1_SB_DQ<23>       J28              276      SCONN288_ADR50001P003C01-SCONNA
M_F_CPU1_SB_DQ<23>       U1               EP10     SOCKET4677_AZIFS054P001C01-SOCA
M_F_CPU1_SB_DQ<24>       J27              133      SCONN288_ADR50001P013C01-SCONNA
M_F_CPU1_SB_DQ<24>       J28              133      SCONN288_ADR50001P003C01-SCONNA
M_F_CPU1_SB_DQ<24>       U1               DV20     SOCKET4677_AZIFS054P001C01-SOCA
M_F_CPU1_SB_DQ<25>       J27              135      SCONN288_ADR50001P013C01-SCONNA
M_F_CPU1_SB_DQ<25>       J28              135      SCONN288_ADR50001P003C01-SCONNA
M_F_CPU1_SB_DQ<25>       U1               DU19     SOCKET4677_AZIFS054P001C01-SOCA
M_F_CPU1_SB_DQ<26>       J27              278      SCONN288_ADR50001P013C01-SCONNA
M_F_CPU1_SB_DQ<26>       J28              278      SCONN288_ADR50001P003C01-SCONNA
M_F_CPU1_SB_DQ<26>       U1               DY20     SOCKET4677_AZIFS054P001C01-SOCA
M_F_CPU1_SB_DQ<27>       J27              280      SCONN288_ADR50001P013C01-SCONNA
M_F_CPU1_SB_DQ<27>       J28              280      SCONN288_ADR50001P003C01-SCONNA
M_F_CPU1_SB_DQ<27>       U1               EA19     SOCKET4677_AZIFS054P001C01-SOCA
M_F_CPU1_SB_DQ<28>       J27              140      SCONN288_ADR50001P013C01-SCONNA
M_F_CPU1_SB_DQ<28>       J28              140      SCONN288_ADR50001P003C01-SCONNA
M_F_CPU1_SB_DQ<28>       U1               EA17     SOCKET4677_AZIFS054P001C01-SOCA
M_F_CPU1_SB_DQ<29>       J27              142      SCONN288_ADR50001P013C01-SCONNA
M_F_CPU1_SB_DQ<29>       J28              142      SCONN288_ADR50001P003C01-SCONNA
M_F_CPU1_SB_DQ<29>       U1               DU17     SOCKET4677_AZIFS054P001C01-SOCA
M_F_CPU1_SB_DQ<30>       J27              285      SCONN288_ADR50001P013C01-SCONNA
M_F_CPU1_SB_DQ<30>       J28              285      SCONN288_ADR50001P003C01-SCONNA
M_F_CPU1_SB_DQ<30>       U1               EC17     SOCKET4677_AZIFS054P001C01-SOCA
M_F_CPU1_SB_DQ<31>       J27              287      SCONN288_ADR50001P013C01-SCONNA
M_F_CPU1_SB_DQ<31>       J28              287      SCONN288_ADR50001P003C01-SCONNA
M_F_CPU1_SB_DQ<31>       U1               DR17     SOCKET4677_AZIFS054P001C01-SOCA
M_F_CPU1_SB_DQS_DN<0>    J27              105      SCONN288_ADR50001P013C01-SCONNA
M_F_CPU1_SB_DQS_DN<0>    J28              105      SCONN288_ADR50001P003C01-SCONNA
M_F_CPU1_SB_DQS_DN<0>    U1               DV30     SOCKET4677_AZIFS054P001C01-SOCA
M_F_CPU1_SB_DQS_DN<1>    J27              116      SCONN288_ADR50001P013C01-SCONNA
M_F_CPU1_SB_DQS_DN<1>    J28              116      SCONN288_ADR50001P003C01-SCONNA
M_F_CPU1_SB_DQS_DN<1>    U1               EE21     SOCKET4677_AZIFS054P001C01-SOCA
M_F_CPU1_SB_DQS_DN<2>    J27              127      SCONN288_ADR50001P013C01-SCONNA
M_F_CPU1_SB_DQS_DN<2>    J28              127      SCONN288_ADR50001P003C01-SCONNA
M_F_CPU1_SB_DQS_DN<2>    U1               EM12     SOCKET4677_AZIFS054P001C01-SOCA
M_F_CPU1_SB_DQS_DN<3>    J27              138      SCONN288_ADR50001P013C01-SCONNA
M_F_CPU1_SB_DQS_DN<3>    J28              138      SCONN288_ADR50001P003C01-SCONNA
M_F_CPU1_SB_DQS_DN<3>    U1               DT18     SOCKET4677_AZIFS054P001C01-SOCA
M_F_CPU1_SB_DQS_DN<4>    J27              238      SCONN288_ADR50001P013C01-SCONNA
M_F_CPU1_SB_DQS_DN<4>    J28              238      SCONN288_ADR50001P003C01-SCONNA
M_F_CPU1_SB_DQS_DN<4>    U1               EJ33     SOCKET4677_AZIFS054P001C01-SOCA
M_F_CPU1_SB_DQS_DN<5>    J27              249      SCONN288_ADR50001P013C01-SCONNA
M_F_CPU1_SB_DQS_DN<5>    J28              249      SCONN288_ADR50001P003C01-SCONNA
M_F_CPU1_SB_DQS_DN<5>    U1               EB30     SOCKET4677_AZIFS054P001C01-SOCA
M_F_CPU1_SB_DQS_DN<6>    J27              260      SCONN288_ADR50001P013C01-SCONNA
M_F_CPU1_SB_DQS_DN<6>    J28              260      SCONN288_ADR50001P003C01-SCONNA
M_F_CPU1_SB_DQS_DN<6>    U1               EJ21     SOCKET4677_AZIFS054P001C01-SOCA
M_F_CPU1_SB_DQS_DN<7>    J27              271      SCONN288_ADR50001P013C01-SCONNA
M_F_CPU1_SB_DQS_DN<7>    J28              271      SCONN288_ADR50001P003C01-SCONNA
M_F_CPU1_SB_DQS_DN<7>    U1               ET12     SOCKET4677_AZIFS054P001C01-SOCA
M_F_CPU1_SB_DQS_DN<8>    J27              282      SCONN288_ADR50001P013C01-SCONNA
M_F_CPU1_SB_DQS_DN<8>    J28              282      SCONN288_ADR50001P003C01-SCONNA
M_F_CPU1_SB_DQS_DN<8>    U1               DY18     SOCKET4677_AZIFS054P001C01-SOCA
M_F_CPU1_SB_DQS_DN<9>    J27              94       SCONN288_ADR50001P013C01-SCONNA
M_F_CPU1_SB_DQS_DN<9>    J28              94       SCONN288_ADR50001P003C01-SCONNA
M_F_CPU1_SB_DQS_DN<9>    U1               EE33     SOCKET4677_AZIFS054P001C01-SOCA
M_F_CPU1_SB_DQS_DP<0>    J27              104      SCONN288_ADR50001P013C01-SCONNA
M_F_CPU1_SB_DQS_DP<0>    J28              104      SCONN288_ADR50001P003C01-SCONNA
M_F_CPU1_SB_DQS_DP<0>    U1               DT30     SOCKET4677_AZIFS054P001C01-SOCA
M_F_CPU1_SB_DQS_DP<1>    J27              115      SCONN288_ADR50001P013C01-SCONNA
M_F_CPU1_SB_DQS_DP<1>    J28              115      SCONN288_ADR50001P003C01-SCONNA
M_F_CPU1_SB_DQS_DP<1>    U1               EC21     SOCKET4677_AZIFS054P001C01-SOCA
M_F_CPU1_SB_DQS_DP<2>    J27              126      SCONN288_ADR50001P013C01-SCONNA
M_F_CPU1_SB_DQS_DP<2>    J28              126      SCONN288_ADR50001P003C01-SCONNA
M_F_CPU1_SB_DQS_DP<2>    U1               EK12     SOCKET4677_AZIFS054P001C01-SOCA
M_F_CPU1_SB_DQS_DP<3>    J27              137      SCONN288_ADR50001P013C01-SCONNA
M_F_CPU1_SB_DQS_DP<3>    J28              137      SCONN288_ADR50001P003C01-SCONNA
M_F_CPU1_SB_DQS_DP<3>    U1               DV18     SOCKET4677_AZIFS054P001C01-SOCA
M_F_CPU1_SB_DQS_DP<4>    J27              239      SCONN288_ADR50001P013C01-SCONNA
M_F_CPU1_SB_DQS_DP<4>    J28              239      SCONN288_ADR50001P003C01-SCONNA
M_F_CPU1_SB_DQS_DP<4>    U1               EG33     SOCKET4677_AZIFS054P001C01-SOCA
M_F_CPU1_SB_DQS_DP<5>    J27              250      SCONN288_ADR50001P013C01-SCONNA
M_F_CPU1_SB_DQS_DP<5>    J28              250      SCONN288_ADR50001P003C01-SCONNA
M_F_CPU1_SB_DQS_DP<5>    U1               DY30     SOCKET4677_AZIFS054P001C01-SOCA
M_F_CPU1_SB_DQS_DP<6>    J27              261      SCONN288_ADR50001P013C01-SCONNA
M_F_CPU1_SB_DQS_DP<6>    J28              261      SCONN288_ADR50001P003C01-SCONNA
M_F_CPU1_SB_DQS_DP<6>    U1               EG21     SOCKET4677_AZIFS054P001C01-SOCA
M_F_CPU1_SB_DQS_DP<7>    J27              272      SCONN288_ADR50001P013C01-SCONNA
M_F_CPU1_SB_DQS_DP<7>    J28              272      SCONN288_ADR50001P003C01-SCONNA
M_F_CPU1_SB_DQS_DP<7>    U1               EP12     SOCKET4677_AZIFS054P001C01-SOCA
M_F_CPU1_SB_DQS_DP<8>    J27              283      SCONN288_ADR50001P013C01-SCONNA
M_F_CPU1_SB_DQS_DP<8>    J28              283      SCONN288_ADR50001P003C01-SCONNA
M_F_CPU1_SB_DQS_DP<8>    U1               EB18     SOCKET4677_AZIFS054P001C01-SOCA
M_F_CPU1_SB_DQS_DP<9>    J27              93       SCONN288_ADR50001P013C01-SCONNA
M_F_CPU1_SB_DQS_DP<9>    J28              93       SCONN288_ADR50001P003C01-SCONNA
M_F_CPU1_SB_DQS_DP<9>    U1               EC33     SOCKET4677_AZIFS054P001C01-SOCA
M_F_CPU1_SB_PAR          J27              227      SCONN288_ADR50001P013C01-SCONNA
M_F_CPU1_SB_PAR          J28              227      SCONN288_ADR50001P003C01-SCONNA
M_F_CPU1_SB_PAR          U1               EJ39     SOCKET4677_AZIFS054P001C01-SOCA
M_F_CPU1_SB_RSP<0>       J27              87       SCONN288_ADR50001P013C01-SCONNA
M_F_CPU1_SB_RSP<0>       U1               DL48     SOCKET4677_AZIFS054P001C01-SOCA
M_F_CPU1_SB_RSP<1>       J28              87       SCONN288_ADR50001P003C01-SCONNA
M_F_CPU1_SB_RSP<1>       U1               DK47     SOCKET4677_AZIFS054P001C01-SOCA
M_G_CPU0_ALERT_N         J13              62       SCONN288_ADR50001P013C01-SCONNA
M_G_CPU0_ALERT_N         J14              62       SCONN288_ADR50001P003C01-SCONNA
M_G_CPU0_ALERT_N         U2               CW50     SOCKET4677_AZIFS054P001C01-SOCA
M_G_CPU0_CLK_DN<0>       J13              218      SCONN288_ADR50001P013C01-SCONNA
M_G_CPU0_CLK_DN<0>       U2               DR45     SOCKET4677_AZIFS054P001C01-SOCA
M_G_CPU0_CLK_DN<1>       J14              218      SCONN288_ADR50001P003C01-SCONNA
M_G_CPU0_CLK_DN<1>       U2               DL45     SOCKET4677_AZIFS054P001C01-SOCA
M_G_CPU0_CLK_DP<0>       J13              217      SCONN288_ADR50001P013C01-SCONNA
M_G_CPU0_CLK_DP<0>       U2               DN45     SOCKET4677_AZIFS054P001C01-SOCA
M_G_CPU0_CLK_DP<1>       J14              217      SCONN288_ADR50001P003C01-SCONNA
M_G_CPU0_CLK_DP<1>       U2               DJ45     SOCKET4677_AZIFS054P001C01-SOCA
M_G_CPU0_SA_CA<0>        J13              66       SCONN288_ADR50001P013C01-SCONNA
M_G_CPU0_SA_CA<0>        J14              66       SCONN288_ADR50001P003C01-SCONNA
M_G_CPU0_SA_CA<0>        U2               DJ52     SOCKET4677_AZIFS054P001C01-SOCA
M_G_CPU0_SA_CA<1>        J13              211      SCONN288_ADR50001P013C01-SCONNA
M_G_CPU0_SA_CA<1>        J14              211      SCONN288_ADR50001P003C01-SCONNA
M_G_CPU0_SA_CA<1>        U2               DR52     SOCKET4677_AZIFS054P001C01-SOCA
M_G_CPU0_SA_CA<2>        J13              68       SCONN288_ADR50001P013C01-SCONNA
M_G_CPU0_SA_CA<2>        J14              68       SCONN288_ADR50001P003C01-SCONNA
M_G_CPU0_SA_CA<2>        U2               DK51     SOCKET4677_AZIFS054P001C01-SOCA
M_G_CPU0_SA_CA<3>        J13              213      SCONN288_ADR50001P013C01-SCONNA
M_G_CPU0_SA_CA<3>        J14              213      SCONN288_ADR50001P003C01-SCONNA
M_G_CPU0_SA_CA<3>        U2               DP51     SOCKET4677_AZIFS054P001C01-SOCA
M_G_CPU0_SA_CA<4>        J13              70       SCONN288_ADR50001P013C01-SCONNA
M_G_CPU0_SA_CA<4>        J14              70       SCONN288_ADR50001P003C01-SCONNA
M_G_CPU0_SA_CA<4>        U2               DL50     SOCKET4677_AZIFS054P001C01-SOCA
M_G_CPU0_SA_CA<5>        J13              215      SCONN288_ADR50001P013C01-SCONNA
M_G_CPU0_SA_CA<5>        J14              215      SCONN288_ADR50001P003C01-SCONNA
M_G_CPU0_SA_CA<5>        U2               DN50     SOCKET4677_AZIFS054P001C01-SOCA
M_G_CPU0_SA_CA<6>        J13              72       SCONN288_ADR50001P013C01-SCONNA
M_G_CPU0_SA_CA<6>        J14              72       SCONN288_ADR50001P003C01-SCONNA
M_G_CPU0_SA_CA<6>        U2               DK44     SOCKET4677_AZIFS054P001C01-SOCA
M_G_CPU0_SA_CB<0>        J13              51       SCONN288_ADR50001P013C01-SCONNA
M_G_CPU0_SA_CB<0>        J14              51       SCONN288_ADR50001P003C01-SCONNA
M_G_CPU0_SA_CB<0>        U2               DL60     SOCKET4677_AZIFS054P001C01-SOCA
M_G_CPU0_SA_CB<1>        J13              53       SCONN288_ADR50001P013C01-SCONNA
M_G_CPU0_SA_CB<1>        J14              53       SCONN288_ADR50001P003C01-SCONNA
M_G_CPU0_SA_CB<1>        U2               DK59     SOCKET4677_AZIFS054P001C01-SOCA
M_G_CPU0_SA_CB<2>        J13              196      SCONN288_ADR50001P013C01-SCONNA
M_G_CPU0_SA_CB<2>        J14              196      SCONN288_ADR50001P003C01-SCONNA
M_G_CPU0_SA_CB<2>        U2               DN60     SOCKET4677_AZIFS054P001C01-SOCA
M_G_CPU0_SA_CB<3>        J13              198      SCONN288_ADR50001P013C01-SCONNA
M_G_CPU0_SA_CB<3>        J14              198      SCONN288_ADR50001P003C01-SCONNA
M_G_CPU0_SA_CB<3>        U2               DP59     SOCKET4677_AZIFS054P001C01-SOCA
M_G_CPU0_SA_CB<4>        J13              58       SCONN288_ADR50001P013C01-SCONNA
M_G_CPU0_SA_CB<4>        J14              58       SCONN288_ADR50001P003C01-SCONNA
M_G_CPU0_SA_CB<4>        U2               DK57     SOCKET4677_AZIFS054P001C01-SOCA
M_G_CPU0_SA_CB<5>        J13              60       SCONN288_ADR50001P013C01-SCONNA
M_G_CPU0_SA_CB<5>        J14              60       SCONN288_ADR50001P003C01-SCONNA
M_G_CPU0_SA_CB<5>        U2               DL56     SOCKET4677_AZIFS054P001C01-SOCA
M_G_CPU0_SA_CB<6>        J13              203      SCONN288_ADR50001P013C01-SCONNA
M_G_CPU0_SA_CB<6>        J14              203      SCONN288_ADR50001P003C01-SCONNA
M_G_CPU0_SA_CB<6>        U2               DP57     SOCKET4677_AZIFS054P001C01-SOCA
M_G_CPU0_SA_CB<7>        J13              205      SCONN288_ADR50001P013C01-SCONNA
M_G_CPU0_SA_CB<7>        J14              205      SCONN288_ADR50001P003C01-SCONNA
M_G_CPU0_SA_CB<7>        U2               DN56     SOCKET4677_AZIFS054P001C01-SOCA
M_G_CPU0_SA_CS_N<0>      J13              64       SCONN288_ADR50001P013C01-SCONNA
M_G_CPU0_SA_CS_N<0>      U2               DN54     SOCKET4677_AZIFS054P001C01-SOCA
M_G_CPU0_SA_CS_N<1>      J13              209      SCONN288_ADR50001P013C01-SCONNA
M_G_CPU0_SA_CS_N<1>      U2               DP53     SOCKET4677_AZIFS054P001C01-SOCA
M_G_CPU0_SA_CS_N<2>      J14              64       SCONN288_ADR50001P003C01-SCONNA
M_G_CPU0_SA_CS_N<2>      U2               DL54     SOCKET4677_AZIFS054P001C01-SOCA
M_G_CPU0_SA_CS_N<3>      J14              209      SCONN288_ADR50001P003C01-SCONNA
M_G_CPU0_SA_CS_N<3>      U2               DK53     SOCKET4677_AZIFS054P001C01-SOCA
M_G_CPU0_SA_DQ<0>        J13              7        SCONN288_ADR50001P013C01-SCONNA
M_G_CPU0_SA_DQ<0>        J14              7        SCONN288_ADR50001P003C01-SCONNA
M_G_CPU0_SA_DQ<0>        U2               DV75     SOCKET4677_AZIFS054P001C01-SOCA
M_G_CPU0_SA_DQ<1>        J13              9        SCONN288_ADR50001P013C01-SCONNA
M_G_CPU0_SA_DQ<1>        J14              9        SCONN288_ADR50001P003C01-SCONNA
M_G_CPU0_SA_DQ<1>        U2               DU74     SOCKET4677_AZIFS054P001C01-SOCA
M_G_CPU0_SA_DQ<2>        J13              152      SCONN288_ADR50001P013C01-SCONNA
M_G_CPU0_SA_DQ<2>        J14              152      SCONN288_ADR50001P003C01-SCONNA
M_G_CPU0_SA_DQ<2>        U2               DY75     SOCKET4677_AZIFS054P001C01-SOCA
M_G_CPU0_SA_DQ<3>        J13              154      SCONN288_ADR50001P013C01-SCONNA
M_G_CPU0_SA_DQ<3>        J14              154      SCONN288_ADR50001P003C01-SCONNA
M_G_CPU0_SA_DQ<3>        U2               EA74     SOCKET4677_AZIFS054P001C01-SOCA
M_G_CPU0_SA_DQ<4>        J13              14       SCONN288_ADR50001P013C01-SCONNA
M_G_CPU0_SA_DQ<4>        J14              14       SCONN288_ADR50001P003C01-SCONNA
M_G_CPU0_SA_DQ<4>        U2               DU72     SOCKET4677_AZIFS054P001C01-SOCA
M_G_CPU0_SA_DQ<5>        J13              16       SCONN288_ADR50001P013C01-SCONNA
M_G_CPU0_SA_DQ<5>        J14              16       SCONN288_ADR50001P003C01-SCONNA
M_G_CPU0_SA_DQ<5>        U2               DV71     SOCKET4677_AZIFS054P001C01-SOCA
M_G_CPU0_SA_DQ<6>        J13              159      SCONN288_ADR50001P013C01-SCONNA
M_G_CPU0_SA_DQ<6>        J14              159      SCONN288_ADR50001P003C01-SCONNA
M_G_CPU0_SA_DQ<6>        U2               EA72     SOCKET4677_AZIFS054P001C01-SOCA
M_G_CPU0_SA_DQ<7>        J13              161      SCONN288_ADR50001P013C01-SCONNA
M_G_CPU0_SA_DQ<7>        J14              161      SCONN288_ADR50001P003C01-SCONNA
M_G_CPU0_SA_DQ<7>        U2               DY71     SOCKET4677_AZIFS054P001C01-SOCA
M_G_CPU0_SA_DQ<8>        J13              18       SCONN288_ADR50001P013C01-SCONNA
M_G_CPU0_SA_DQ<8>        J14              18       SCONN288_ADR50001P003C01-SCONNA
M_G_CPU0_SA_DQ<8>        U2               DL72     SOCKET4677_AZIFS054P001C01-SOCA
M_G_CPU0_SA_DQ<9>        J13              20       SCONN288_ADR50001P013C01-SCONNA
M_G_CPU0_SA_DQ<9>        J14              20       SCONN288_ADR50001P003C01-SCONNA
M_G_CPU0_SA_DQ<9>        U2               DK71     SOCKET4677_AZIFS054P001C01-SOCA
M_G_CPU0_SA_DQ<10>       J13              163      SCONN288_ADR50001P013C01-SCONNA
M_G_CPU0_SA_DQ<10>       J14              163      SCONN288_ADR50001P003C01-SCONNA
M_G_CPU0_SA_DQ<10>       U2               DN72     SOCKET4677_AZIFS054P001C01-SOCA
M_G_CPU0_SA_DQ<11>       J13              165      SCONN288_ADR50001P013C01-SCONNA
M_G_CPU0_SA_DQ<11>       J14              165      SCONN288_ADR50001P003C01-SCONNA
M_G_CPU0_SA_DQ<11>       U2               DP71     SOCKET4677_AZIFS054P001C01-SOCA
M_G_CPU0_SA_DQ<12>       J13              25       SCONN288_ADR50001P013C01-SCONNA
M_G_CPU0_SA_DQ<12>       J14              25       SCONN288_ADR50001P003C01-SCONNA
M_G_CPU0_SA_DQ<12>       U2               DK69     SOCKET4677_AZIFS054P001C01-SOCA
M_G_CPU0_SA_DQ<13>       J13              27       SCONN288_ADR50001P013C01-SCONNA
M_G_CPU0_SA_DQ<13>       J14              27       SCONN288_ADR50001P003C01-SCONNA
M_G_CPU0_SA_DQ<13>       U2               DL68     SOCKET4677_AZIFS054P001C01-SOCA
M_G_CPU0_SA_DQ<14>       J13              170      SCONN288_ADR50001P013C01-SCONNA
M_G_CPU0_SA_DQ<14>       J14              170      SCONN288_ADR50001P003C01-SCONNA
M_G_CPU0_SA_DQ<14>       U2               DP69     SOCKET4677_AZIFS054P001C01-SOCA
M_G_CPU0_SA_DQ<15>       J13              172      SCONN288_ADR50001P013C01-SCONNA
M_G_CPU0_SA_DQ<15>       J14              172      SCONN288_ADR50001P003C01-SCONNA
M_G_CPU0_SA_DQ<15>       U2               DN68     SOCKET4677_AZIFS054P001C01-SOCA
M_G_CPU0_SA_DQ<16>       J13              29       SCONN288_ADR50001P013C01-SCONNA
M_G_CPU0_SA_DQ<16>       J14              29       SCONN288_ADR50001P003C01-SCONNA
M_G_CPU0_SA_DQ<16>       U2               DV63     SOCKET4677_AZIFS054P001C01-SOCA
M_G_CPU0_SA_DQ<17>       J13              31       SCONN288_ADR50001P013C01-SCONNA
M_G_CPU0_SA_DQ<17>       J14              31       SCONN288_ADR50001P003C01-SCONNA
M_G_CPU0_SA_DQ<17>       U2               DU62     SOCKET4677_AZIFS054P001C01-SOCA
M_G_CPU0_SA_DQ<18>       J13              174      SCONN288_ADR50001P013C01-SCONNA
M_G_CPU0_SA_DQ<18>       J14              174      SCONN288_ADR50001P003C01-SCONNA
M_G_CPU0_SA_DQ<18>       U2               DY63     SOCKET4677_AZIFS054P001C01-SOCA
M_G_CPU0_SA_DQ<19>       J13              176      SCONN288_ADR50001P013C01-SCONNA
M_G_CPU0_SA_DQ<19>       J14              176      SCONN288_ADR50001P003C01-SCONNA
M_G_CPU0_SA_DQ<19>       U2               EA62     SOCKET4677_AZIFS054P001C01-SOCA
M_G_CPU0_SA_DQ<20>       J13              36       SCONN288_ADR50001P013C01-SCONNA
M_G_CPU0_SA_DQ<20>       J14              36       SCONN288_ADR50001P003C01-SCONNA
M_G_CPU0_SA_DQ<20>       U2               DU60     SOCKET4677_AZIFS054P001C01-SOCA
M_G_CPU0_SA_DQ<21>       J13              38       SCONN288_ADR50001P013C01-SCONNA
M_G_CPU0_SA_DQ<21>       J14              38       SCONN288_ADR50001P003C01-SCONNA
M_G_CPU0_SA_DQ<21>       U2               DV59     SOCKET4677_AZIFS054P001C01-SOCA
M_G_CPU0_SA_DQ<22>       J13              181      SCONN288_ADR50001P013C01-SCONNA
M_G_CPU0_SA_DQ<22>       J14              181      SCONN288_ADR50001P003C01-SCONNA
M_G_CPU0_SA_DQ<22>       U2               EA60     SOCKET4677_AZIFS054P001C01-SOCA
M_G_CPU0_SA_DQ<23>       J13              183      SCONN288_ADR50001P013C01-SCONNA
M_G_CPU0_SA_DQ<23>       J14              183      SCONN288_ADR50001P003C01-SCONNA
M_G_CPU0_SA_DQ<23>       U2               DY59     SOCKET4677_AZIFS054P001C01-SOCA
M_G_CPU0_SA_DQ<24>       J13              40       SCONN288_ADR50001P013C01-SCONNA
M_G_CPU0_SA_DQ<24>       J14              40       SCONN288_ADR50001P003C01-SCONNA
M_G_CPU0_SA_DQ<24>       U2               DL66     SOCKET4677_AZIFS054P001C01-SOCA
M_G_CPU0_SA_DQ<25>       J13              42       SCONN288_ADR50001P013C01-SCONNA
M_G_CPU0_SA_DQ<25>       J14              42       SCONN288_ADR50001P003C01-SCONNA
M_G_CPU0_SA_DQ<25>       U2               DK65     SOCKET4677_AZIFS054P001C01-SOCA
M_G_CPU0_SA_DQ<26>       J13              185      SCONN288_ADR50001P013C01-SCONNA
M_G_CPU0_SA_DQ<26>       J14              185      SCONN288_ADR50001P003C01-SCONNA
M_G_CPU0_SA_DQ<26>       U2               DN66     SOCKET4677_AZIFS054P001C01-SOCA
M_G_CPU0_SA_DQ<27>       J13              187      SCONN288_ADR50001P013C01-SCONNA
M_G_CPU0_SA_DQ<27>       J14              187      SCONN288_ADR50001P003C01-SCONNA
M_G_CPU0_SA_DQ<27>       U2               DP65     SOCKET4677_AZIFS054P001C01-SOCA
M_G_CPU0_SA_DQ<28>       J13              47       SCONN288_ADR50001P013C01-SCONNA
M_G_CPU0_SA_DQ<28>       J14              47       SCONN288_ADR50001P003C01-SCONNA
M_G_CPU0_SA_DQ<28>       U2               DK63     SOCKET4677_AZIFS054P001C01-SOCA
M_G_CPU0_SA_DQ<29>       J13              49       SCONN288_ADR50001P013C01-SCONNA
M_G_CPU0_SA_DQ<29>       J14              49       SCONN288_ADR50001P003C01-SCONNA
M_G_CPU0_SA_DQ<29>       U2               DL62     SOCKET4677_AZIFS054P001C01-SOCA
M_G_CPU0_SA_DQ<30>       J13              192      SCONN288_ADR50001P013C01-SCONNA
M_G_CPU0_SA_DQ<30>       J14              192      SCONN288_ADR50001P003C01-SCONNA
M_G_CPU0_SA_DQ<30>       U2               DP63     SOCKET4677_AZIFS054P001C01-SOCA
M_G_CPU0_SA_DQ<31>       J13              194      SCONN288_ADR50001P013C01-SCONNA
M_G_CPU0_SA_DQ<31>       J14              194      SCONN288_ADR50001P003C01-SCONNA
M_G_CPU0_SA_DQ<31>       U2               DN62     SOCKET4677_AZIFS054P001C01-SOCA
M_G_CPU0_SA_DQS_DN<0>    J13              12       SCONN288_ADR50001P013C01-SCONNA
M_G_CPU0_SA_DQS_DN<0>    J14              12       SCONN288_ADR50001P003C01-SCONNA
M_G_CPU0_SA_DQS_DN<0>    U2               DV73     SOCKET4677_AZIFS054P001C01-SOCA
M_G_CPU0_SA_DQS_DN<1>    J13              23       SCONN288_ADR50001P013C01-SCONNA
M_G_CPU0_SA_DQS_DN<1>    J14              23       SCONN288_ADR50001P003C01-SCONNA
M_G_CPU0_SA_DQS_DN<1>    U2               DJ70     SOCKET4677_AZIFS054P001C01-SOCA
M_G_CPU0_SA_DQS_DN<2>    J13              34       SCONN288_ADR50001P013C01-SCONNA
M_G_CPU0_SA_DQS_DN<2>    J14              34       SCONN288_ADR50001P003C01-SCONNA
M_G_CPU0_SA_DQS_DN<2>    U2               DT61     SOCKET4677_AZIFS054P001C01-SOCA
M_G_CPU0_SA_DQS_DN<3>    J13              45       SCONN288_ADR50001P013C01-SCONNA
M_G_CPU0_SA_DQS_DN<3>    J14              45       SCONN288_ADR50001P003C01-SCONNA
M_G_CPU0_SA_DQS_DN<3>    U2               DL64     SOCKET4677_AZIFS054P001C01-SOCA
M_G_CPU0_SA_DQS_DN<4>    J13              56       SCONN288_ADR50001P013C01-SCONNA
M_G_CPU0_SA_DQS_DN<4>    J14              56       SCONN288_ADR50001P003C01-SCONNA
M_G_CPU0_SA_DQS_DN<4>    U2               DL58     SOCKET4677_AZIFS054P001C01-SOCA
M_G_CPU0_SA_DQS_DN<5>    J13              156      SCONN288_ADR50001P013C01-SCONNA
M_G_CPU0_SA_DQS_DN<5>    J14              156      SCONN288_ADR50001P003C01-SCONNA
M_G_CPU0_SA_DQS_DN<5>    U2               EB73     SOCKET4677_AZIFS054P001C01-SOCA
M_G_CPU0_SA_DQS_DN<6>    J13              167      SCONN288_ADR50001P013C01-SCONNA
M_G_CPU0_SA_DQS_DN<6>    J14              167      SCONN288_ADR50001P003C01-SCONNA
M_G_CPU0_SA_DQS_DN<6>    U2               DR70     SOCKET4677_AZIFS054P001C01-SOCA
M_G_CPU0_SA_DQS_DN<7>    J13              178      SCONN288_ADR50001P013C01-SCONNA
M_G_CPU0_SA_DQS_DN<7>    J14              178      SCONN288_ADR50001P003C01-SCONNA
M_G_CPU0_SA_DQS_DN<7>    U2               EB61     SOCKET4677_AZIFS054P001C01-SOCA
M_G_CPU0_SA_DQS_DN<8>    J13              189      SCONN288_ADR50001P013C01-SCONNA
M_G_CPU0_SA_DQS_DN<8>    J14              189      SCONN288_ADR50001P003C01-SCONNA
M_G_CPU0_SA_DQS_DN<8>    U2               DR64     SOCKET4677_AZIFS054P001C01-SOCA
M_G_CPU0_SA_DQS_DN<9>    J13              200      SCONN288_ADR50001P013C01-SCONNA
M_G_CPU0_SA_DQS_DN<9>    J14              200      SCONN288_ADR50001P003C01-SCONNA
M_G_CPU0_SA_DQS_DN<9>    U2               DR58     SOCKET4677_AZIFS054P001C01-SOCA
M_G_CPU0_SA_DQS_DP<0>    J13              11       SCONN288_ADR50001P013C01-SCONNA
M_G_CPU0_SA_DQS_DP<0>    J14              11       SCONN288_ADR50001P003C01-SCONNA
M_G_CPU0_SA_DQS_DP<0>    U2               DT73     SOCKET4677_AZIFS054P001C01-SOCA
M_G_CPU0_SA_DQS_DP<1>    J13              22       SCONN288_ADR50001P013C01-SCONNA
M_G_CPU0_SA_DQS_DP<1>    J14              22       SCONN288_ADR50001P003C01-SCONNA
M_G_CPU0_SA_DQS_DP<1>    U2               DL70     SOCKET4677_AZIFS054P001C01-SOCA
M_G_CPU0_SA_DQS_DP<2>    J13              33       SCONN288_ADR50001P013C01-SCONNA
M_G_CPU0_SA_DQS_DP<2>    J14              33       SCONN288_ADR50001P003C01-SCONNA
M_G_CPU0_SA_DQS_DP<2>    U2               DV61     SOCKET4677_AZIFS054P001C01-SOCA
M_G_CPU0_SA_DQS_DP<3>    J13              44       SCONN288_ADR50001P013C01-SCONNA
M_G_CPU0_SA_DQS_DP<3>    J14              44       SCONN288_ADR50001P003C01-SCONNA
M_G_CPU0_SA_DQS_DP<3>    U2               DJ64     SOCKET4677_AZIFS054P001C01-SOCA
M_G_CPU0_SA_DQS_DP<4>    J13              55       SCONN288_ADR50001P013C01-SCONNA
M_G_CPU0_SA_DQS_DP<4>    J14              55       SCONN288_ADR50001P003C01-SCONNA
M_G_CPU0_SA_DQS_DP<4>    U2               DJ58     SOCKET4677_AZIFS054P001C01-SOCA
M_G_CPU0_SA_DQS_DP<5>    J13              157      SCONN288_ADR50001P013C01-SCONNA
M_G_CPU0_SA_DQS_DP<5>    J14              157      SCONN288_ADR50001P003C01-SCONNA
M_G_CPU0_SA_DQS_DP<5>    U2               DY73     SOCKET4677_AZIFS054P001C01-SOCA
M_G_CPU0_SA_DQS_DP<6>    J13              168      SCONN288_ADR50001P013C01-SCONNA
M_G_CPU0_SA_DQS_DP<6>    J14              168      SCONN288_ADR50001P003C01-SCONNA
M_G_CPU0_SA_DQS_DP<6>    U2               DN70     SOCKET4677_AZIFS054P001C01-SOCA
M_G_CPU0_SA_DQS_DP<7>    J13              179      SCONN288_ADR50001P013C01-SCONNA
M_G_CPU0_SA_DQS_DP<7>    J14              179      SCONN288_ADR50001P003C01-SCONNA
M_G_CPU0_SA_DQS_DP<7>    U2               DY61     SOCKET4677_AZIFS054P001C01-SOCA
M_G_CPU0_SA_DQS_DP<8>    J13              190      SCONN288_ADR50001P013C01-SCONNA
M_G_CPU0_SA_DQS_DP<8>    J14              190      SCONN288_ADR50001P003C01-SCONNA
M_G_CPU0_SA_DQS_DP<8>    U2               DN64     SOCKET4677_AZIFS054P001C01-SOCA
M_G_CPU0_SA_DQS_DP<9>    J13              201      SCONN288_ADR50001P013C01-SCONNA
M_G_CPU0_SA_DQS_DP<9>    J14              201      SCONN288_ADR50001P003C01-SCONNA
M_G_CPU0_SA_DQS_DP<9>    U2               DN58     SOCKET4677_AZIFS054P001C01-SOCA
M_G_CPU0_SA_PAR          J13              74       SCONN288_ADR50001P013C01-SCONNA
M_G_CPU0_SA_PAR          J14              74       SCONN288_ADR50001P003C01-SCONNA
M_G_CPU0_SA_PAR          U2               DL43     SOCKET4677_AZIFS054P001C01-SOCA
M_G_CPU0_SA_RSP<0>       J13              86       SCONN288_ADR50001P013C01-SCONNA
M_G_CPU0_SA_RSP<0>       U2               EA48     SOCKET4677_AZIFS054P001C01-SOCA
M_G_CPU0_SA_RSP<1>       J14              86       SCONN288_ADR50001P003C01-SCONNA
M_G_CPU0_SA_RSP<1>       U2               DY47     SOCKET4677_AZIFS054P001C01-SOCA
M_G_CPU0_SB_CA<0>        J13              76       SCONN288_ADR50001P013C01-SCONNA
M_G_CPU0_SB_CA<0>        J14              76       SCONN288_ADR50001P003C01-SCONNA
M_G_CPU0_SB_CA<0>        U2               DN43     SOCKET4677_AZIFS054P001C01-SOCA
M_G_CPU0_SB_CA<1>        J13              221      SCONN288_ADR50001P013C01-SCONNA
M_G_CPU0_SB_CA<1>        J14              221      SCONN288_ADR50001P003C01-SCONNA
M_G_CPU0_SB_CA<1>        U2               DP44     SOCKET4677_AZIFS054P001C01-SOCA
M_G_CPU0_SB_CA<2>        J13              78       SCONN288_ADR50001P013C01-SCONNA
M_G_CPU0_SB_CA<2>        J14              78       SCONN288_ADR50001P003C01-SCONNA
M_G_CPU0_SB_CA<2>        U2               DV44     SOCKET4677_AZIFS054P001C01-SOCA
M_G_CPU0_SB_CA<3>        J13              223      SCONN288_ADR50001P013C01-SCONNA
M_G_CPU0_SB_CA<3>        J14              223      SCONN288_ADR50001P003C01-SCONNA
M_G_CPU0_SB_CA<3>        U2               DY44     SOCKET4677_AZIFS054P001C01-SOCA
M_G_CPU0_SB_CA<4>        J13              80       SCONN288_ADR50001P013C01-SCONNA
M_G_CPU0_SB_CA<4>        J14              80       SCONN288_ADR50001P003C01-SCONNA
M_G_CPU0_SB_CA<4>        U2               DU43     SOCKET4677_AZIFS054P001C01-SOCA
M_G_CPU0_SB_CA<5>        J13              225      SCONN288_ADR50001P013C01-SCONNA
M_G_CPU0_SB_CA<5>        J14              225      SCONN288_ADR50001P003C01-SCONNA
M_G_CPU0_SB_CA<5>        U2               EA43     SOCKET4677_AZIFS054P001C01-SOCA
M_G_CPU0_SB_CA<6>        J13              82       SCONN288_ADR50001P013C01-SCONNA
M_G_CPU0_SB_CA<6>        J14              82       SCONN288_ADR50001P003C01-SCONNA
M_G_CPU0_SB_CA<6>        U2               DT42     SOCKET4677_AZIFS054P001C01-SOCA
M_G_CPU0_SB_CB<0>        J13              96       SCONN288_ADR50001P013C01-SCONNA
M_G_CPU0_SB_CB<0>        J14              96       SCONN288_ADR50001P003C01-SCONNA
M_G_CPU0_SB_CB<0>        U2               DU35     SOCKET4677_AZIFS054P001C01-SOCA
M_G_CPU0_SB_CB<1>        J13              98       SCONN288_ADR50001P013C01-SCONNA
M_G_CPU0_SB_CB<1>        J14              98       SCONN288_ADR50001P003C01-SCONNA
M_G_CPU0_SB_CB<1>        U2               DV34     SOCKET4677_AZIFS054P001C01-SOCA
M_G_CPU0_SB_CB<2>        J13              241      SCONN288_ADR50001P013C01-SCONNA
M_G_CPU0_SB_CB<2>        J14              241      SCONN288_ADR50001P003C01-SCONNA
M_G_CPU0_SB_CB<2>        U2               EA35     SOCKET4677_AZIFS054P001C01-SOCA
M_G_CPU0_SB_CB<3>        J13              243      SCONN288_ADR50001P013C01-SCONNA
M_G_CPU0_SB_CB<3>        J14              243      SCONN288_ADR50001P003C01-SCONNA
M_G_CPU0_SB_CB<3>        U2               DY34     SOCKET4677_AZIFS054P001C01-SOCA
M_G_CPU0_SB_CB<4>        J13              89       SCONN288_ADR50001P013C01-SCONNA
M_G_CPU0_SB_CB<4>        J14              89       SCONN288_ADR50001P003C01-SCONNA
M_G_CPU0_SB_CB<4>        U2               DV38     SOCKET4677_AZIFS054P001C01-SOCA
M_G_CPU0_SB_CB<5>        J13              91       SCONN288_ADR50001P013C01-SCONNA
M_G_CPU0_SB_CB<5>        J14              91       SCONN288_ADR50001P003C01-SCONNA
M_G_CPU0_SB_CB<5>        U2               DU37     SOCKET4677_AZIFS054P001C01-SOCA
M_G_CPU0_SB_CB<6>        J13              234      SCONN288_ADR50001P013C01-SCONNA
M_G_CPU0_SB_CB<6>        J14              234      SCONN288_ADR50001P003C01-SCONNA
M_G_CPU0_SB_CB<6>        U2               DY38     SOCKET4677_AZIFS054P001C01-SOCA
M_G_CPU0_SB_CB<7>        J13              236      SCONN288_ADR50001P013C01-SCONNA
M_G_CPU0_SB_CB<7>        J14              236      SCONN288_ADR50001P003C01-SCONNA
M_G_CPU0_SB_CB<7>        U2               EA37     SOCKET4677_AZIFS054P001C01-SOCA
M_G_CPU0_SB_CS_N<0>      J13              84       SCONN288_ADR50001P013C01-SCONNA
M_G_CPU0_SB_CS_N<0>      U2               EA41     SOCKET4677_AZIFS054P001C01-SOCA
M_G_CPU0_SB_CS_N<1>      J13              229      SCONN288_ADR50001P013C01-SCONNA
M_G_CPU0_SB_CS_N<1>      U2               DY40     SOCKET4677_AZIFS054P001C01-SOCA
M_G_CPU0_SB_CS_N<2>      J14              84       SCONN288_ADR50001P003C01-SCONNA
M_G_CPU0_SB_CS_N<2>      U2               DU41     SOCKET4677_AZIFS054P001C01-SOCA
M_G_CPU0_SB_CS_N<3>      J14              229      SCONN288_ADR50001P003C01-SCONNA
M_G_CPU0_SB_CS_N<3>      U2               DV40     SOCKET4677_AZIFS054P001C01-SOCA
M_G_CPU0_SB_DQ<0>        J13              100      SCONN288_ADR50001P013C01-SCONNA
M_G_CPU0_SB_DQ<0>        J14              100      SCONN288_ADR50001P003C01-SCONNA
M_G_CPU0_SB_DQ<0>        U2               DL35     SOCKET4677_AZIFS054P001C01-SOCA
M_G_CPU0_SB_DQ<1>        J13              102      SCONN288_ADR50001P013C01-SCONNA
M_G_CPU0_SB_DQ<1>        J14              102      SCONN288_ADR50001P003C01-SCONNA
M_G_CPU0_SB_DQ<1>        U2               DK34     SOCKET4677_AZIFS054P001C01-SOCA
M_G_CPU0_SB_DQ<2>        J13              245      SCONN288_ADR50001P013C01-SCONNA
M_G_CPU0_SB_DQ<2>        J14              245      SCONN288_ADR50001P003C01-SCONNA
M_G_CPU0_SB_DQ<2>        U2               DN35     SOCKET4677_AZIFS054P001C01-SOCA
M_G_CPU0_SB_DQ<3>        J13              247      SCONN288_ADR50001P013C01-SCONNA
M_G_CPU0_SB_DQ<3>        J14              247      SCONN288_ADR50001P003C01-SCONNA
M_G_CPU0_SB_DQ<3>        U2               DP34     SOCKET4677_AZIFS054P001C01-SOCA
M_G_CPU0_SB_DQ<4>        J13              107      SCONN288_ADR50001P013C01-SCONNA
M_G_CPU0_SB_DQ<4>        J14              107      SCONN288_ADR50001P003C01-SCONNA
M_G_CPU0_SB_DQ<4>        U2               DK32     SOCKET4677_AZIFS054P001C01-SOCA
M_G_CPU0_SB_DQ<5>        J13              109      SCONN288_ADR50001P013C01-SCONNA
M_G_CPU0_SB_DQ<5>        J14              109      SCONN288_ADR50001P003C01-SCONNA
M_G_CPU0_SB_DQ<5>        U2               DL31     SOCKET4677_AZIFS054P001C01-SOCA
M_G_CPU0_SB_DQ<6>        J13              252      SCONN288_ADR50001P013C01-SCONNA
M_G_CPU0_SB_DQ<6>        J14              252      SCONN288_ADR50001P003C01-SCONNA
M_G_CPU0_SB_DQ<6>        U2               DP32     SOCKET4677_AZIFS054P001C01-SOCA
M_G_CPU0_SB_DQ<7>        J13              254      SCONN288_ADR50001P013C01-SCONNA
M_G_CPU0_SB_DQ<7>        J14              254      SCONN288_ADR50001P003C01-SCONNA
M_G_CPU0_SB_DQ<7>        U2               DN31     SOCKET4677_AZIFS054P001C01-SOCA
M_G_CPU0_SB_DQ<8>        J13              111      SCONN288_ADR50001P013C01-SCONNA
M_G_CPU0_SB_DQ<8>        J14              111      SCONN288_ADR50001P003C01-SCONNA
M_G_CPU0_SB_DQ<8>        U2               DN29     SOCKET4677_AZIFS054P001C01-SOCA
M_G_CPU0_SB_DQ<9>        J13              113      SCONN288_ADR50001P013C01-SCONNA
M_G_CPU0_SB_DQ<9>        J14              113      SCONN288_ADR50001P003C01-SCONNA
M_G_CPU0_SB_DQ<9>        U2               DK28     SOCKET4677_AZIFS054P001C01-SOCA
M_G_CPU0_SB_DQ<10>       J13              256      SCONN288_ADR50001P013C01-SCONNA
M_G_CPU0_SB_DQ<10>       J14              256      SCONN288_ADR50001P003C01-SCONNA
M_G_CPU0_SB_DQ<10>       U2               DL29     SOCKET4677_AZIFS054P001C01-SOCA
M_G_CPU0_SB_DQ<11>       J13              258      SCONN288_ADR50001P013C01-SCONNA
M_G_CPU0_SB_DQ<11>       J14              258      SCONN288_ADR50001P003C01-SCONNA
M_G_CPU0_SB_DQ<11>       U2               DP28     SOCKET4677_AZIFS054P001C01-SOCA
M_G_CPU0_SB_DQ<12>       J13              118      SCONN288_ADR50001P013C01-SCONNA
M_G_CPU0_SB_DQ<12>       J14              118      SCONN288_ADR50001P003C01-SCONNA
M_G_CPU0_SB_DQ<12>       U2               DK26     SOCKET4677_AZIFS054P001C01-SOCA
M_G_CPU0_SB_DQ<13>       J13              120      SCONN288_ADR50001P013C01-SCONNA
M_G_CPU0_SB_DQ<13>       J14              120      SCONN288_ADR50001P003C01-SCONNA
M_G_CPU0_SB_DQ<13>       U2               DL25     SOCKET4677_AZIFS054P001C01-SOCA
M_G_CPU0_SB_DQ<14>       J13              263      SCONN288_ADR50001P013C01-SCONNA
M_G_CPU0_SB_DQ<14>       J14              263      SCONN288_ADR50001P003C01-SCONNA
M_G_CPU0_SB_DQ<14>       U2               DP26     SOCKET4677_AZIFS054P001C01-SOCA
M_G_CPU0_SB_DQ<15>       J13              265      SCONN288_ADR50001P013C01-SCONNA
M_G_CPU0_SB_DQ<15>       J14              265      SCONN288_ADR50001P003C01-SCONNA
M_G_CPU0_SB_DQ<15>       U2               DN25     SOCKET4677_AZIFS054P001C01-SOCA
M_G_CPU0_SB_DQ<16>       J13              122      SCONN288_ADR50001P013C01-SCONNA
M_G_CPU0_SB_DQ<16>       J14              122      SCONN288_ADR50001P003C01-SCONNA
M_G_CPU0_SB_DQ<16>       U2               DV26     SOCKET4677_AZIFS054P001C01-SOCA
M_G_CPU0_SB_DQ<17>       J13              124      SCONN288_ADR50001P013C01-SCONNA
M_G_CPU0_SB_DQ<17>       J14              124      SCONN288_ADR50001P003C01-SCONNA
M_G_CPU0_SB_DQ<17>       U2               DU25     SOCKET4677_AZIFS054P001C01-SOCA
M_G_CPU0_SB_DQ<18>       J13              267      SCONN288_ADR50001P013C01-SCONNA
M_G_CPU0_SB_DQ<18>       J14              267      SCONN288_ADR50001P003C01-SCONNA
M_G_CPU0_SB_DQ<18>       U2               DY26     SOCKET4677_AZIFS054P001C01-SOCA
M_G_CPU0_SB_DQ<19>       J13              269      SCONN288_ADR50001P013C01-SCONNA
M_G_CPU0_SB_DQ<19>       J14              269      SCONN288_ADR50001P003C01-SCONNA
M_G_CPU0_SB_DQ<19>       U2               EA25     SOCKET4677_AZIFS054P001C01-SOCA
M_G_CPU0_SB_DQ<20>       J13              129      SCONN288_ADR50001P013C01-SCONNA
M_G_CPU0_SB_DQ<20>       J14              129      SCONN288_ADR50001P003C01-SCONNA
M_G_CPU0_SB_DQ<20>       U2               DU23     SOCKET4677_AZIFS054P001C01-SOCA
M_G_CPU0_SB_DQ<21>       J13              131      SCONN288_ADR50001P013C01-SCONNA
M_G_CPU0_SB_DQ<21>       J14              131      SCONN288_ADR50001P003C01-SCONNA
M_G_CPU0_SB_DQ<21>       U2               DV22     SOCKET4677_AZIFS054P001C01-SOCA
M_G_CPU0_SB_DQ<22>       J13              274      SCONN288_ADR50001P013C01-SCONNA
M_G_CPU0_SB_DQ<22>       J14              274      SCONN288_ADR50001P003C01-SCONNA
M_G_CPU0_SB_DQ<22>       U2               EA23     SOCKET4677_AZIFS054P001C01-SOCA
M_G_CPU0_SB_DQ<23>       J13              276      SCONN288_ADR50001P013C01-SCONNA
M_G_CPU0_SB_DQ<23>       J14              276      SCONN288_ADR50001P003C01-SCONNA
M_G_CPU0_SB_DQ<23>       U2               DY22     SOCKET4677_AZIFS054P001C01-SOCA
M_G_CPU0_SB_DQ<24>       J13              133      SCONN288_ADR50001P013C01-SCONNA
M_G_CPU0_SB_DQ<24>       J14              133      SCONN288_ADR50001P003C01-SCONNA
M_G_CPU0_SB_DQ<24>       U2               EK8      SOCKET4677_AZIFS054P001C01-SOCA
M_G_CPU0_SB_DQ<25>       J13              135      SCONN288_ADR50001P013C01-SCONNA
M_G_CPU0_SB_DQ<25>       J14              135      SCONN288_ADR50001P003C01-SCONNA
M_G_CPU0_SB_DQ<25>       U2               EH8      SOCKET4677_AZIFS054P001C01-SOCA
M_G_CPU0_SB_DQ<26>       J13              278      SCONN288_ADR50001P013C01-SCONNA
M_G_CPU0_SB_DQ<26>       J14              278      SCONN288_ADR50001P003C01-SCONNA
M_G_CPU0_SB_DQ<26>       U2               EP8      SOCKET4677_AZIFS054P001C01-SOCA
M_G_CPU0_SB_DQ<27>       J13              280      SCONN288_ADR50001P013C01-SCONNA
M_G_CPU0_SB_DQ<27>       J14              280      SCONN288_ADR50001P003C01-SCONNA
M_G_CPU0_SB_DQ<27>       U2               ET8      SOCKET4677_AZIFS054P001C01-SOCA
M_G_CPU0_SB_DQ<28>       J13              140      SCONN288_ADR50001P013C01-SCONNA
M_G_CPU0_SB_DQ<28>       J14              140      SCONN288_ADR50001P003C01-SCONNA
M_G_CPU0_SB_DQ<28>       U2               EK6      SOCKET4677_AZIFS054P001C01-SOCA
M_G_CPU0_SB_DQ<29>       J13              142      SCONN288_ADR50001P013C01-SCONNA
M_G_CPU0_SB_DQ<29>       J14              142      SCONN288_ADR50001P003C01-SCONNA
M_G_CPU0_SB_DQ<29>       U2               EJ5      SOCKET4677_AZIFS054P001C01-SOCA
M_G_CPU0_SB_DQ<30>       J13              285      SCONN288_ADR50001P013C01-SCONNA
M_G_CPU0_SB_DQ<30>       J14              285      SCONN288_ADR50001P003C01-SCONNA
M_G_CPU0_SB_DQ<30>       U2               EP4      SOCKET4677_AZIFS054P001C01-SOCA
M_G_CPU0_SB_DQ<31>       J13              287      SCONN288_ADR50001P013C01-SCONNA
M_G_CPU0_SB_DQ<31>       J14              287      SCONN288_ADR50001P003C01-SCONNA
M_G_CPU0_SB_DQ<31>       U2               EM4      SOCKET4677_AZIFS054P001C01-SOCA
M_G_CPU0_SB_DQS_DN<0>    J13              105      SCONN288_ADR50001P013C01-SCONNA
M_G_CPU0_SB_DQS_DN<0>    J14              105      SCONN288_ADR50001P003C01-SCONNA
M_G_CPU0_SB_DQS_DN<0>    U2               DJ33     SOCKET4677_AZIFS054P001C01-SOCA
M_G_CPU0_SB_DQS_DN<1>    J13              116      SCONN288_ADR50001P013C01-SCONNA
M_G_CPU0_SB_DQS_DN<1>    J14              116      SCONN288_ADR50001P003C01-SCONNA
M_G_CPU0_SB_DQS_DN<1>    U2               DJ27     SOCKET4677_AZIFS054P001C01-SOCA
M_G_CPU0_SB_DQS_DN<2>    J13              127      SCONN288_ADR50001P013C01-SCONNA
M_G_CPU0_SB_DQS_DN<2>    J14              127      SCONN288_ADR50001P003C01-SCONNA
M_G_CPU0_SB_DQS_DN<2>    U2               DV24     SOCKET4677_AZIFS054P001C01-SOCA
M_G_CPU0_SB_DQS_DN<3>    J13              138      SCONN288_ADR50001P013C01-SCONNA
M_G_CPU0_SB_DQS_DN<3>    J14              138      SCONN288_ADR50001P003C01-SCONNA
M_G_CPU0_SB_DQS_DN<3>    U2               EP6      SOCKET4677_AZIFS054P001C01-SOCA
M_G_CPU0_SB_DQS_DN<4>    J13              238      SCONN288_ADR50001P013C01-SCONNA
M_G_CPU0_SB_DQS_DN<4>    J14              238      SCONN288_ADR50001P003C01-SCONNA
M_G_CPU0_SB_DQS_DN<4>    U2               EB36     SOCKET4677_AZIFS054P001C01-SOCA
M_G_CPU0_SB_DQS_DN<5>    J13              249      SCONN288_ADR50001P013C01-SCONNA
M_G_CPU0_SB_DQS_DN<5>    J14              249      SCONN288_ADR50001P003C01-SCONNA
M_G_CPU0_SB_DQS_DN<5>    U2               DR33     SOCKET4677_AZIFS054P001C01-SOCA
M_G_CPU0_SB_DQS_DN<6>    J13              260      SCONN288_ADR50001P013C01-SCONNA
M_G_CPU0_SB_DQS_DN<6>    J14              260      SCONN288_ADR50001P003C01-SCONNA
M_G_CPU0_SB_DQS_DN<6>    U2               DN27     SOCKET4677_AZIFS054P001C01-SOCA
M_G_CPU0_SB_DQS_DN<7>    J13              271      SCONN288_ADR50001P013C01-SCONNA
M_G_CPU0_SB_DQS_DN<7>    J14              271      SCONN288_ADR50001P003C01-SCONNA
M_G_CPU0_SB_DQS_DN<7>    U2               EB24     SOCKET4677_AZIFS054P001C01-SOCA
M_G_CPU0_SB_DQS_DN<8>    J13              282      SCONN288_ADR50001P013C01-SCONNA
M_G_CPU0_SB_DQS_DN<8>    J14              282      SCONN288_ADR50001P003C01-SCONNA
M_G_CPU0_SB_DQS_DN<8>    U2               EM6      SOCKET4677_AZIFS054P001C01-SOCA
M_G_CPU0_SB_DQS_DN<9>    J13              94       SCONN288_ADR50001P013C01-SCONNA
M_G_CPU0_SB_DQS_DN<9>    J14              94       SCONN288_ADR50001P003C01-SCONNA
M_G_CPU0_SB_DQS_DN<9>    U2               DV36     SOCKET4677_AZIFS054P001C01-SOCA
M_G_CPU0_SB_DQS_DP<0>    J13              104      SCONN288_ADR50001P013C01-SCONNA
M_G_CPU0_SB_DQS_DP<0>    J14              104      SCONN288_ADR50001P003C01-SCONNA
M_G_CPU0_SB_DQS_DP<0>    U2               DL33     SOCKET4677_AZIFS054P001C01-SOCA
M_G_CPU0_SB_DQS_DP<1>    J13              115      SCONN288_ADR50001P013C01-SCONNA
M_G_CPU0_SB_DQS_DP<1>    J14              115      SCONN288_ADR50001P003C01-SCONNA
M_G_CPU0_SB_DQS_DP<1>    U2               DL27     SOCKET4677_AZIFS054P001C01-SOCA
M_G_CPU0_SB_DQS_DP<2>    J13              126      SCONN288_ADR50001P013C01-SCONNA
M_G_CPU0_SB_DQS_DP<2>    J14              126      SCONN288_ADR50001P003C01-SCONNA
M_G_CPU0_SB_DQS_DP<2>    U2               DT24     SOCKET4677_AZIFS054P001C01-SOCA
M_G_CPU0_SB_DQS_DP<3>    J13              137      SCONN288_ADR50001P013C01-SCONNA
M_G_CPU0_SB_DQS_DP<3>    J14              137      SCONN288_ADR50001P003C01-SCONNA
M_G_CPU0_SB_DQS_DP<3>    U2               EN7      SOCKET4677_AZIFS054P001C01-SOCA
M_G_CPU0_SB_DQS_DP<4>    J13              239      SCONN288_ADR50001P013C01-SCONNA
M_G_CPU0_SB_DQS_DP<4>    J14              239      SCONN288_ADR50001P003C01-SCONNA
M_G_CPU0_SB_DQS_DP<4>    U2               DY36     SOCKET4677_AZIFS054P001C01-SOCA
M_G_CPU0_SB_DQS_DP<5>    J13              250      SCONN288_ADR50001P013C01-SCONNA
M_G_CPU0_SB_DQS_DP<5>    J14              250      SCONN288_ADR50001P003C01-SCONNA
M_G_CPU0_SB_DQS_DP<5>    U2               DN33     SOCKET4677_AZIFS054P001C01-SOCA
M_G_CPU0_SB_DQS_DP<6>    J13              261      SCONN288_ADR50001P013C01-SCONNA
M_G_CPU0_SB_DQS_DP<6>    J14              261      SCONN288_ADR50001P003C01-SCONNA
M_G_CPU0_SB_DQS_DP<6>    U2               DR27     SOCKET4677_AZIFS054P001C01-SOCA
M_G_CPU0_SB_DQS_DP<7>    J13              272      SCONN288_ADR50001P013C01-SCONNA
M_G_CPU0_SB_DQS_DP<7>    J14              272      SCONN288_ADR50001P003C01-SCONNA
M_G_CPU0_SB_DQS_DP<7>    U2               DY24     SOCKET4677_AZIFS054P001C01-SOCA
M_G_CPU0_SB_DQS_DP<8>    J13              283      SCONN288_ADR50001P013C01-SCONNA
M_G_CPU0_SB_DQS_DP<8>    J14              283      SCONN288_ADR50001P003C01-SCONNA
M_G_CPU0_SB_DQS_DP<8>    U2               EN5      SOCKET4677_AZIFS054P001C01-SOCA
M_G_CPU0_SB_DQS_DP<9>    J13              93       SCONN288_ADR50001P013C01-SCONNA
M_G_CPU0_SB_DQS_DP<9>    J14              93       SCONN288_ADR50001P003C01-SCONNA
M_G_CPU0_SB_DQS_DP<9>    U2               DT36     SOCKET4677_AZIFS054P001C01-SOCA
M_G_CPU0_SB_PAR          J13              227      SCONN288_ADR50001P013C01-SCONNA
M_G_CPU0_SB_PAR          J14              227      SCONN288_ADR50001P003C01-SCONNA
M_G_CPU0_SB_PAR          U2               EB42     SOCKET4677_AZIFS054P001C01-SOCA
M_G_CPU0_SB_RSP<0>       J13              87       SCONN288_ADR50001P013C01-SCONNA
M_G_CPU0_SB_RSP<0>       U2               DU48     SOCKET4677_AZIFS054P001C01-SOCA
M_G_CPU0_SB_RSP<1>       J14              87       SCONN288_ADR50001P003C01-SCONNA
M_G_CPU0_SB_RSP<1>       U2               DV47     SOCKET4677_AZIFS054P001C01-SOCA
M_G_CPU1_ALERT_N         J29              62       SCONN288_ADR50001P013C01-SCONNA
M_G_CPU1_ALERT_N         J30              62       SCONN288_ADR50001P003C01-SCONNA
M_G_CPU1_ALERT_N         U1               CW50     SOCKET4677_AZIFS054P001C01-SOCA
M_G_CPU1_CLK_DN<0>       J29              218      SCONN288_ADR50001P013C01-SCONNA
M_G_CPU1_CLK_DN<0>       U1               DR45     SOCKET4677_AZIFS054P001C01-SOCA
M_G_CPU1_CLK_DN<1>       J30              218      SCONN288_ADR50001P003C01-SCONNA
M_G_CPU1_CLK_DN<1>       U1               DL45     SOCKET4677_AZIFS054P001C01-SOCA
M_G_CPU1_CLK_DP<0>       J29              217      SCONN288_ADR50001P013C01-SCONNA
M_G_CPU1_CLK_DP<0>       U1               DN45     SOCKET4677_AZIFS054P001C01-SOCA
M_G_CPU1_CLK_DP<1>       J30              217      SCONN288_ADR50001P003C01-SCONNA
M_G_CPU1_CLK_DP<1>       U1               DJ45     SOCKET4677_AZIFS054P001C01-SOCA
M_G_CPU1_SA_CA<0>        J29              66       SCONN288_ADR50001P013C01-SCONNA
M_G_CPU1_SA_CA<0>        J30              66       SCONN288_ADR50001P003C01-SCONNA
M_G_CPU1_SA_CA<0>        U1               DJ52     SOCKET4677_AZIFS054P001C01-SOCA
M_G_CPU1_SA_CA<1>        J29              211      SCONN288_ADR50001P013C01-SCONNA
M_G_CPU1_SA_CA<1>        J30              211      SCONN288_ADR50001P003C01-SCONNA
M_G_CPU1_SA_CA<1>        U1               DR52     SOCKET4677_AZIFS054P001C01-SOCA
M_G_CPU1_SA_CA<2>        J29              68       SCONN288_ADR50001P013C01-SCONNA
M_G_CPU1_SA_CA<2>        J30              68       SCONN288_ADR50001P003C01-SCONNA
M_G_CPU1_SA_CA<2>        U1               DK51     SOCKET4677_AZIFS054P001C01-SOCA
M_G_CPU1_SA_CA<3>        J29              213      SCONN288_ADR50001P013C01-SCONNA
M_G_CPU1_SA_CA<3>        J30              213      SCONN288_ADR50001P003C01-SCONNA
M_G_CPU1_SA_CA<3>        U1               DP51     SOCKET4677_AZIFS054P001C01-SOCA
M_G_CPU1_SA_CA<4>        J29              70       SCONN288_ADR50001P013C01-SCONNA
M_G_CPU1_SA_CA<4>        J30              70       SCONN288_ADR50001P003C01-SCONNA
M_G_CPU1_SA_CA<4>        U1               DL50     SOCKET4677_AZIFS054P001C01-SOCA
M_G_CPU1_SA_CA<5>        J29              215      SCONN288_ADR50001P013C01-SCONNA
M_G_CPU1_SA_CA<5>        J30              215      SCONN288_ADR50001P003C01-SCONNA
M_G_CPU1_SA_CA<5>        U1               DN50     SOCKET4677_AZIFS054P001C01-SOCA
M_G_CPU1_SA_CA<6>        J29              72       SCONN288_ADR50001P013C01-SCONNA
M_G_CPU1_SA_CA<6>        J30              72       SCONN288_ADR50001P003C01-SCONNA
M_G_CPU1_SA_CA<6>        U1               DK44     SOCKET4677_AZIFS054P001C01-SOCA
M_G_CPU1_SA_CB<0>        J29              51       SCONN288_ADR50001P013C01-SCONNA
M_G_CPU1_SA_CB<0>        J30              51       SCONN288_ADR50001P003C01-SCONNA
M_G_CPU1_SA_CB<0>        U1               DL60     SOCKET4677_AZIFS054P001C01-SOCA
M_G_CPU1_SA_CB<1>        J29              53       SCONN288_ADR50001P013C01-SCONNA
M_G_CPU1_SA_CB<1>        J30              53       SCONN288_ADR50001P003C01-SCONNA
M_G_CPU1_SA_CB<1>        U1               DK59     SOCKET4677_AZIFS054P001C01-SOCA
M_G_CPU1_SA_CB<2>        J29              196      SCONN288_ADR50001P013C01-SCONNA
M_G_CPU1_SA_CB<2>        J30              196      SCONN288_ADR50001P003C01-SCONNA
M_G_CPU1_SA_CB<2>        U1               DN60     SOCKET4677_AZIFS054P001C01-SOCA
M_G_CPU1_SA_CB<3>        J29              198      SCONN288_ADR50001P013C01-SCONNA
M_G_CPU1_SA_CB<3>        J30              198      SCONN288_ADR50001P003C01-SCONNA
M_G_CPU1_SA_CB<3>        U1               DP59     SOCKET4677_AZIFS054P001C01-SOCA
M_G_CPU1_SA_CB<4>        J29              58       SCONN288_ADR50001P013C01-SCONNA
M_G_CPU1_SA_CB<4>        J30              58       SCONN288_ADR50001P003C01-SCONNA
M_G_CPU1_SA_CB<4>        U1               DK57     SOCKET4677_AZIFS054P001C01-SOCA
M_G_CPU1_SA_CB<5>        J29              60       SCONN288_ADR50001P013C01-SCONNA
M_G_CPU1_SA_CB<5>        J30              60       SCONN288_ADR50001P003C01-SCONNA
M_G_CPU1_SA_CB<5>        U1               DL56     SOCKET4677_AZIFS054P001C01-SOCA
M_G_CPU1_SA_CB<6>        J29              203      SCONN288_ADR50001P013C01-SCONNA
M_G_CPU1_SA_CB<6>        J30              203      SCONN288_ADR50001P003C01-SCONNA
M_G_CPU1_SA_CB<6>        U1               DP57     SOCKET4677_AZIFS054P001C01-SOCA
M_G_CPU1_SA_CB<7>        J29              205      SCONN288_ADR50001P013C01-SCONNA
M_G_CPU1_SA_CB<7>        J30              205      SCONN288_ADR50001P003C01-SCONNA
M_G_CPU1_SA_CB<7>        U1               DN56     SOCKET4677_AZIFS054P001C01-SOCA
M_G_CPU1_SA_CS_N<0>      J29              64       SCONN288_ADR50001P013C01-SCONNA
M_G_CPU1_SA_CS_N<0>      U1               DN54     SOCKET4677_AZIFS054P001C01-SOCA
M_G_CPU1_SA_CS_N<1>      J29              209      SCONN288_ADR50001P013C01-SCONNA
M_G_CPU1_SA_CS_N<1>      U1               DP53     SOCKET4677_AZIFS054P001C01-SOCA
M_G_CPU1_SA_CS_N<2>      J30              64       SCONN288_ADR50001P003C01-SCONNA
M_G_CPU1_SA_CS_N<2>      U1               DL54     SOCKET4677_AZIFS054P001C01-SOCA
M_G_CPU1_SA_CS_N<3>      J30              209      SCONN288_ADR50001P003C01-SCONNA
M_G_CPU1_SA_CS_N<3>      U1               DK53     SOCKET4677_AZIFS054P001C01-SOCA
M_G_CPU1_SA_DQ<0>        J29              7        SCONN288_ADR50001P013C01-SCONNA
M_G_CPU1_SA_DQ<0>        J30              7        SCONN288_ADR50001P003C01-SCONNA
M_G_CPU1_SA_DQ<0>        U1               DV75     SOCKET4677_AZIFS054P001C01-SOCA
M_G_CPU1_SA_DQ<1>        J29              9        SCONN288_ADR50001P013C01-SCONNA
M_G_CPU1_SA_DQ<1>        J30              9        SCONN288_ADR50001P003C01-SCONNA
M_G_CPU1_SA_DQ<1>        U1               DU74     SOCKET4677_AZIFS054P001C01-SOCA
M_G_CPU1_SA_DQ<2>        J29              152      SCONN288_ADR50001P013C01-SCONNA
M_G_CPU1_SA_DQ<2>        J30              152      SCONN288_ADR50001P003C01-SCONNA
M_G_CPU1_SA_DQ<2>        U1               DY75     SOCKET4677_AZIFS054P001C01-SOCA
M_G_CPU1_SA_DQ<3>        J29              154      SCONN288_ADR50001P013C01-SCONNA
M_G_CPU1_SA_DQ<3>        J30              154      SCONN288_ADR50001P003C01-SCONNA
M_G_CPU1_SA_DQ<3>        U1               EA74     SOCKET4677_AZIFS054P001C01-SOCA
M_G_CPU1_SA_DQ<4>        J29              14       SCONN288_ADR50001P013C01-SCONNA
M_G_CPU1_SA_DQ<4>        J30              14       SCONN288_ADR50001P003C01-SCONNA
M_G_CPU1_SA_DQ<4>        U1               DU72     SOCKET4677_AZIFS054P001C01-SOCA
M_G_CPU1_SA_DQ<5>        J29              16       SCONN288_ADR50001P013C01-SCONNA
M_G_CPU1_SA_DQ<5>        J30              16       SCONN288_ADR50001P003C01-SCONNA
M_G_CPU1_SA_DQ<5>        U1               DV71     SOCKET4677_AZIFS054P001C01-SOCA
M_G_CPU1_SA_DQ<6>        J29              159      SCONN288_ADR50001P013C01-SCONNA
M_G_CPU1_SA_DQ<6>        J30              159      SCONN288_ADR50001P003C01-SCONNA
M_G_CPU1_SA_DQ<6>        U1               EA72     SOCKET4677_AZIFS054P001C01-SOCA
M_G_CPU1_SA_DQ<7>        J29              161      SCONN288_ADR50001P013C01-SCONNA
M_G_CPU1_SA_DQ<7>        J30              161      SCONN288_ADR50001P003C01-SCONNA
M_G_CPU1_SA_DQ<7>        U1               DY71     SOCKET4677_AZIFS054P001C01-SOCA
M_G_CPU1_SA_DQ<8>        J29              18       SCONN288_ADR50001P013C01-SCONNA
M_G_CPU1_SA_DQ<8>        J30              18       SCONN288_ADR50001P003C01-SCONNA
M_G_CPU1_SA_DQ<8>        U1               DL72     SOCKET4677_AZIFS054P001C01-SOCA
M_G_CPU1_SA_DQ<9>        J29              20       SCONN288_ADR50001P013C01-SCONNA
M_G_CPU1_SA_DQ<9>        J30              20       SCONN288_ADR50001P003C01-SCONNA
M_G_CPU1_SA_DQ<9>        U1               DK71     SOCKET4677_AZIFS054P001C01-SOCA
M_G_CPU1_SA_DQ<10>       J29              163      SCONN288_ADR50001P013C01-SCONNA
M_G_CPU1_SA_DQ<10>       J30              163      SCONN288_ADR50001P003C01-SCONNA
M_G_CPU1_SA_DQ<10>       U1               DN72     SOCKET4677_AZIFS054P001C01-SOCA
M_G_CPU1_SA_DQ<11>       J29              165      SCONN288_ADR50001P013C01-SCONNA
M_G_CPU1_SA_DQ<11>       J30              165      SCONN288_ADR50001P003C01-SCONNA
M_G_CPU1_SA_DQ<11>       U1               DP71     SOCKET4677_AZIFS054P001C01-SOCA
M_G_CPU1_SA_DQ<12>       J29              25       SCONN288_ADR50001P013C01-SCONNA
M_G_CPU1_SA_DQ<12>       J30              25       SCONN288_ADR50001P003C01-SCONNA
M_G_CPU1_SA_DQ<12>       U1               DK69     SOCKET4677_AZIFS054P001C01-SOCA
M_G_CPU1_SA_DQ<13>       J29              27       SCONN288_ADR50001P013C01-SCONNA
M_G_CPU1_SA_DQ<13>       J30              27       SCONN288_ADR50001P003C01-SCONNA
M_G_CPU1_SA_DQ<13>       U1               DL68     SOCKET4677_AZIFS054P001C01-SOCA
M_G_CPU1_SA_DQ<14>       J29              170      SCONN288_ADR50001P013C01-SCONNA
M_G_CPU1_SA_DQ<14>       J30              170      SCONN288_ADR50001P003C01-SCONNA
M_G_CPU1_SA_DQ<14>       U1               DP69     SOCKET4677_AZIFS054P001C01-SOCA
M_G_CPU1_SA_DQ<15>       J29              172      SCONN288_ADR50001P013C01-SCONNA
M_G_CPU1_SA_DQ<15>       J30              172      SCONN288_ADR50001P003C01-SCONNA
M_G_CPU1_SA_DQ<15>       U1               DN68     SOCKET4677_AZIFS054P001C01-SOCA
M_G_CPU1_SA_DQ<16>       J29              29       SCONN288_ADR50001P013C01-SCONNA
M_G_CPU1_SA_DQ<16>       J30              29       SCONN288_ADR50001P003C01-SCONNA
M_G_CPU1_SA_DQ<16>       U1               DV63     SOCKET4677_AZIFS054P001C01-SOCA
M_G_CPU1_SA_DQ<17>       J29              31       SCONN288_ADR50001P013C01-SCONNA
M_G_CPU1_SA_DQ<17>       J30              31       SCONN288_ADR50001P003C01-SCONNA
M_G_CPU1_SA_DQ<17>       U1               DU62     SOCKET4677_AZIFS054P001C01-SOCA
M_G_CPU1_SA_DQ<18>       J29              174      SCONN288_ADR50001P013C01-SCONNA
M_G_CPU1_SA_DQ<18>       J30              174      SCONN288_ADR50001P003C01-SCONNA
M_G_CPU1_SA_DQ<18>       U1               DY63     SOCKET4677_AZIFS054P001C01-SOCA
M_G_CPU1_SA_DQ<19>       J29              176      SCONN288_ADR50001P013C01-SCONNA
M_G_CPU1_SA_DQ<19>       J30              176      SCONN288_ADR50001P003C01-SCONNA
M_G_CPU1_SA_DQ<19>       U1               EA62     SOCKET4677_AZIFS054P001C01-SOCA
M_G_CPU1_SA_DQ<20>       J29              36       SCONN288_ADR50001P013C01-SCONNA
M_G_CPU1_SA_DQ<20>       J30              36       SCONN288_ADR50001P003C01-SCONNA
M_G_CPU1_SA_DQ<20>       U1               DU60     SOCKET4677_AZIFS054P001C01-SOCA
M_G_CPU1_SA_DQ<21>       J29              38       SCONN288_ADR50001P013C01-SCONNA
M_G_CPU1_SA_DQ<21>       J30              38       SCONN288_ADR50001P003C01-SCONNA
M_G_CPU1_SA_DQ<21>       U1               DV59     SOCKET4677_AZIFS054P001C01-SOCA
M_G_CPU1_SA_DQ<22>       J29              181      SCONN288_ADR50001P013C01-SCONNA
M_G_CPU1_SA_DQ<22>       J30              181      SCONN288_ADR50001P003C01-SCONNA
M_G_CPU1_SA_DQ<22>       U1               EA60     SOCKET4677_AZIFS054P001C01-SOCA
M_G_CPU1_SA_DQ<23>       J29              183      SCONN288_ADR50001P013C01-SCONNA
M_G_CPU1_SA_DQ<23>       J30              183      SCONN288_ADR50001P003C01-SCONNA
M_G_CPU1_SA_DQ<23>       U1               DY59     SOCKET4677_AZIFS054P001C01-SOCA
M_G_CPU1_SA_DQ<24>       J29              40       SCONN288_ADR50001P013C01-SCONNA
M_G_CPU1_SA_DQ<24>       J30              40       SCONN288_ADR50001P003C01-SCONNA
M_G_CPU1_SA_DQ<24>       U1               DL66     SOCKET4677_AZIFS054P001C01-SOCA
M_G_CPU1_SA_DQ<25>       J29              42       SCONN288_ADR50001P013C01-SCONNA
M_G_CPU1_SA_DQ<25>       J30              42       SCONN288_ADR50001P003C01-SCONNA
M_G_CPU1_SA_DQ<25>       U1               DK65     SOCKET4677_AZIFS054P001C01-SOCA
M_G_CPU1_SA_DQ<26>       J29              185      SCONN288_ADR50001P013C01-SCONNA
M_G_CPU1_SA_DQ<26>       J30              185      SCONN288_ADR50001P003C01-SCONNA
M_G_CPU1_SA_DQ<26>       U1               DN66     SOCKET4677_AZIFS054P001C01-SOCA
M_G_CPU1_SA_DQ<27>       J29              187      SCONN288_ADR50001P013C01-SCONNA
M_G_CPU1_SA_DQ<27>       J30              187      SCONN288_ADR50001P003C01-SCONNA
M_G_CPU1_SA_DQ<27>       U1               DP65     SOCKET4677_AZIFS054P001C01-SOCA
M_G_CPU1_SA_DQ<28>       J29              47       SCONN288_ADR50001P013C01-SCONNA
M_G_CPU1_SA_DQ<28>       J30              47       SCONN288_ADR50001P003C01-SCONNA
M_G_CPU1_SA_DQ<28>       U1               DK63     SOCKET4677_AZIFS054P001C01-SOCA
M_G_CPU1_SA_DQ<29>       J29              49       SCONN288_ADR50001P013C01-SCONNA
M_G_CPU1_SA_DQ<29>       J30              49       SCONN288_ADR50001P003C01-SCONNA
M_G_CPU1_SA_DQ<29>       U1               DL62     SOCKET4677_AZIFS054P001C01-SOCA
M_G_CPU1_SA_DQ<30>       J29              192      SCONN288_ADR50001P013C01-SCONNA
M_G_CPU1_SA_DQ<30>       J30              192      SCONN288_ADR50001P003C01-SCONNA
M_G_CPU1_SA_DQ<30>       U1               DP63     SOCKET4677_AZIFS054P001C01-SOCA
M_G_CPU1_SA_DQ<31>       J29              194      SCONN288_ADR50001P013C01-SCONNA
M_G_CPU1_SA_DQ<31>       J30              194      SCONN288_ADR50001P003C01-SCONNA
M_G_CPU1_SA_DQ<31>       U1               DN62     SOCKET4677_AZIFS054P001C01-SOCA
M_G_CPU1_SA_DQS_DN<0>    J29              12       SCONN288_ADR50001P013C01-SCONNA
M_G_CPU1_SA_DQS_DN<0>    J30              12       SCONN288_ADR50001P003C01-SCONNA
M_G_CPU1_SA_DQS_DN<0>    U1               DV73     SOCKET4677_AZIFS054P001C01-SOCA
M_G_CPU1_SA_DQS_DN<1>    J29              23       SCONN288_ADR50001P013C01-SCONNA
M_G_CPU1_SA_DQS_DN<1>    J30              23       SCONN288_ADR50001P003C01-SCONNA
M_G_CPU1_SA_DQS_DN<1>    U1               DJ70     SOCKET4677_AZIFS054P001C01-SOCA
M_G_CPU1_SA_DQS_DN<2>    J29              34       SCONN288_ADR50001P013C01-SCONNA
M_G_CPU1_SA_DQS_DN<2>    J30              34       SCONN288_ADR50001P003C01-SCONNA
M_G_CPU1_SA_DQS_DN<2>    U1               DT61     SOCKET4677_AZIFS054P001C01-SOCA
M_G_CPU1_SA_DQS_DN<3>    J29              45       SCONN288_ADR50001P013C01-SCONNA
M_G_CPU1_SA_DQS_DN<3>    J30              45       SCONN288_ADR50001P003C01-SCONNA
M_G_CPU1_SA_DQS_DN<3>    U1               DL64     SOCKET4677_AZIFS054P001C01-SOCA
M_G_CPU1_SA_DQS_DN<4>    J29              56       SCONN288_ADR50001P013C01-SCONNA
M_G_CPU1_SA_DQS_DN<4>    J30              56       SCONN288_ADR50001P003C01-SCONNA
M_G_CPU1_SA_DQS_DN<4>    U1               DL58     SOCKET4677_AZIFS054P001C01-SOCA
M_G_CPU1_SA_DQS_DN<5>    J29              156      SCONN288_ADR50001P013C01-SCONNA
M_G_CPU1_SA_DQS_DN<5>    J30              156      SCONN288_ADR50001P003C01-SCONNA
M_G_CPU1_SA_DQS_DN<5>    U1               EB73     SOCKET4677_AZIFS054P001C01-SOCA
M_G_CPU1_SA_DQS_DN<6>    J29              167      SCONN288_ADR50001P013C01-SCONNA
M_G_CPU1_SA_DQS_DN<6>    J30              167      SCONN288_ADR50001P003C01-SCONNA
M_G_CPU1_SA_DQS_DN<6>    U1               DR70     SOCKET4677_AZIFS054P001C01-SOCA
M_G_CPU1_SA_DQS_DN<7>    J29              178      SCONN288_ADR50001P013C01-SCONNA
M_G_CPU1_SA_DQS_DN<7>    J30              178      SCONN288_ADR50001P003C01-SCONNA
M_G_CPU1_SA_DQS_DN<7>    U1               EB61     SOCKET4677_AZIFS054P001C01-SOCA
M_G_CPU1_SA_DQS_DN<8>    J29              189      SCONN288_ADR50001P013C01-SCONNA
M_G_CPU1_SA_DQS_DN<8>    J30              189      SCONN288_ADR50001P003C01-SCONNA
M_G_CPU1_SA_DQS_DN<8>    U1               DR64     SOCKET4677_AZIFS054P001C01-SOCA
M_G_CPU1_SA_DQS_DN<9>    J29              200      SCONN288_ADR50001P013C01-SCONNA
M_G_CPU1_SA_DQS_DN<9>    J30              200      SCONN288_ADR50001P003C01-SCONNA
M_G_CPU1_SA_DQS_DN<9>    U1               DR58     SOCKET4677_AZIFS054P001C01-SOCA
M_G_CPU1_SA_DQS_DP<0>    J29              11       SCONN288_ADR50001P013C01-SCONNA
M_G_CPU1_SA_DQS_DP<0>    J30              11       SCONN288_ADR50001P003C01-SCONNA
M_G_CPU1_SA_DQS_DP<0>    U1               DT73     SOCKET4677_AZIFS054P001C01-SOCA
M_G_CPU1_SA_DQS_DP<1>    J29              22       SCONN288_ADR50001P013C01-SCONNA
M_G_CPU1_SA_DQS_DP<1>    J30              22       SCONN288_ADR50001P003C01-SCONNA
M_G_CPU1_SA_DQS_DP<1>    U1               DL70     SOCKET4677_AZIFS054P001C01-SOCA
M_G_CPU1_SA_DQS_DP<2>    J29              33       SCONN288_ADR50001P013C01-SCONNA
M_G_CPU1_SA_DQS_DP<2>    J30              33       SCONN288_ADR50001P003C01-SCONNA
M_G_CPU1_SA_DQS_DP<2>    U1               DV61     SOCKET4677_AZIFS054P001C01-SOCA
M_G_CPU1_SA_DQS_DP<3>    J29              44       SCONN288_ADR50001P013C01-SCONNA
M_G_CPU1_SA_DQS_DP<3>    J30              44       SCONN288_ADR50001P003C01-SCONNA
M_G_CPU1_SA_DQS_DP<3>    U1               DJ64     SOCKET4677_AZIFS054P001C01-SOCA
M_G_CPU1_SA_DQS_DP<4>    J29              55       SCONN288_ADR50001P013C01-SCONNA
M_G_CPU1_SA_DQS_DP<4>    J30              55       SCONN288_ADR50001P003C01-SCONNA
M_G_CPU1_SA_DQS_DP<4>    U1               DJ58     SOCKET4677_AZIFS054P001C01-SOCA
M_G_CPU1_SA_DQS_DP<5>    J29              157      SCONN288_ADR50001P013C01-SCONNA
M_G_CPU1_SA_DQS_DP<5>    J30              157      SCONN288_ADR50001P003C01-SCONNA
M_G_CPU1_SA_DQS_DP<5>    U1               DY73     SOCKET4677_AZIFS054P001C01-SOCA
M_G_CPU1_SA_DQS_DP<6>    J29              168      SCONN288_ADR50001P013C01-SCONNA
M_G_CPU1_SA_DQS_DP<6>    J30              168      SCONN288_ADR50001P003C01-SCONNA
M_G_CPU1_SA_DQS_DP<6>    U1               DN70     SOCKET4677_AZIFS054P001C01-SOCA
M_G_CPU1_SA_DQS_DP<7>    J29              179      SCONN288_ADR50001P013C01-SCONNA
M_G_CPU1_SA_DQS_DP<7>    J30              179      SCONN288_ADR50001P003C01-SCONNA
M_G_CPU1_SA_DQS_DP<7>    U1               DY61     SOCKET4677_AZIFS054P001C01-SOCA
M_G_CPU1_SA_DQS_DP<8>    J29              190      SCONN288_ADR50001P013C01-SCONNA
M_G_CPU1_SA_DQS_DP<8>    J30              190      SCONN288_ADR50001P003C01-SCONNA
M_G_CPU1_SA_DQS_DP<8>    U1               DN64     SOCKET4677_AZIFS054P001C01-SOCA
M_G_CPU1_SA_DQS_DP<9>    J29              201      SCONN288_ADR50001P013C01-SCONNA
M_G_CPU1_SA_DQS_DP<9>    J30              201      SCONN288_ADR50001P003C01-SCONNA
M_G_CPU1_SA_DQS_DP<9>    U1               DN58     SOCKET4677_AZIFS054P001C01-SOCA
M_G_CPU1_SA_PAR          J29              74       SCONN288_ADR50001P013C01-SCONNA
M_G_CPU1_SA_PAR          J30              74       SCONN288_ADR50001P003C01-SCONNA
M_G_CPU1_SA_PAR          U1               DL43     SOCKET4677_AZIFS054P001C01-SOCA
M_G_CPU1_SA_RSP<0>       J29              86       SCONN288_ADR50001P013C01-SCONNA
M_G_CPU1_SA_RSP<0>       U1               EA48     SOCKET4677_AZIFS054P001C01-SOCA
M_G_CPU1_SA_RSP<1>       J30              86       SCONN288_ADR50001P003C01-SCONNA
M_G_CPU1_SA_RSP<1>       U1               DY47     SOCKET4677_AZIFS054P001C01-SOCA
M_G_CPU1_SB_CA<0>        J29              76       SCONN288_ADR50001P013C01-SCONNA
M_G_CPU1_SB_CA<0>        J30              76       SCONN288_ADR50001P003C01-SCONNA
M_G_CPU1_SB_CA<0>        U1               DN43     SOCKET4677_AZIFS054P001C01-SOCA
M_G_CPU1_SB_CA<1>        J29              221      SCONN288_ADR50001P013C01-SCONNA
M_G_CPU1_SB_CA<1>        J30              221      SCONN288_ADR50001P003C01-SCONNA
M_G_CPU1_SB_CA<1>        U1               DP44     SOCKET4677_AZIFS054P001C01-SOCA
M_G_CPU1_SB_CA<2>        J29              78       SCONN288_ADR50001P013C01-SCONNA
M_G_CPU1_SB_CA<2>        J30              78       SCONN288_ADR50001P003C01-SCONNA
M_G_CPU1_SB_CA<2>        U1               DV44     SOCKET4677_AZIFS054P001C01-SOCA
M_G_CPU1_SB_CA<3>        J29              223      SCONN288_ADR50001P013C01-SCONNA
M_G_CPU1_SB_CA<3>        J30              223      SCONN288_ADR50001P003C01-SCONNA
M_G_CPU1_SB_CA<3>        U1               DY44     SOCKET4677_AZIFS054P001C01-SOCA
M_G_CPU1_SB_CA<4>        J29              80       SCONN288_ADR50001P013C01-SCONNA
M_G_CPU1_SB_CA<4>        J30              80       SCONN288_ADR50001P003C01-SCONNA
M_G_CPU1_SB_CA<4>        U1               DU43     SOCKET4677_AZIFS054P001C01-SOCA
M_G_CPU1_SB_CA<5>        J29              225      SCONN288_ADR50001P013C01-SCONNA
M_G_CPU1_SB_CA<5>        J30              225      SCONN288_ADR50001P003C01-SCONNA
M_G_CPU1_SB_CA<5>        U1               EA43     SOCKET4677_AZIFS054P001C01-SOCA
M_G_CPU1_SB_CA<6>        J29              82       SCONN288_ADR50001P013C01-SCONNA
M_G_CPU1_SB_CA<6>        J30              82       SCONN288_ADR50001P003C01-SCONNA
M_G_CPU1_SB_CA<6>        U1               DT42     SOCKET4677_AZIFS054P001C01-SOCA
M_G_CPU1_SB_CB<0>        J29              96       SCONN288_ADR50001P013C01-SCONNA
M_G_CPU1_SB_CB<0>        J30              96       SCONN288_ADR50001P003C01-SCONNA
M_G_CPU1_SB_CB<0>        U1               DU35     SOCKET4677_AZIFS054P001C01-SOCA
M_G_CPU1_SB_CB<1>        J29              98       SCONN288_ADR50001P013C01-SCONNA
M_G_CPU1_SB_CB<1>        J30              98       SCONN288_ADR50001P003C01-SCONNA
M_G_CPU1_SB_CB<1>        U1               DV34     SOCKET4677_AZIFS054P001C01-SOCA
M_G_CPU1_SB_CB<2>        J29              241      SCONN288_ADR50001P013C01-SCONNA
M_G_CPU1_SB_CB<2>        J30              241      SCONN288_ADR50001P003C01-SCONNA
M_G_CPU1_SB_CB<2>        U1               EA35     SOCKET4677_AZIFS054P001C01-SOCA
M_G_CPU1_SB_CB<3>        J29              243      SCONN288_ADR50001P013C01-SCONNA
M_G_CPU1_SB_CB<3>        J30              243      SCONN288_ADR50001P003C01-SCONNA
M_G_CPU1_SB_CB<3>        U1               DY34     SOCKET4677_AZIFS054P001C01-SOCA
M_G_CPU1_SB_CB<4>        J29              89       SCONN288_ADR50001P013C01-SCONNA
M_G_CPU1_SB_CB<4>        J30              89       SCONN288_ADR50001P003C01-SCONNA
M_G_CPU1_SB_CB<4>        U1               DV38     SOCKET4677_AZIFS054P001C01-SOCA
M_G_CPU1_SB_CB<5>        J29              91       SCONN288_ADR50001P013C01-SCONNA
M_G_CPU1_SB_CB<5>        J30              91       SCONN288_ADR50001P003C01-SCONNA
M_G_CPU1_SB_CB<5>        U1               DU37     SOCKET4677_AZIFS054P001C01-SOCA
M_G_CPU1_SB_CB<6>        J29              234      SCONN288_ADR50001P013C01-SCONNA
M_G_CPU1_SB_CB<6>        J30              234      SCONN288_ADR50001P003C01-SCONNA
M_G_CPU1_SB_CB<6>        U1               DY38     SOCKET4677_AZIFS054P001C01-SOCA
M_G_CPU1_SB_CB<7>        J29              236      SCONN288_ADR50001P013C01-SCONNA
M_G_CPU1_SB_CB<7>        J30              236      SCONN288_ADR50001P003C01-SCONNA
M_G_CPU1_SB_CB<7>        U1               EA37     SOCKET4677_AZIFS054P001C01-SOCA
M_G_CPU1_SB_CS_N<0>      J29              84       SCONN288_ADR50001P013C01-SCONNA
M_G_CPU1_SB_CS_N<0>      U1               EA41     SOCKET4677_AZIFS054P001C01-SOCA
M_G_CPU1_SB_CS_N<1>      J29              229      SCONN288_ADR50001P013C01-SCONNA
M_G_CPU1_SB_CS_N<1>      U1               DY40     SOCKET4677_AZIFS054P001C01-SOCA
M_G_CPU1_SB_CS_N<2>      J30              84       SCONN288_ADR50001P003C01-SCONNA
M_G_CPU1_SB_CS_N<2>      U1               DU41     SOCKET4677_AZIFS054P001C01-SOCA
M_G_CPU1_SB_CS_N<3>      J30              229      SCONN288_ADR50001P003C01-SCONNA
M_G_CPU1_SB_CS_N<3>      U1               DV40     SOCKET4677_AZIFS054P001C01-SOCA
M_G_CPU1_SB_DQ<0>        J29              100      SCONN288_ADR50001P013C01-SCONNA
M_G_CPU1_SB_DQ<0>        J30              100      SCONN288_ADR50001P003C01-SCONNA
M_G_CPU1_SB_DQ<0>        U1               DL35     SOCKET4677_AZIFS054P001C01-SOCA
M_G_CPU1_SB_DQ<1>        J29              102      SCONN288_ADR50001P013C01-SCONNA
M_G_CPU1_SB_DQ<1>        J30              102      SCONN288_ADR50001P003C01-SCONNA
M_G_CPU1_SB_DQ<1>        U1               DK34     SOCKET4677_AZIFS054P001C01-SOCA
M_G_CPU1_SB_DQ<2>        J29              245      SCONN288_ADR50001P013C01-SCONNA
M_G_CPU1_SB_DQ<2>        J30              245      SCONN288_ADR50001P003C01-SCONNA
M_G_CPU1_SB_DQ<2>        U1               DN35     SOCKET4677_AZIFS054P001C01-SOCA
M_G_CPU1_SB_DQ<3>        J29              247      SCONN288_ADR50001P013C01-SCONNA
M_G_CPU1_SB_DQ<3>        J30              247      SCONN288_ADR50001P003C01-SCONNA
M_G_CPU1_SB_DQ<3>        U1               DP34     SOCKET4677_AZIFS054P001C01-SOCA
M_G_CPU1_SB_DQ<4>        J29              107      SCONN288_ADR50001P013C01-SCONNA
M_G_CPU1_SB_DQ<4>        J30              107      SCONN288_ADR50001P003C01-SCONNA
M_G_CPU1_SB_DQ<4>        U1               DK32     SOCKET4677_AZIFS054P001C01-SOCA
M_G_CPU1_SB_DQ<5>        J29              109      SCONN288_ADR50001P013C01-SCONNA
M_G_CPU1_SB_DQ<5>        J30              109      SCONN288_ADR50001P003C01-SCONNA
M_G_CPU1_SB_DQ<5>        U1               DL31     SOCKET4677_AZIFS054P001C01-SOCA
M_G_CPU1_SB_DQ<6>        J29              252      SCONN288_ADR50001P013C01-SCONNA
M_G_CPU1_SB_DQ<6>        J30              252      SCONN288_ADR50001P003C01-SCONNA
M_G_CPU1_SB_DQ<6>        U1               DP32     SOCKET4677_AZIFS054P001C01-SOCA
M_G_CPU1_SB_DQ<7>        J29              254      SCONN288_ADR50001P013C01-SCONNA
M_G_CPU1_SB_DQ<7>        J30              254      SCONN288_ADR50001P003C01-SCONNA
M_G_CPU1_SB_DQ<7>        U1               DN31     SOCKET4677_AZIFS054P001C01-SOCA
M_G_CPU1_SB_DQ<8>        J29              111      SCONN288_ADR50001P013C01-SCONNA
M_G_CPU1_SB_DQ<8>        J30              111      SCONN288_ADR50001P003C01-SCONNA
M_G_CPU1_SB_DQ<8>        U1               DN29     SOCKET4677_AZIFS054P001C01-SOCA
M_G_CPU1_SB_DQ<9>        J29              113      SCONN288_ADR50001P013C01-SCONNA
M_G_CPU1_SB_DQ<9>        J30              113      SCONN288_ADR50001P003C01-SCONNA
M_G_CPU1_SB_DQ<9>        U1               DK28     SOCKET4677_AZIFS054P001C01-SOCA
M_G_CPU1_SB_DQ<10>       J29              256      SCONN288_ADR50001P013C01-SCONNA
M_G_CPU1_SB_DQ<10>       J30              256      SCONN288_ADR50001P003C01-SCONNA
M_G_CPU1_SB_DQ<10>       U1               DL29     SOCKET4677_AZIFS054P001C01-SOCA
M_G_CPU1_SB_DQ<11>       J29              258      SCONN288_ADR50001P013C01-SCONNA
M_G_CPU1_SB_DQ<11>       J30              258      SCONN288_ADR50001P003C01-SCONNA
M_G_CPU1_SB_DQ<11>       U1               DP28     SOCKET4677_AZIFS054P001C01-SOCA
M_G_CPU1_SB_DQ<12>       J29              118      SCONN288_ADR50001P013C01-SCONNA
M_G_CPU1_SB_DQ<12>       J30              118      SCONN288_ADR50001P003C01-SCONNA
M_G_CPU1_SB_DQ<12>       U1               DK26     SOCKET4677_AZIFS054P001C01-SOCA
M_G_CPU1_SB_DQ<13>       J29              120      SCONN288_ADR50001P013C01-SCONNA
M_G_CPU1_SB_DQ<13>       J30              120      SCONN288_ADR50001P003C01-SCONNA
M_G_CPU1_SB_DQ<13>       U1               DL25     SOCKET4677_AZIFS054P001C01-SOCA
M_G_CPU1_SB_DQ<14>       J29              263      SCONN288_ADR50001P013C01-SCONNA
M_G_CPU1_SB_DQ<14>       J30              263      SCONN288_ADR50001P003C01-SCONNA
M_G_CPU1_SB_DQ<14>       U1               DP26     SOCKET4677_AZIFS054P001C01-SOCA
M_G_CPU1_SB_DQ<15>       J29              265      SCONN288_ADR50001P013C01-SCONNA
M_G_CPU1_SB_DQ<15>       J30              265      SCONN288_ADR50001P003C01-SCONNA
M_G_CPU1_SB_DQ<15>       U1               DN25     SOCKET4677_AZIFS054P001C01-SOCA
M_G_CPU1_SB_DQ<16>       J29              122      SCONN288_ADR50001P013C01-SCONNA
M_G_CPU1_SB_DQ<16>       J30              122      SCONN288_ADR50001P003C01-SCONNA
M_G_CPU1_SB_DQ<16>       U1               DV26     SOCKET4677_AZIFS054P001C01-SOCA
M_G_CPU1_SB_DQ<17>       J29              124      SCONN288_ADR50001P013C01-SCONNA
M_G_CPU1_SB_DQ<17>       J30              124      SCONN288_ADR50001P003C01-SCONNA
M_G_CPU1_SB_DQ<17>       U1               DU25     SOCKET4677_AZIFS054P001C01-SOCA
M_G_CPU1_SB_DQ<18>       J29              267      SCONN288_ADR50001P013C01-SCONNA
M_G_CPU1_SB_DQ<18>       J30              267      SCONN288_ADR50001P003C01-SCONNA
M_G_CPU1_SB_DQ<18>       U1               DY26     SOCKET4677_AZIFS054P001C01-SOCA
M_G_CPU1_SB_DQ<19>       J29              269      SCONN288_ADR50001P013C01-SCONNA
M_G_CPU1_SB_DQ<19>       J30              269      SCONN288_ADR50001P003C01-SCONNA
M_G_CPU1_SB_DQ<19>       U1               EA25     SOCKET4677_AZIFS054P001C01-SOCA
M_G_CPU1_SB_DQ<20>       J29              129      SCONN288_ADR50001P013C01-SCONNA
M_G_CPU1_SB_DQ<20>       J30              129      SCONN288_ADR50001P003C01-SCONNA
M_G_CPU1_SB_DQ<20>       U1               DU23     SOCKET4677_AZIFS054P001C01-SOCA
M_G_CPU1_SB_DQ<21>       J29              131      SCONN288_ADR50001P013C01-SCONNA
M_G_CPU1_SB_DQ<21>       J30              131      SCONN288_ADR50001P003C01-SCONNA
M_G_CPU1_SB_DQ<21>       U1               DV22     SOCKET4677_AZIFS054P001C01-SOCA
M_G_CPU1_SB_DQ<22>       J29              274      SCONN288_ADR50001P013C01-SCONNA
M_G_CPU1_SB_DQ<22>       J30              274      SCONN288_ADR50001P003C01-SCONNA
M_G_CPU1_SB_DQ<22>       U1               EA23     SOCKET4677_AZIFS054P001C01-SOCA
M_G_CPU1_SB_DQ<23>       J29              276      SCONN288_ADR50001P013C01-SCONNA
M_G_CPU1_SB_DQ<23>       J30              276      SCONN288_ADR50001P003C01-SCONNA
M_G_CPU1_SB_DQ<23>       U1               DY22     SOCKET4677_AZIFS054P001C01-SOCA
M_G_CPU1_SB_DQ<24>       J29              133      SCONN288_ADR50001P013C01-SCONNA
M_G_CPU1_SB_DQ<24>       J30              133      SCONN288_ADR50001P003C01-SCONNA
M_G_CPU1_SB_DQ<24>       U1               EK8      SOCKET4677_AZIFS054P001C01-SOCA
M_G_CPU1_SB_DQ<25>       J29              135      SCONN288_ADR50001P013C01-SCONNA
M_G_CPU1_SB_DQ<25>       J30              135      SCONN288_ADR50001P003C01-SCONNA
M_G_CPU1_SB_DQ<25>       U1               EH8      SOCKET4677_AZIFS054P001C01-SOCA
M_G_CPU1_SB_DQ<26>       J29              278      SCONN288_ADR50001P013C01-SCONNA
M_G_CPU1_SB_DQ<26>       J30              278      SCONN288_ADR50001P003C01-SCONNA
M_G_CPU1_SB_DQ<26>       U1               EP8      SOCKET4677_AZIFS054P001C01-SOCA
M_G_CPU1_SB_DQ<27>       J29              280      SCONN288_ADR50001P013C01-SCONNA
M_G_CPU1_SB_DQ<27>       J30              280      SCONN288_ADR50001P003C01-SCONNA
M_G_CPU1_SB_DQ<27>       U1               ET8      SOCKET4677_AZIFS054P001C01-SOCA
M_G_CPU1_SB_DQ<28>       J29              140      SCONN288_ADR50001P013C01-SCONNA
M_G_CPU1_SB_DQ<28>       J30              140      SCONN288_ADR50001P003C01-SCONNA
M_G_CPU1_SB_DQ<28>       U1               EK6      SOCKET4677_AZIFS054P001C01-SOCA
M_G_CPU1_SB_DQ<29>       J29              142      SCONN288_ADR50001P013C01-SCONNA
M_G_CPU1_SB_DQ<29>       J30              142      SCONN288_ADR50001P003C01-SCONNA
M_G_CPU1_SB_DQ<29>       U1               EJ5      SOCKET4677_AZIFS054P001C01-SOCA
M_G_CPU1_SB_DQ<30>       J29              285      SCONN288_ADR50001P013C01-SCONNA
M_G_CPU1_SB_DQ<30>       J30              285      SCONN288_ADR50001P003C01-SCONNA
M_G_CPU1_SB_DQ<30>       U1               EP4      SOCKET4677_AZIFS054P001C01-SOCA
M_G_CPU1_SB_DQ<31>       J29              287      SCONN288_ADR50001P013C01-SCONNA
M_G_CPU1_SB_DQ<31>       J30              287      SCONN288_ADR50001P003C01-SCONNA
M_G_CPU1_SB_DQ<31>       U1               EM4      SOCKET4677_AZIFS054P001C01-SOCA
M_G_CPU1_SB_DQS_DN<0>    J29              105      SCONN288_ADR50001P013C01-SCONNA
M_G_CPU1_SB_DQS_DN<0>    J30              105      SCONN288_ADR50001P003C01-SCONNA
M_G_CPU1_SB_DQS_DN<0>    U1               DJ33     SOCKET4677_AZIFS054P001C01-SOCA
M_G_CPU1_SB_DQS_DN<1>    J29              116      SCONN288_ADR50001P013C01-SCONNA
M_G_CPU1_SB_DQS_DN<1>    J30              116      SCONN288_ADR50001P003C01-SCONNA
M_G_CPU1_SB_DQS_DN<1>    U1               DJ27     SOCKET4677_AZIFS054P001C01-SOCA
M_G_CPU1_SB_DQS_DN<2>    J29              127      SCONN288_ADR50001P013C01-SCONNA
M_G_CPU1_SB_DQS_DN<2>    J30              127      SCONN288_ADR50001P003C01-SCONNA
M_G_CPU1_SB_DQS_DN<2>    U1               DV24     SOCKET4677_AZIFS054P001C01-SOCA
M_G_CPU1_SB_DQS_DN<3>    J29              138      SCONN288_ADR50001P013C01-SCONNA
M_G_CPU1_SB_DQS_DN<3>    J30              138      SCONN288_ADR50001P003C01-SCONNA
M_G_CPU1_SB_DQS_DN<3>    U1               EP6      SOCKET4677_AZIFS054P001C01-SOCA
M_G_CPU1_SB_DQS_DN<4>    J29              238      SCONN288_ADR50001P013C01-SCONNA
M_G_CPU1_SB_DQS_DN<4>    J30              238      SCONN288_ADR50001P003C01-SCONNA
M_G_CPU1_SB_DQS_DN<4>    U1               EB36     SOCKET4677_AZIFS054P001C01-SOCA
M_G_CPU1_SB_DQS_DN<5>    J29              249      SCONN288_ADR50001P013C01-SCONNA
M_G_CPU1_SB_DQS_DN<5>    J30              249      SCONN288_ADR50001P003C01-SCONNA
M_G_CPU1_SB_DQS_DN<5>    U1               DR33     SOCKET4677_AZIFS054P001C01-SOCA
M_G_CPU1_SB_DQS_DN<6>    J29              260      SCONN288_ADR50001P013C01-SCONNA
M_G_CPU1_SB_DQS_DN<6>    J30              260      SCONN288_ADR50001P003C01-SCONNA
M_G_CPU1_SB_DQS_DN<6>    U1               DN27     SOCKET4677_AZIFS054P001C01-SOCA
M_G_CPU1_SB_DQS_DN<7>    J29              271      SCONN288_ADR50001P013C01-SCONNA
M_G_CPU1_SB_DQS_DN<7>    J30              271      SCONN288_ADR50001P003C01-SCONNA
M_G_CPU1_SB_DQS_DN<7>    U1               EB24     SOCKET4677_AZIFS054P001C01-SOCA
M_G_CPU1_SB_DQS_DN<8>    J29              282      SCONN288_ADR50001P013C01-SCONNA
M_G_CPU1_SB_DQS_DN<8>    J30              282      SCONN288_ADR50001P003C01-SCONNA
M_G_CPU1_SB_DQS_DN<8>    U1               EM6      SOCKET4677_AZIFS054P001C01-SOCA
M_G_CPU1_SB_DQS_DN<9>    J29              94       SCONN288_ADR50001P013C01-SCONNA
M_G_CPU1_SB_DQS_DN<9>    J30              94       SCONN288_ADR50001P003C01-SCONNA
M_G_CPU1_SB_DQS_DN<9>    U1               DV36     SOCKET4677_AZIFS054P001C01-SOCA
M_G_CPU1_SB_DQS_DP<0>    J29              104      SCONN288_ADR50001P013C01-SCONNA
M_G_CPU1_SB_DQS_DP<0>    J30              104      SCONN288_ADR50001P003C01-SCONNA
M_G_CPU1_SB_DQS_DP<0>    U1               DL33     SOCKET4677_AZIFS054P001C01-SOCA
M_G_CPU1_SB_DQS_DP<1>    J29              115      SCONN288_ADR50001P013C01-SCONNA
M_G_CPU1_SB_DQS_DP<1>    J30              115      SCONN288_ADR50001P003C01-SCONNA
M_G_CPU1_SB_DQS_DP<1>    U1               DL27     SOCKET4677_AZIFS054P001C01-SOCA
M_G_CPU1_SB_DQS_DP<2>    J29              126      SCONN288_ADR50001P013C01-SCONNA
M_G_CPU1_SB_DQS_DP<2>    J30              126      SCONN288_ADR50001P003C01-SCONNA
M_G_CPU1_SB_DQS_DP<2>    U1               DT24     SOCKET4677_AZIFS054P001C01-SOCA
M_G_CPU1_SB_DQS_DP<3>    J29              137      SCONN288_ADR50001P013C01-SCONNA
M_G_CPU1_SB_DQS_DP<3>    J30              137      SCONN288_ADR50001P003C01-SCONNA
M_G_CPU1_SB_DQS_DP<3>    U1               EN7      SOCKET4677_AZIFS054P001C01-SOCA
M_G_CPU1_SB_DQS_DP<4>    J29              239      SCONN288_ADR50001P013C01-SCONNA
M_G_CPU1_SB_DQS_DP<4>    J30              239      SCONN288_ADR50001P003C01-SCONNA
M_G_CPU1_SB_DQS_DP<4>    U1               DY36     SOCKET4677_AZIFS054P001C01-SOCA
M_G_CPU1_SB_DQS_DP<5>    J29              250      SCONN288_ADR50001P013C01-SCONNA
M_G_CPU1_SB_DQS_DP<5>    J30              250      SCONN288_ADR50001P003C01-SCONNA
M_G_CPU1_SB_DQS_DP<5>    U1               DN33     SOCKET4677_AZIFS054P001C01-SOCA
M_G_CPU1_SB_DQS_DP<6>    J29              261      SCONN288_ADR50001P013C01-SCONNA
M_G_CPU1_SB_DQS_DP<6>    J30              261      SCONN288_ADR50001P003C01-SCONNA
M_G_CPU1_SB_DQS_DP<6>    U1               DR27     SOCKET4677_AZIFS054P001C01-SOCA
M_G_CPU1_SB_DQS_DP<7>    J29              272      SCONN288_ADR50001P013C01-SCONNA
M_G_CPU1_SB_DQS_DP<7>    J30              272      SCONN288_ADR50001P003C01-SCONNA
M_G_CPU1_SB_DQS_DP<7>    U1               DY24     SOCKET4677_AZIFS054P001C01-SOCA
M_G_CPU1_SB_DQS_DP<8>    J29              283      SCONN288_ADR50001P013C01-SCONNA
M_G_CPU1_SB_DQS_DP<8>    J30              283      SCONN288_ADR50001P003C01-SCONNA
M_G_CPU1_SB_DQS_DP<8>    U1               EN5      SOCKET4677_AZIFS054P001C01-SOCA
M_G_CPU1_SB_DQS_DP<9>    J29              93       SCONN288_ADR50001P013C01-SCONNA
M_G_CPU1_SB_DQS_DP<9>    J30              93       SCONN288_ADR50001P003C01-SCONNA
M_G_CPU1_SB_DQS_DP<9>    U1               DT36     SOCKET4677_AZIFS054P001C01-SOCA
M_G_CPU1_SB_PAR          J29              227      SCONN288_ADR50001P013C01-SCONNA
M_G_CPU1_SB_PAR          J30              227      SCONN288_ADR50001P003C01-SCONNA
M_G_CPU1_SB_PAR          U1               EB42     SOCKET4677_AZIFS054P001C01-SOCA
M_G_CPU1_SB_RSP<0>       J29              87       SCONN288_ADR50001P013C01-SCONNA
M_G_CPU1_SB_RSP<0>       U1               DU48     SOCKET4677_AZIFS054P001C01-SOCA
M_G_CPU1_SB_RSP<1>       J30              87       SCONN288_ADR50001P003C01-SCONNA
M_G_CPU1_SB_RSP<1>       U1               DV47     SOCKET4677_AZIFS054P001C01-SOCA
M_H_CPU0_ALERT_N         J15              62       SCONN288_ADR50001P013C01-SCONNA
M_H_CPU0_ALERT_N         J16              62       SCONN288_ADR50001P003C01-SCONNA
M_H_CPU0_ALERT_N         U2               CY51     SOCKET4677_AZIFS054P001C01-SOCA
M_H_CPU0_CLK_DN<0>       J15              218      SCONN288_ADR50001P013C01-SCONNA
M_H_CPU0_CLK_DN<0>       U2               DH42     SOCKET4677_AZIFS054P001C01-SOCA
M_H_CPU0_CLK_DN<1>       J16              218      SCONN288_ADR50001P003C01-SCONNA
M_H_CPU0_CLK_DN<1>       U2               DD42     SOCKET4677_AZIFS054P001C01-SOCA
M_H_CPU0_CLK_DP<0>       J15              217      SCONN288_ADR50001P013C01-SCONNA
M_H_CPU0_CLK_DP<0>       U2               DF42     SOCKET4677_AZIFS054P001C01-SOCA
M_H_CPU0_CLK_DP<1>       J16              217      SCONN288_ADR50001P003C01-SCONNA
M_H_CPU0_CLK_DP<1>       U2               DB42     SOCKET4677_AZIFS054P001C01-SOCA
M_H_CPU0_SA_CA<0>        J15              66       SCONN288_ADR50001P013C01-SCONNA
M_H_CPU0_SA_CA<0>        J16              66       SCONN288_ADR50001P003C01-SCONNA
M_H_CPU0_SA_CA<0>        U2               DB49     SOCKET4677_AZIFS054P001C01-SOCA
M_H_CPU0_SA_CA<1>        J15              211      SCONN288_ADR50001P013C01-SCONNA
M_H_CPU0_SA_CA<1>        J16              211      SCONN288_ADR50001P003C01-SCONNA
M_H_CPU0_SA_CA<1>        U2               DH49     SOCKET4677_AZIFS054P001C01-SOCA
M_H_CPU0_SA_CA<2>        J15              68       SCONN288_ADR50001P013C01-SCONNA
M_H_CPU0_SA_CA<2>        J16              68       SCONN288_ADR50001P003C01-SCONNA
M_H_CPU0_SA_CA<2>        U2               DC48     SOCKET4677_AZIFS054P001C01-SOCA
M_H_CPU0_SA_CA<3>        J15              213      SCONN288_ADR50001P013C01-SCONNA
M_H_CPU0_SA_CA<3>        J16              213      SCONN288_ADR50001P003C01-SCONNA
M_H_CPU0_SA_CA<3>        U2               DG48     SOCKET4677_AZIFS054P001C01-SOCA
M_H_CPU0_SA_CA<4>        J15              70       SCONN288_ADR50001P013C01-SCONNA
M_H_CPU0_SA_CA<4>        J16              70       SCONN288_ADR50001P003C01-SCONNA
M_H_CPU0_SA_CA<4>        U2               DD47     SOCKET4677_AZIFS054P001C01-SOCA
M_H_CPU0_SA_CA<5>        J15              215      SCONN288_ADR50001P013C01-SCONNA
M_H_CPU0_SA_CA<5>        J16              215      SCONN288_ADR50001P003C01-SCONNA
M_H_CPU0_SA_CA<5>        U2               DF47     SOCKET4677_AZIFS054P001C01-SOCA
M_H_CPU0_SA_CA<6>        J15              72       SCONN288_ADR50001P013C01-SCONNA
M_H_CPU0_SA_CA<6>        J16              72       SCONN288_ADR50001P003C01-SCONNA
M_H_CPU0_SA_CA<6>        U2               DC41     SOCKET4677_AZIFS054P001C01-SOCA
M_H_CPU0_SA_CB<0>        J15              51       SCONN288_ADR50001P013C01-SCONNA
M_H_CPU0_SA_CB<0>        J16              51       SCONN288_ADR50001P003C01-SCONNA
M_H_CPU0_SA_CB<0>        U2               DD57     SOCKET4677_AZIFS054P001C01-SOCA
M_H_CPU0_SA_CB<1>        J15              53       SCONN288_ADR50001P013C01-SCONNA
M_H_CPU0_SA_CB<1>        J16              53       SCONN288_ADR50001P003C01-SCONNA
M_H_CPU0_SA_CB<1>        U2               DC56     SOCKET4677_AZIFS054P001C01-SOCA
M_H_CPU0_SA_CB<2>        J15              196      SCONN288_ADR50001P013C01-SCONNA
M_H_CPU0_SA_CB<2>        J16              196      SCONN288_ADR50001P003C01-SCONNA
M_H_CPU0_SA_CB<2>        U2               DF57     SOCKET4677_AZIFS054P001C01-SOCA
M_H_CPU0_SA_CB<3>        J15              198      SCONN288_ADR50001P013C01-SCONNA
M_H_CPU0_SA_CB<3>        J16              198      SCONN288_ADR50001P003C01-SCONNA
M_H_CPU0_SA_CB<3>        U2               DG56     SOCKET4677_AZIFS054P001C01-SOCA
M_H_CPU0_SA_CB<4>        J15              58       SCONN288_ADR50001P013C01-SCONNA
M_H_CPU0_SA_CB<4>        J16              58       SCONN288_ADR50001P003C01-SCONNA
M_H_CPU0_SA_CB<4>        U2               DC54     SOCKET4677_AZIFS054P001C01-SOCA
M_H_CPU0_SA_CB<5>        J15              60       SCONN288_ADR50001P013C01-SCONNA
M_H_CPU0_SA_CB<5>        J16              60       SCONN288_ADR50001P003C01-SCONNA
M_H_CPU0_SA_CB<5>        U2               DD53     SOCKET4677_AZIFS054P001C01-SOCA
M_H_CPU0_SA_CB<6>        J15              203      SCONN288_ADR50001P013C01-SCONNA
M_H_CPU0_SA_CB<6>        J16              203      SCONN288_ADR50001P003C01-SCONNA
M_H_CPU0_SA_CB<6>        U2               DG54     SOCKET4677_AZIFS054P001C01-SOCA
M_H_CPU0_SA_CB<7>        J15              205      SCONN288_ADR50001P013C01-SCONNA
M_H_CPU0_SA_CB<7>        J16              205      SCONN288_ADR50001P003C01-SCONNA
M_H_CPU0_SA_CB<7>        U2               DF53     SOCKET4677_AZIFS054P001C01-SOCA
M_H_CPU0_SA_CS_N<0>      J15              64       SCONN288_ADR50001P013C01-SCONNA
M_H_CPU0_SA_CS_N<0>      U2               DF51     SOCKET4677_AZIFS054P001C01-SOCA
M_H_CPU0_SA_CS_N<1>      J15              209      SCONN288_ADR50001P013C01-SCONNA
M_H_CPU0_SA_CS_N<1>      U2               DG50     SOCKET4677_AZIFS054P001C01-SOCA
M_H_CPU0_SA_CS_N<2>      J16              64       SCONN288_ADR50001P003C01-SCONNA
M_H_CPU0_SA_CS_N<2>      U2               DD51     SOCKET4677_AZIFS054P001C01-SOCA
M_H_CPU0_SA_CS_N<3>      J16              209      SCONN288_ADR50001P003C01-SCONNA
M_H_CPU0_SA_CS_N<3>      U2               DC50     SOCKET4677_AZIFS054P001C01-SOCA
M_H_CPU0_SA_DQ<0>        J15              7        SCONN288_ADR50001P013C01-SCONNA
M_H_CPU0_SA_DQ<0>        J16              7        SCONN288_ADR50001P003C01-SCONNA
M_H_CPU0_SA_DQ<0>        U2               DY79     SOCKET4677_AZIFS054P001C01-SOCA
M_H_CPU0_SA_DQ<1>        J15              9        SCONN288_ADR50001P013C01-SCONNA
M_H_CPU0_SA_DQ<1>        J16              9        SCONN288_ADR50001P003C01-SCONNA
M_H_CPU0_SA_DQ<1>        U2               DT77     SOCKET4677_AZIFS054P001C01-SOCA
M_H_CPU0_SA_DQ<2>        J15              152      SCONN288_ADR50001P013C01-SCONNA
M_H_CPU0_SA_DQ<2>        J16              152      SCONN288_ADR50001P003C01-SCONNA
M_H_CPU0_SA_DQ<2>        U2               DW78     SOCKET4677_AZIFS054P001C01-SOCA
M_H_CPU0_SA_DQ<3>        J15              154      SCONN288_ADR50001P013C01-SCONNA
M_H_CPU0_SA_DQ<3>        J16              154      SCONN288_ADR50001P003C01-SCONNA
M_H_CPU0_SA_DQ<3>        U2               DP77     SOCKET4677_AZIFS054P001C01-SOCA
M_H_CPU0_SA_DQ<4>        J15              14       SCONN288_ADR50001P013C01-SCONNA
M_H_CPU0_SA_DQ<4>        J16              14       SCONN288_ADR50001P003C01-SCONNA
M_H_CPU0_SA_DQ<4>        U2               DK75     SOCKET4677_AZIFS054P001C01-SOCA
M_H_CPU0_SA_DQ<5>        J15              16       SCONN288_ADR50001P013C01-SCONNA
M_H_CPU0_SA_DQ<5>        J16              16       SCONN288_ADR50001P003C01-SCONNA
M_H_CPU0_SA_DQ<5>        U2               DL74     SOCKET4677_AZIFS054P001C01-SOCA
M_H_CPU0_SA_DQ<6>        J15              159      SCONN288_ADR50001P013C01-SCONNA
M_H_CPU0_SA_DQ<6>        J16              159      SCONN288_ADR50001P003C01-SCONNA
M_H_CPU0_SA_DQ<6>        U2               DP75     SOCKET4677_AZIFS054P001C01-SOCA
M_H_CPU0_SA_DQ<7>        J15              161      SCONN288_ADR50001P013C01-SCONNA
M_H_CPU0_SA_DQ<7>        J16              161      SCONN288_ADR50001P003C01-SCONNA
M_H_CPU0_SA_DQ<7>        U2               DN74     SOCKET4677_AZIFS054P001C01-SOCA
M_H_CPU0_SA_DQ<8>        J15              18       SCONN288_ADR50001P013C01-SCONNA
M_H_CPU0_SA_DQ<8>        J16              18       SCONN288_ADR50001P003C01-SCONNA
M_H_CPU0_SA_DQ<8>        U2               DD75     SOCKET4677_AZIFS054P001C01-SOCA
M_H_CPU0_SA_DQ<9>        J15              20       SCONN288_ADR50001P013C01-SCONNA
M_H_CPU0_SA_DQ<9>        J16              20       SCONN288_ADR50001P003C01-SCONNA
M_H_CPU0_SA_DQ<9>        U2               DC74     SOCKET4677_AZIFS054P001C01-SOCA
M_H_CPU0_SA_DQ<10>       J15              163      SCONN288_ADR50001P013C01-SCONNA
M_H_CPU0_SA_DQ<10>       J16              163      SCONN288_ADR50001P003C01-SCONNA
M_H_CPU0_SA_DQ<10>       U2               DF75     SOCKET4677_AZIFS054P001C01-SOCA
M_H_CPU0_SA_DQ<11>       J15              165      SCONN288_ADR50001P013C01-SCONNA
M_H_CPU0_SA_DQ<11>       J16              165      SCONN288_ADR50001P003C01-SCONNA
M_H_CPU0_SA_DQ<11>       U2               DG74     SOCKET4677_AZIFS054P001C01-SOCA
M_H_CPU0_SA_DQ<12>       J15              25       SCONN288_ADR50001P013C01-SCONNA
M_H_CPU0_SA_DQ<12>       J16              25       SCONN288_ADR50001P003C01-SCONNA
M_H_CPU0_SA_DQ<12>       U2               DC72     SOCKET4677_AZIFS054P001C01-SOCA
M_H_CPU0_SA_DQ<13>       J15              27       SCONN288_ADR50001P013C01-SCONNA
M_H_CPU0_SA_DQ<13>       J16              27       SCONN288_ADR50001P003C01-SCONNA
M_H_CPU0_SA_DQ<13>       U2               DD71     SOCKET4677_AZIFS054P001C01-SOCA
M_H_CPU0_SA_DQ<14>       J15              170      SCONN288_ADR50001P013C01-SCONNA
M_H_CPU0_SA_DQ<14>       J16              170      SCONN288_ADR50001P003C01-SCONNA
M_H_CPU0_SA_DQ<14>       U2               DG72     SOCKET4677_AZIFS054P001C01-SOCA
M_H_CPU0_SA_DQ<15>       J15              172      SCONN288_ADR50001P013C01-SCONNA
M_H_CPU0_SA_DQ<15>       J16              172      SCONN288_ADR50001P003C01-SCONNA
M_H_CPU0_SA_DQ<15>       U2               DF71     SOCKET4677_AZIFS054P001C01-SOCA
M_H_CPU0_SA_DQ<16>       J15              29       SCONN288_ADR50001P013C01-SCONNA
M_H_CPU0_SA_DQ<16>       J16              29       SCONN288_ADR50001P003C01-SCONNA
M_H_CPU0_SA_DQ<16>       U2               DD69     SOCKET4677_AZIFS054P001C01-SOCA
M_H_CPU0_SA_DQ<17>       J15              31       SCONN288_ADR50001P013C01-SCONNA
M_H_CPU0_SA_DQ<17>       J16              31       SCONN288_ADR50001P003C01-SCONNA
M_H_CPU0_SA_DQ<17>       U2               DC68     SOCKET4677_AZIFS054P001C01-SOCA
M_H_CPU0_SA_DQ<18>       J15              174      SCONN288_ADR50001P013C01-SCONNA
M_H_CPU0_SA_DQ<18>       J16              174      SCONN288_ADR50001P003C01-SCONNA
M_H_CPU0_SA_DQ<18>       U2               DF69     SOCKET4677_AZIFS054P001C01-SOCA
M_H_CPU0_SA_DQ<19>       J15              176      SCONN288_ADR50001P013C01-SCONNA
M_H_CPU0_SA_DQ<19>       J16              176      SCONN288_ADR50001P003C01-SCONNA
M_H_CPU0_SA_DQ<19>       U2               DG68     SOCKET4677_AZIFS054P001C01-SOCA
M_H_CPU0_SA_DQ<20>       J15              36       SCONN288_ADR50001P013C01-SCONNA
M_H_CPU0_SA_DQ<20>       J16              36       SCONN288_ADR50001P003C01-SCONNA
M_H_CPU0_SA_DQ<20>       U2               DC66     SOCKET4677_AZIFS054P001C01-SOCA
M_H_CPU0_SA_DQ<21>       J15              38       SCONN288_ADR50001P013C01-SCONNA
M_H_CPU0_SA_DQ<21>       J16              38       SCONN288_ADR50001P003C01-SCONNA
M_H_CPU0_SA_DQ<21>       U2               DD65     SOCKET4677_AZIFS054P001C01-SOCA
M_H_CPU0_SA_DQ<22>       J15              181      SCONN288_ADR50001P013C01-SCONNA
M_H_CPU0_SA_DQ<22>       J16              181      SCONN288_ADR50001P003C01-SCONNA
M_H_CPU0_SA_DQ<22>       U2               DG66     SOCKET4677_AZIFS054P001C01-SOCA
M_H_CPU0_SA_DQ<23>       J15              183      SCONN288_ADR50001P013C01-SCONNA
M_H_CPU0_SA_DQ<23>       J16              183      SCONN288_ADR50001P003C01-SCONNA
M_H_CPU0_SA_DQ<23>       U2               DF65     SOCKET4677_AZIFS054P001C01-SOCA
M_H_CPU0_SA_DQ<24>       J15              40       SCONN288_ADR50001P013C01-SCONNA
M_H_CPU0_SA_DQ<24>       J16              40       SCONN288_ADR50001P003C01-SCONNA
M_H_CPU0_SA_DQ<24>       U2               DD63     SOCKET4677_AZIFS054P001C01-SOCA
M_H_CPU0_SA_DQ<25>       J15              42       SCONN288_ADR50001P013C01-SCONNA
M_H_CPU0_SA_DQ<25>       J16              42       SCONN288_ADR50001P003C01-SCONNA
M_H_CPU0_SA_DQ<25>       U2               DC62     SOCKET4677_AZIFS054P001C01-SOCA
M_H_CPU0_SA_DQ<26>       J15              185      SCONN288_ADR50001P013C01-SCONNA
M_H_CPU0_SA_DQ<26>       J16              185      SCONN288_ADR50001P003C01-SCONNA
M_H_CPU0_SA_DQ<26>       U2               DF63     SOCKET4677_AZIFS054P001C01-SOCA
M_H_CPU0_SA_DQ<27>       J15              187      SCONN288_ADR50001P013C01-SCONNA
M_H_CPU0_SA_DQ<27>       J16              187      SCONN288_ADR50001P003C01-SCONNA
M_H_CPU0_SA_DQ<27>       U2               DG62     SOCKET4677_AZIFS054P001C01-SOCA
M_H_CPU0_SA_DQ<28>       J15              47       SCONN288_ADR50001P013C01-SCONNA
M_H_CPU0_SA_DQ<28>       J16              47       SCONN288_ADR50001P003C01-SCONNA
M_H_CPU0_SA_DQ<28>       U2               DC60     SOCKET4677_AZIFS054P001C01-SOCA
M_H_CPU0_SA_DQ<29>       J15              49       SCONN288_ADR50001P013C01-SCONNA
M_H_CPU0_SA_DQ<29>       J16              49       SCONN288_ADR50001P003C01-SCONNA
M_H_CPU0_SA_DQ<29>       U2               DD59     SOCKET4677_AZIFS054P001C01-SOCA
M_H_CPU0_SA_DQ<30>       J15              192      SCONN288_ADR50001P013C01-SCONNA
M_H_CPU0_SA_DQ<30>       J16              192      SCONN288_ADR50001P003C01-SCONNA
M_H_CPU0_SA_DQ<30>       U2               DG60     SOCKET4677_AZIFS054P001C01-SOCA
M_H_CPU0_SA_DQ<31>       J15              194      SCONN288_ADR50001P013C01-SCONNA
M_H_CPU0_SA_DQ<31>       J16              194      SCONN288_ADR50001P003C01-SCONNA
M_H_CPU0_SA_DQ<31>       U2               DF59     SOCKET4677_AZIFS054P001C01-SOCA
M_H_CPU0_SA_DQS_DN<0>    J15              12       SCONN288_ADR50001P013C01-SCONNA
M_H_CPU0_SA_DQS_DN<0>    J16              12       SCONN288_ADR50001P003C01-SCONNA
M_H_CPU0_SA_DQS_DN<0>    U2               DJ76     SOCKET4677_AZIFS054P001C01-SOCA
M_H_CPU0_SA_DQS_DN<1>    J15              23       SCONN288_ADR50001P013C01-SCONNA
M_H_CPU0_SA_DQS_DN<1>    J16              23       SCONN288_ADR50001P003C01-SCONNA
M_H_CPU0_SA_DQS_DN<1>    U2               DB73     SOCKET4677_AZIFS054P001C01-SOCA
M_H_CPU0_SA_DQS_DN<2>    J15              34       SCONN288_ADR50001P013C01-SCONNA
M_H_CPU0_SA_DQS_DN<2>    J16              34       SCONN288_ADR50001P003C01-SCONNA
M_H_CPU0_SA_DQS_DN<2>    U2               DD67     SOCKET4677_AZIFS054P001C01-SOCA
M_H_CPU0_SA_DQS_DN<3>    J15              45       SCONN288_ADR50001P013C01-SCONNA
M_H_CPU0_SA_DQS_DN<3>    J16              45       SCONN288_ADR50001P003C01-SCONNA
M_H_CPU0_SA_DQS_DN<3>    U2               DD61     SOCKET4677_AZIFS054P001C01-SOCA
M_H_CPU0_SA_DQS_DN<4>    J15              56       SCONN288_ADR50001P013C01-SCONNA
M_H_CPU0_SA_DQS_DN<4>    J16              56       SCONN288_ADR50001P003C01-SCONNA
M_H_CPU0_SA_DQS_DN<4>    U2               DD55     SOCKET4677_AZIFS054P001C01-SOCA
M_H_CPU0_SA_DQS_DN<5>    J15              156      SCONN288_ADR50001P013C01-SCONNA
M_H_CPU0_SA_DQS_DN<5>    J16              156      SCONN288_ADR50001P003C01-SCONNA
M_H_CPU0_SA_DQS_DN<5>    U2               DR76     SOCKET4677_AZIFS054P001C01-SOCA
M_H_CPU0_SA_DQS_DN<6>    J15              167      SCONN288_ADR50001P013C01-SCONNA
M_H_CPU0_SA_DQS_DN<6>    J16              167      SCONN288_ADR50001P003C01-SCONNA
M_H_CPU0_SA_DQS_DN<6>    U2               DH73     SOCKET4677_AZIFS054P001C01-SOCA
M_H_CPU0_SA_DQS_DN<7>    J15              178      SCONN288_ADR50001P013C01-SCONNA
M_H_CPU0_SA_DQS_DN<7>    J16              178      SCONN288_ADR50001P003C01-SCONNA
M_H_CPU0_SA_DQS_DN<7>    U2               DH67     SOCKET4677_AZIFS054P001C01-SOCA
M_H_CPU0_SA_DQS_DN<8>    J15              189      SCONN288_ADR50001P013C01-SCONNA
M_H_CPU0_SA_DQS_DN<8>    J16              189      SCONN288_ADR50001P003C01-SCONNA
M_H_CPU0_SA_DQS_DN<8>    U2               DH61     SOCKET4677_AZIFS054P001C01-SOCA
M_H_CPU0_SA_DQS_DN<9>    J15              200      SCONN288_ADR50001P013C01-SCONNA
M_H_CPU0_SA_DQS_DN<9>    J16              200      SCONN288_ADR50001P003C01-SCONNA
M_H_CPU0_SA_DQS_DN<9>    U2               DH55     SOCKET4677_AZIFS054P001C01-SOCA
M_H_CPU0_SA_DQS_DP<0>    J15              11       SCONN288_ADR50001P013C01-SCONNA
M_H_CPU0_SA_DQS_DP<0>    J16              11       SCONN288_ADR50001P003C01-SCONNA
M_H_CPU0_SA_DQS_DP<0>    U2               DL76     SOCKET4677_AZIFS054P001C01-SOCA
M_H_CPU0_SA_DQS_DP<1>    J15              22       SCONN288_ADR50001P013C01-SCONNA
M_H_CPU0_SA_DQS_DP<1>    J16              22       SCONN288_ADR50001P003C01-SCONNA
M_H_CPU0_SA_DQS_DP<1>    U2               DD73     SOCKET4677_AZIFS054P001C01-SOCA
M_H_CPU0_SA_DQS_DP<2>    J15              33       SCONN288_ADR50001P013C01-SCONNA
M_H_CPU0_SA_DQS_DP<2>    J16              33       SCONN288_ADR50001P003C01-SCONNA
M_H_CPU0_SA_DQS_DP<2>    U2               DB67     SOCKET4677_AZIFS054P001C01-SOCA
M_H_CPU0_SA_DQS_DP<3>    J15              44       SCONN288_ADR50001P013C01-SCONNA
M_H_CPU0_SA_DQS_DP<3>    J16              44       SCONN288_ADR50001P003C01-SCONNA
M_H_CPU0_SA_DQS_DP<3>    U2               DB61     SOCKET4677_AZIFS054P001C01-SOCA
M_H_CPU0_SA_DQS_DP<4>    J15              55       SCONN288_ADR50001P013C01-SCONNA
M_H_CPU0_SA_DQS_DP<4>    J16              55       SCONN288_ADR50001P003C01-SCONNA
M_H_CPU0_SA_DQS_DP<4>    U2               DB55     SOCKET4677_AZIFS054P001C01-SOCA
M_H_CPU0_SA_DQS_DP<5>    J15              157      SCONN288_ADR50001P013C01-SCONNA
M_H_CPU0_SA_DQS_DP<5>    J16              157      SCONN288_ADR50001P003C01-SCONNA
M_H_CPU0_SA_DQS_DP<5>    U2               DN76     SOCKET4677_AZIFS054P001C01-SOCA
M_H_CPU0_SA_DQS_DP<6>    J15              168      SCONN288_ADR50001P013C01-SCONNA
M_H_CPU0_SA_DQS_DP<6>    J16              168      SCONN288_ADR50001P003C01-SCONNA
M_H_CPU0_SA_DQS_DP<6>    U2               DF73     SOCKET4677_AZIFS054P001C01-SOCA
M_H_CPU0_SA_DQS_DP<7>    J15              179      SCONN288_ADR50001P013C01-SCONNA
M_H_CPU0_SA_DQS_DP<7>    J16              179      SCONN288_ADR50001P003C01-SCONNA
M_H_CPU0_SA_DQS_DP<7>    U2               DF67     SOCKET4677_AZIFS054P001C01-SOCA
M_H_CPU0_SA_DQS_DP<8>    J15              190      SCONN288_ADR50001P013C01-SCONNA
M_H_CPU0_SA_DQS_DP<8>    J16              190      SCONN288_ADR50001P003C01-SCONNA
M_H_CPU0_SA_DQS_DP<8>    U2               DF61     SOCKET4677_AZIFS054P001C01-SOCA
M_H_CPU0_SA_DQS_DP<9>    J15              201      SCONN288_ADR50001P013C01-SCONNA
M_H_CPU0_SA_DQS_DP<9>    J16              201      SCONN288_ADR50001P003C01-SCONNA
M_H_CPU0_SA_DQS_DP<9>    U2               DF55     SOCKET4677_AZIFS054P001C01-SOCA
M_H_CPU0_SA_PAR          J15              74       SCONN288_ADR50001P013C01-SCONNA
M_H_CPU0_SA_PAR          J16              74       SCONN288_ADR50001P003C01-SCONNA
M_H_CPU0_SA_PAR          U2               DD40     SOCKET4677_AZIFS054P001C01-SOCA
M_H_CPU0_SA_RSP<0>       J15              86       SCONN288_ADR50001P013C01-SCONNA
M_H_CPU0_SA_RSP<0>       U2               EG48     SOCKET4677_AZIFS054P001C01-SOCA
M_H_CPU0_SA_RSP<1>       J16              86       SCONN288_ADR50001P003C01-SCONNA
M_H_CPU0_SA_RSP<1>       U2               EH47     SOCKET4677_AZIFS054P001C01-SOCA
M_H_CPU0_SB_CA<0>        J15              76       SCONN288_ADR50001P013C01-SCONNA
M_H_CPU0_SB_CA<0>        J16              76       SCONN288_ADR50001P003C01-SCONNA
M_H_CPU0_SB_CA<0>        U2               DF40     SOCKET4677_AZIFS054P001C01-SOCA
M_H_CPU0_SB_CA<1>        J15              221      SCONN288_ADR50001P013C01-SCONNA
M_H_CPU0_SB_CA<1>        J16              221      SCONN288_ADR50001P003C01-SCONNA
M_H_CPU0_SB_CA<1>        U2               DG41     SOCKET4677_AZIFS054P001C01-SOCA
M_H_CPU0_SB_CA<2>        J15              78       SCONN288_ADR50001P013C01-SCONNA
M_H_CPU0_SB_CA<2>        J16              78       SCONN288_ADR50001P003C01-SCONNA
M_H_CPU0_SB_CA<2>        U2               DL41     SOCKET4677_AZIFS054P001C01-SOCA
M_H_CPU0_SB_CA<3>        J15              223      SCONN288_ADR50001P013C01-SCONNA
M_H_CPU0_SB_CA<3>        J16              223      SCONN288_ADR50001P003C01-SCONNA
M_H_CPU0_SB_CA<3>        U2               DN41     SOCKET4677_AZIFS054P001C01-SOCA
M_H_CPU0_SB_CA<4>        J15              80       SCONN288_ADR50001P013C01-SCONNA
M_H_CPU0_SB_CA<4>        J16              80       SCONN288_ADR50001P003C01-SCONNA
M_H_CPU0_SB_CA<4>        U2               DK40     SOCKET4677_AZIFS054P001C01-SOCA
M_H_CPU0_SB_CA<5>        J15              225      SCONN288_ADR50001P013C01-SCONNA
M_H_CPU0_SB_CA<5>        J16              225      SCONN288_ADR50001P003C01-SCONNA
M_H_CPU0_SB_CA<5>        U2               DP40     SOCKET4677_AZIFS054P001C01-SOCA
M_H_CPU0_SB_CA<6>        J15              82       SCONN288_ADR50001P013C01-SCONNA
M_H_CPU0_SB_CA<6>        J16              82       SCONN288_ADR50001P003C01-SCONNA
M_H_CPU0_SB_CA<6>        U2               DJ39     SOCKET4677_AZIFS054P001C01-SOCA
M_H_CPU0_SB_CB<0>        J15              96       SCONN288_ADR50001P013C01-SCONNA
M_H_CPU0_SB_CB<0>        J16              96       SCONN288_ADR50001P003C01-SCONNA
M_H_CPU0_SB_CB<0>        U2               DC35     SOCKET4677_AZIFS054P001C01-SOCA
M_H_CPU0_SB_CB<1>        J15              98       SCONN288_ADR50001P013C01-SCONNA
M_H_CPU0_SB_CB<1>        J16              98       SCONN288_ADR50001P003C01-SCONNA
M_H_CPU0_SB_CB<1>        U2               DD34     SOCKET4677_AZIFS054P001C01-SOCA
M_H_CPU0_SB_CB<2>        J15              241      SCONN288_ADR50001P013C01-SCONNA
M_H_CPU0_SB_CB<2>        J16              241      SCONN288_ADR50001P003C01-SCONNA
M_H_CPU0_SB_CB<2>        U2               DG35     SOCKET4677_AZIFS054P001C01-SOCA
M_H_CPU0_SB_CB<3>        J15              243      SCONN288_ADR50001P013C01-SCONNA
M_H_CPU0_SB_CB<3>        J16              243      SCONN288_ADR50001P003C01-SCONNA
M_H_CPU0_SB_CB<3>        U2               DF34     SOCKET4677_AZIFS054P001C01-SOCA
M_H_CPU0_SB_CB<4>        J15              89       SCONN288_ADR50001P013C01-SCONNA
M_H_CPU0_SB_CB<4>        J16              89       SCONN288_ADR50001P003C01-SCONNA
M_H_CPU0_SB_CB<4>        U2               DF38     SOCKET4677_AZIFS054P001C01-SOCA
M_H_CPU0_SB_CB<5>        J15              91       SCONN288_ADR50001P013C01-SCONNA
M_H_CPU0_SB_CB<5>        J16              91       SCONN288_ADR50001P003C01-SCONNA
M_H_CPU0_SB_CB<5>        U2               DG37     SOCKET4677_AZIFS054P001C01-SOCA
M_H_CPU0_SB_CB<6>        J15              234      SCONN288_ADR50001P013C01-SCONNA
M_H_CPU0_SB_CB<6>        J16              234      SCONN288_ADR50001P003C01-SCONNA
M_H_CPU0_SB_CB<6>        U2               DD38     SOCKET4677_AZIFS054P001C01-SOCA
M_H_CPU0_SB_CB<7>        J15              236      SCONN288_ADR50001P013C01-SCONNA
M_H_CPU0_SB_CB<7>        J16              236      SCONN288_ADR50001P003C01-SCONNA
M_H_CPU0_SB_CB<7>        U2               DC37     SOCKET4677_AZIFS054P001C01-SOCA
M_H_CPU0_SB_CS_N<0>      J15              84       SCONN288_ADR50001P013C01-SCONNA
M_H_CPU0_SB_CS_N<0>      U2               DL37     SOCKET4677_AZIFS054P001C01-SOCA
M_H_CPU0_SB_CS_N<1>      J15              229      SCONN288_ADR50001P013C01-SCONNA
M_H_CPU0_SB_CS_N<1>      U2               DN37     SOCKET4677_AZIFS054P001C01-SOCA
M_H_CPU0_SB_CS_N<2>      J16              84       SCONN288_ADR50001P003C01-SCONNA
M_H_CPU0_SB_CS_N<2>      U2               DK38     SOCKET4677_AZIFS054P001C01-SOCA
M_H_CPU0_SB_CS_N<3>      J16              229      SCONN288_ADR50001P003C01-SCONNA
M_H_CPU0_SB_CS_N<3>      U2               DP38     SOCKET4677_AZIFS054P001C01-SOCA
M_H_CPU0_SB_DQ<0>        J15              100      SCONN288_ADR50001P013C01-SCONNA
M_H_CPU0_SB_DQ<0>        J16              100      SCONN288_ADR50001P003C01-SCONNA
M_H_CPU0_SB_DQ<0>        U2               DD32     SOCKET4677_AZIFS054P001C01-SOCA
M_H_CPU0_SB_DQ<1>        J15              102      SCONN288_ADR50001P013C01-SCONNA
M_H_CPU0_SB_DQ<1>        J16              102      SCONN288_ADR50001P003C01-SCONNA
M_H_CPU0_SB_DQ<1>        U2               DC31     SOCKET4677_AZIFS054P001C01-SOCA
M_H_CPU0_SB_DQ<2>        J15              245      SCONN288_ADR50001P013C01-SCONNA
M_H_CPU0_SB_DQ<2>        J16              245      SCONN288_ADR50001P003C01-SCONNA
M_H_CPU0_SB_DQ<2>        U2               DF32     SOCKET4677_AZIFS054P001C01-SOCA
M_H_CPU0_SB_DQ<3>        J15              247      SCONN288_ADR50001P013C01-SCONNA
M_H_CPU0_SB_DQ<3>        J16              247      SCONN288_ADR50001P003C01-SCONNA
M_H_CPU0_SB_DQ<3>        U2               DG31     SOCKET4677_AZIFS054P001C01-SOCA
M_H_CPU0_SB_DQ<4>        J15              107      SCONN288_ADR50001P013C01-SCONNA
M_H_CPU0_SB_DQ<4>        J16              107      SCONN288_ADR50001P003C01-SCONNA
M_H_CPU0_SB_DQ<4>        U2               DC29     SOCKET4677_AZIFS054P001C01-SOCA
M_H_CPU0_SB_DQ<5>        J15              109      SCONN288_ADR50001P013C01-SCONNA
M_H_CPU0_SB_DQ<5>        J16              109      SCONN288_ADR50001P003C01-SCONNA
M_H_CPU0_SB_DQ<5>        U2               DF28     SOCKET4677_AZIFS054P001C01-SOCA
M_H_CPU0_SB_DQ<6>        J15              252      SCONN288_ADR50001P013C01-SCONNA
M_H_CPU0_SB_DQ<6>        J16              252      SCONN288_ADR50001P003C01-SCONNA
M_H_CPU0_SB_DQ<6>        U2               DG29     SOCKET4677_AZIFS054P001C01-SOCA
M_H_CPU0_SB_DQ<7>        J15              254      SCONN288_ADR50001P013C01-SCONNA
M_H_CPU0_SB_DQ<7>        J16              254      SCONN288_ADR50001P003C01-SCONNA
M_H_CPU0_SB_DQ<7>        U2               DD28     SOCKET4677_AZIFS054P001C01-SOCA
M_H_CPU0_SB_DQ<8>        J15              111      SCONN288_ADR50001P013C01-SCONNA
M_H_CPU0_SB_DQ<8>        J16              111      SCONN288_ADR50001P003C01-SCONNA
M_H_CPU0_SB_DQ<8>        U2               DD26     SOCKET4677_AZIFS054P001C01-SOCA
M_H_CPU0_SB_DQ<9>        J15              113      SCONN288_ADR50001P013C01-SCONNA
M_H_CPU0_SB_DQ<9>        J16              113      SCONN288_ADR50001P003C01-SCONNA
M_H_CPU0_SB_DQ<9>        U2               DC25     SOCKET4677_AZIFS054P001C01-SOCA
M_H_CPU0_SB_DQ<10>       J15              256      SCONN288_ADR50001P013C01-SCONNA
M_H_CPU0_SB_DQ<10>       J16              256      SCONN288_ADR50001P003C01-SCONNA
M_H_CPU0_SB_DQ<10>       U2               DF26     SOCKET4677_AZIFS054P001C01-SOCA
M_H_CPU0_SB_DQ<11>       J15              258      SCONN288_ADR50001P013C01-SCONNA
M_H_CPU0_SB_DQ<11>       J16              258      SCONN288_ADR50001P003C01-SCONNA
M_H_CPU0_SB_DQ<11>       U2               DG25     SOCKET4677_AZIFS054P001C01-SOCA
M_H_CPU0_SB_DQ<12>       J15              118      SCONN288_ADR50001P013C01-SCONNA
M_H_CPU0_SB_DQ<12>       J16              118      SCONN288_ADR50001P003C01-SCONNA
M_H_CPU0_SB_DQ<12>       U2               DC23     SOCKET4677_AZIFS054P001C01-SOCA
M_H_CPU0_SB_DQ<13>       J15              120      SCONN288_ADR50001P013C01-SCONNA
M_H_CPU0_SB_DQ<13>       J16              120      SCONN288_ADR50001P003C01-SCONNA
M_H_CPU0_SB_DQ<13>       U2               DD22     SOCKET4677_AZIFS054P001C01-SOCA
M_H_CPU0_SB_DQ<14>       J15              263      SCONN288_ADR50001P013C01-SCONNA
M_H_CPU0_SB_DQ<14>       J16              263      SCONN288_ADR50001P003C01-SCONNA
M_H_CPU0_SB_DQ<14>       U2               DG23     SOCKET4677_AZIFS054P001C01-SOCA
M_H_CPU0_SB_DQ<15>       J15              265      SCONN288_ADR50001P013C01-SCONNA
M_H_CPU0_SB_DQ<15>       J16              265      SCONN288_ADR50001P003C01-SCONNA
M_H_CPU0_SB_DQ<15>       U2               DF22     SOCKET4677_AZIFS054P001C01-SOCA
M_H_CPU0_SB_DQ<16>       J15              122      SCONN288_ADR50001P013C01-SCONNA
M_H_CPU0_SB_DQ<16>       J16              122      SCONN288_ADR50001P003C01-SCONNA
M_H_CPU0_SB_DQ<16>       U2               DL23     SOCKET4677_AZIFS054P001C01-SOCA
M_H_CPU0_SB_DQ<17>       J15              124      SCONN288_ADR50001P013C01-SCONNA
M_H_CPU0_SB_DQ<17>       J16              124      SCONN288_ADR50001P003C01-SCONNA
M_H_CPU0_SB_DQ<17>       U2               DK22     SOCKET4677_AZIFS054P001C01-SOCA
M_H_CPU0_SB_DQ<18>       J15              267      SCONN288_ADR50001P013C01-SCONNA
M_H_CPU0_SB_DQ<18>       J16              267      SCONN288_ADR50001P003C01-SCONNA
M_H_CPU0_SB_DQ<18>       U2               DN23     SOCKET4677_AZIFS054P001C01-SOCA
M_H_CPU0_SB_DQ<19>       J15              269      SCONN288_ADR50001P013C01-SCONNA
M_H_CPU0_SB_DQ<19>       J16              269      SCONN288_ADR50001P003C01-SCONNA
M_H_CPU0_SB_DQ<19>       U2               DP22     SOCKET4677_AZIFS054P001C01-SOCA
M_H_CPU0_SB_DQ<20>       J15              129      SCONN288_ADR50001P013C01-SCONNA
M_H_CPU0_SB_DQ<20>       J16              129      SCONN288_ADR50001P003C01-SCONNA
M_H_CPU0_SB_DQ<20>       U2               DK20     SOCKET4677_AZIFS054P001C01-SOCA
M_H_CPU0_SB_DQ<21>       J15              131      SCONN288_ADR50001P013C01-SCONNA
M_H_CPU0_SB_DQ<21>       J16              131      SCONN288_ADR50001P003C01-SCONNA
M_H_CPU0_SB_DQ<21>       U2               DL19     SOCKET4677_AZIFS054P001C01-SOCA
M_H_CPU0_SB_DQ<22>       J15              274      SCONN288_ADR50001P013C01-SCONNA
M_H_CPU0_SB_DQ<22>       J16              274      SCONN288_ADR50001P003C01-SCONNA
M_H_CPU0_SB_DQ<22>       U2               DP20     SOCKET4677_AZIFS054P001C01-SOCA
M_H_CPU0_SB_DQ<23>       J15              276      SCONN288_ADR50001P013C01-SCONNA
M_H_CPU0_SB_DQ<23>       J16              276      SCONN288_ADR50001P003C01-SCONNA
M_H_CPU0_SB_DQ<23>       U2               DN19     SOCKET4677_AZIFS054P001C01-SOCA
M_H_CPU0_SB_DQ<24>       J15              133      SCONN288_ADR50001P013C01-SCONNA
M_H_CPU0_SB_DQ<24>       J16              133      SCONN288_ADR50001P003C01-SCONNA
M_H_CPU0_SB_DQ<24>       U2               DD20     SOCKET4677_AZIFS054P001C01-SOCA
M_H_CPU0_SB_DQ<25>       J15              135      SCONN288_ADR50001P013C01-SCONNA
M_H_CPU0_SB_DQ<25>       J16              135      SCONN288_ADR50001P003C01-SCONNA
M_H_CPU0_SB_DQ<25>       U2               DC19     SOCKET4677_AZIFS054P001C01-SOCA
M_H_CPU0_SB_DQ<26>       J15              278      SCONN288_ADR50001P013C01-SCONNA
M_H_CPU0_SB_DQ<26>       J16              278      SCONN288_ADR50001P003C01-SCONNA
M_H_CPU0_SB_DQ<26>       U2               DF20     SOCKET4677_AZIFS054P001C01-SOCA
M_H_CPU0_SB_DQ<27>       J15              280      SCONN288_ADR50001P013C01-SCONNA
M_H_CPU0_SB_DQ<27>       J16              280      SCONN288_ADR50001P003C01-SCONNA
M_H_CPU0_SB_DQ<27>       U2               DG19     SOCKET4677_AZIFS054P001C01-SOCA
M_H_CPU0_SB_DQ<28>       J15              140      SCONN288_ADR50001P013C01-SCONNA
M_H_CPU0_SB_DQ<28>       J16              140      SCONN288_ADR50001P003C01-SCONNA
M_H_CPU0_SB_DQ<28>       U2               DG17     SOCKET4677_AZIFS054P001C01-SOCA
M_H_CPU0_SB_DQ<29>       J15              142      SCONN288_ADR50001P013C01-SCONNA
M_H_CPU0_SB_DQ<29>       J16              142      SCONN288_ADR50001P003C01-SCONNA
M_H_CPU0_SB_DQ<29>       U2               DA17     SOCKET4677_AZIFS054P001C01-SOCA
M_H_CPU0_SB_DQ<30>       J15              285      SCONN288_ADR50001P013C01-SCONNA
M_H_CPU0_SB_DQ<30>       J16              285      SCONN288_ADR50001P003C01-SCONNA
M_H_CPU0_SB_DQ<30>       U2               DJ17     SOCKET4677_AZIFS054P001C01-SOCA
M_H_CPU0_SB_DQ<31>       J15              287      SCONN288_ADR50001P013C01-SCONNA
M_H_CPU0_SB_DQ<31>       J16              287      SCONN288_ADR50001P003C01-SCONNA
M_H_CPU0_SB_DQ<31>       U2               DC17     SOCKET4677_AZIFS054P001C01-SOCA
M_H_CPU0_SB_DQS_DN<0>    J15              105      SCONN288_ADR50001P013C01-SCONNA
M_H_CPU0_SB_DQS_DN<0>    J16              105      SCONN288_ADR50001P003C01-SCONNA
M_H_CPU0_SB_DQS_DN<0>    U2               DD30     SOCKET4677_AZIFS054P001C01-SOCA
M_H_CPU0_SB_DQS_DN<1>    J15              116      SCONN288_ADR50001P013C01-SCONNA
M_H_CPU0_SB_DQS_DN<1>    J16              116      SCONN288_ADR50001P003C01-SCONNA
M_H_CPU0_SB_DQS_DN<1>    U2               DD24     SOCKET4677_AZIFS054P001C01-SOCA
M_H_CPU0_SB_DQS_DN<2>    J15              127      SCONN288_ADR50001P013C01-SCONNA
M_H_CPU0_SB_DQS_DN<2>    J16              127      SCONN288_ADR50001P003C01-SCONNA
M_H_CPU0_SB_DQS_DN<2>    U2               DL21     SOCKET4677_AZIFS054P001C01-SOCA
M_H_CPU0_SB_DQS_DN<3>    J15              138      SCONN288_ADR50001P013C01-SCONNA
M_H_CPU0_SB_DQS_DN<3>    J16              138      SCONN288_ADR50001P003C01-SCONNA
M_H_CPU0_SB_DQS_DN<3>    U2               DB18     SOCKET4677_AZIFS054P001C01-SOCA
M_H_CPU0_SB_DQS_DN<4>    J15              238      SCONN288_ADR50001P013C01-SCONNA
M_H_CPU0_SB_DQS_DN<4>    J16              238      SCONN288_ADR50001P003C01-SCONNA
M_H_CPU0_SB_DQS_DN<4>    U2               DH36     SOCKET4677_AZIFS054P001C01-SOCA
M_H_CPU0_SB_DQS_DN<5>    J15              249      SCONN288_ADR50001P013C01-SCONNA
M_H_CPU0_SB_DQS_DN<5>    J16              249      SCONN288_ADR50001P003C01-SCONNA
M_H_CPU0_SB_DQS_DN<5>    U2               DH30     SOCKET4677_AZIFS054P001C01-SOCA
M_H_CPU0_SB_DQS_DN<6>    J15              260      SCONN288_ADR50001P013C01-SCONNA
M_H_CPU0_SB_DQS_DN<6>    J16              260      SCONN288_ADR50001P003C01-SCONNA
M_H_CPU0_SB_DQS_DN<6>    U2               DH24     SOCKET4677_AZIFS054P001C01-SOCA
M_H_CPU0_SB_DQS_DN<7>    J15              271      SCONN288_ADR50001P013C01-SCONNA
M_H_CPU0_SB_DQS_DN<7>    J16              271      SCONN288_ADR50001P003C01-SCONNA
M_H_CPU0_SB_DQS_DN<7>    U2               DR21     SOCKET4677_AZIFS054P001C01-SOCA
M_H_CPU0_SB_DQS_DN<8>    J15              282      SCONN288_ADR50001P013C01-SCONNA
M_H_CPU0_SB_DQS_DN<8>    J16              282      SCONN288_ADR50001P003C01-SCONNA
M_H_CPU0_SB_DQS_DN<8>    U2               DF18     SOCKET4677_AZIFS054P001C01-SOCA
M_H_CPU0_SB_DQS_DN<9>    J15              94       SCONN288_ADR50001P013C01-SCONNA
M_H_CPU0_SB_DQS_DN<9>    J16              94       SCONN288_ADR50001P003C01-SCONNA
M_H_CPU0_SB_DQS_DN<9>    U2               DD36     SOCKET4677_AZIFS054P001C01-SOCA
M_H_CPU0_SB_DQS_DP<0>    J15              104      SCONN288_ADR50001P013C01-SCONNA
M_H_CPU0_SB_DQS_DP<0>    J16              104      SCONN288_ADR50001P003C01-SCONNA
M_H_CPU0_SB_DQS_DP<0>    U2               DB30     SOCKET4677_AZIFS054P001C01-SOCA
M_H_CPU0_SB_DQS_DP<1>    J15              115      SCONN288_ADR50001P013C01-SCONNA
M_H_CPU0_SB_DQS_DP<1>    J16              115      SCONN288_ADR50001P003C01-SCONNA
M_H_CPU0_SB_DQS_DP<1>    U2               DB24     SOCKET4677_AZIFS054P001C01-SOCA
M_H_CPU0_SB_DQS_DP<2>    J15              126      SCONN288_ADR50001P013C01-SCONNA
M_H_CPU0_SB_DQS_DP<2>    J16              126      SCONN288_ADR50001P003C01-SCONNA
M_H_CPU0_SB_DQS_DP<2>    U2               DJ21     SOCKET4677_AZIFS054P001C01-SOCA
M_H_CPU0_SB_DQS_DP<3>    J15              137      SCONN288_ADR50001P013C01-SCONNA
M_H_CPU0_SB_DQS_DP<3>    J16              137      SCONN288_ADR50001P003C01-SCONNA
M_H_CPU0_SB_DQS_DP<3>    U2               DD18     SOCKET4677_AZIFS054P001C01-SOCA
M_H_CPU0_SB_DQS_DP<4>    J15              239      SCONN288_ADR50001P013C01-SCONNA
M_H_CPU0_SB_DQS_DP<4>    J16              239      SCONN288_ADR50001P003C01-SCONNA
M_H_CPU0_SB_DQS_DP<4>    U2               DF36     SOCKET4677_AZIFS054P001C01-SOCA
M_H_CPU0_SB_DQS_DP<5>    J15              250      SCONN288_ADR50001P013C01-SCONNA
M_H_CPU0_SB_DQS_DP<5>    J16              250      SCONN288_ADR50001P003C01-SCONNA
M_H_CPU0_SB_DQS_DP<5>    U2               DF30     SOCKET4677_AZIFS054P001C01-SOCA
M_H_CPU0_SB_DQS_DP<6>    J15              261      SCONN288_ADR50001P013C01-SCONNA
M_H_CPU0_SB_DQS_DP<6>    J16              261      SCONN288_ADR50001P003C01-SCONNA
M_H_CPU0_SB_DQS_DP<6>    U2               DF24     SOCKET4677_AZIFS054P001C01-SOCA
M_H_CPU0_SB_DQS_DP<7>    J15              272      SCONN288_ADR50001P013C01-SCONNA
M_H_CPU0_SB_DQS_DP<7>    J16              272      SCONN288_ADR50001P003C01-SCONNA
M_H_CPU0_SB_DQS_DP<7>    U2               DN21     SOCKET4677_AZIFS054P001C01-SOCA
M_H_CPU0_SB_DQS_DP<8>    J15              283      SCONN288_ADR50001P013C01-SCONNA
M_H_CPU0_SB_DQS_DP<8>    J16              283      SCONN288_ADR50001P003C01-SCONNA
M_H_CPU0_SB_DQS_DP<8>    U2               DH18     SOCKET4677_AZIFS054P001C01-SOCA
M_H_CPU0_SB_DQS_DP<9>    J15              93       SCONN288_ADR50001P013C01-SCONNA
M_H_CPU0_SB_DQS_DP<9>    J16              93       SCONN288_ADR50001P003C01-SCONNA
M_H_CPU0_SB_DQS_DP<9>    U2               DB36     SOCKET4677_AZIFS054P001C01-SOCA
M_H_CPU0_SB_PAR          J15              227      SCONN288_ADR50001P013C01-SCONNA
M_H_CPU0_SB_PAR          J16              227      SCONN288_ADR50001P003C01-SCONNA
M_H_CPU0_SB_PAR          U2               DR39     SOCKET4677_AZIFS054P001C01-SOCA
M_H_CPU0_SB_RSP<0>       J15              87       SCONN288_ADR50001P013C01-SCONNA
M_H_CPU0_SB_RSP<0>       U2               EE48     SOCKET4677_AZIFS054P001C01-SOCA
M_H_CPU0_SB_RSP<1>       J16              87       SCONN288_ADR50001P003C01-SCONNA
M_H_CPU0_SB_RSP<1>       U2               ED47     SOCKET4677_AZIFS054P001C01-SOCA
M_H_CPU1_ALERT_N         J31              62       SCONN288_ADR50001P013C01-SCONNA
M_H_CPU1_ALERT_N         J32              62       SCONN288_ADR50001P003C01-SCONNA
M_H_CPU1_ALERT_N         U1               CY51     SOCKET4677_AZIFS054P001C01-SOCA
M_H_CPU1_CLK_DN<0>       J31              218      SCONN288_ADR50001P013C01-SCONNA
M_H_CPU1_CLK_DN<0>       U1               DH42     SOCKET4677_AZIFS054P001C01-SOCA
M_H_CPU1_CLK_DN<1>       J32              218      SCONN288_ADR50001P003C01-SCONNA
M_H_CPU1_CLK_DN<1>       U1               DD42     SOCKET4677_AZIFS054P001C01-SOCA
M_H_CPU1_CLK_DP<0>       J31              217      SCONN288_ADR50001P013C01-SCONNA
M_H_CPU1_CLK_DP<0>       U1               DF42     SOCKET4677_AZIFS054P001C01-SOCA
M_H_CPU1_CLK_DP<1>       J32              217      SCONN288_ADR50001P003C01-SCONNA
M_H_CPU1_CLK_DP<1>       U1               DB42     SOCKET4677_AZIFS054P001C01-SOCA
M_H_CPU1_SA_CA<0>        J31              66       SCONN288_ADR50001P013C01-SCONNA
M_H_CPU1_SA_CA<0>        J32              66       SCONN288_ADR50001P003C01-SCONNA
M_H_CPU1_SA_CA<0>        U1               DB49     SOCKET4677_AZIFS054P001C01-SOCA
M_H_CPU1_SA_CA<1>        J31              211      SCONN288_ADR50001P013C01-SCONNA
M_H_CPU1_SA_CA<1>        J32              211      SCONN288_ADR50001P003C01-SCONNA
M_H_CPU1_SA_CA<1>        U1               DH49     SOCKET4677_AZIFS054P001C01-SOCA
M_H_CPU1_SA_CA<2>        J31              68       SCONN288_ADR50001P013C01-SCONNA
M_H_CPU1_SA_CA<2>        J32              68       SCONN288_ADR50001P003C01-SCONNA
M_H_CPU1_SA_CA<2>        U1               DC48     SOCKET4677_AZIFS054P001C01-SOCA
M_H_CPU1_SA_CA<3>        J31              213      SCONN288_ADR50001P013C01-SCONNA
M_H_CPU1_SA_CA<3>        J32              213      SCONN288_ADR50001P003C01-SCONNA
M_H_CPU1_SA_CA<3>        U1               DG48     SOCKET4677_AZIFS054P001C01-SOCA
M_H_CPU1_SA_CA<4>        J31              70       SCONN288_ADR50001P013C01-SCONNA
M_H_CPU1_SA_CA<4>        J32              70       SCONN288_ADR50001P003C01-SCONNA
M_H_CPU1_SA_CA<4>        U1               DD47     SOCKET4677_AZIFS054P001C01-SOCA
M_H_CPU1_SA_CA<5>        J31              215      SCONN288_ADR50001P013C01-SCONNA
M_H_CPU1_SA_CA<5>        J32              215      SCONN288_ADR50001P003C01-SCONNA
M_H_CPU1_SA_CA<5>        U1               DF47     SOCKET4677_AZIFS054P001C01-SOCA
M_H_CPU1_SA_CA<6>        J31              72       SCONN288_ADR50001P013C01-SCONNA
M_H_CPU1_SA_CA<6>        J32              72       SCONN288_ADR50001P003C01-SCONNA
M_H_CPU1_SA_CA<6>        U1               DC41     SOCKET4677_AZIFS054P001C01-SOCA
M_H_CPU1_SA_CB<0>        J31              51       SCONN288_ADR50001P013C01-SCONNA
M_H_CPU1_SA_CB<0>        J32              51       SCONN288_ADR50001P003C01-SCONNA
M_H_CPU1_SA_CB<0>        U1               DD57     SOCKET4677_AZIFS054P001C01-SOCA
M_H_CPU1_SA_CB<1>        J31              53       SCONN288_ADR50001P013C01-SCONNA
M_H_CPU1_SA_CB<1>        J32              53       SCONN288_ADR50001P003C01-SCONNA
M_H_CPU1_SA_CB<1>        U1               DC56     SOCKET4677_AZIFS054P001C01-SOCA
M_H_CPU1_SA_CB<2>        J31              196      SCONN288_ADR50001P013C01-SCONNA
M_H_CPU1_SA_CB<2>        J32              196      SCONN288_ADR50001P003C01-SCONNA
M_H_CPU1_SA_CB<2>        U1               DF57     SOCKET4677_AZIFS054P001C01-SOCA
M_H_CPU1_SA_CB<3>        J31              198      SCONN288_ADR50001P013C01-SCONNA
M_H_CPU1_SA_CB<3>        J32              198      SCONN288_ADR50001P003C01-SCONNA
M_H_CPU1_SA_CB<3>        U1               DG56     SOCKET4677_AZIFS054P001C01-SOCA
M_H_CPU1_SA_CB<4>        J31              58       SCONN288_ADR50001P013C01-SCONNA
M_H_CPU1_SA_CB<4>        J32              58       SCONN288_ADR50001P003C01-SCONNA
M_H_CPU1_SA_CB<4>        U1               DC54     SOCKET4677_AZIFS054P001C01-SOCA
M_H_CPU1_SA_CB<5>        J31              60       SCONN288_ADR50001P013C01-SCONNA
M_H_CPU1_SA_CB<5>        J32              60       SCONN288_ADR50001P003C01-SCONNA
M_H_CPU1_SA_CB<5>        U1               DD53     SOCKET4677_AZIFS054P001C01-SOCA
M_H_CPU1_SA_CB<6>        J31              203      SCONN288_ADR50001P013C01-SCONNA
M_H_CPU1_SA_CB<6>        J32              203      SCONN288_ADR50001P003C01-SCONNA
M_H_CPU1_SA_CB<6>        U1               DG54     SOCKET4677_AZIFS054P001C01-SOCA
M_H_CPU1_SA_CB<7>        J31              205      SCONN288_ADR50001P013C01-SCONNA
M_H_CPU1_SA_CB<7>        J32              205      SCONN288_ADR50001P003C01-SCONNA
M_H_CPU1_SA_CB<7>        U1               DF53     SOCKET4677_AZIFS054P001C01-SOCA
M_H_CPU1_SA_CS_N<0>      J31              64       SCONN288_ADR50001P013C01-SCONNA
M_H_CPU1_SA_CS_N<0>      U1               DF51     SOCKET4677_AZIFS054P001C01-SOCA
M_H_CPU1_SA_CS_N<1>      J31              209      SCONN288_ADR50001P013C01-SCONNA
M_H_CPU1_SA_CS_N<1>      U1               DG50     SOCKET4677_AZIFS054P001C01-SOCA
M_H_CPU1_SA_CS_N<2>      J32              64       SCONN288_ADR50001P003C01-SCONNA
M_H_CPU1_SA_CS_N<2>      U1               DD51     SOCKET4677_AZIFS054P001C01-SOCA
M_H_CPU1_SA_CS_N<3>      J32              209      SCONN288_ADR50001P003C01-SCONNA
M_H_CPU1_SA_CS_N<3>      U1               DC50     SOCKET4677_AZIFS054P001C01-SOCA
M_H_CPU1_SA_DQ<0>        J31              7        SCONN288_ADR50001P013C01-SCONNA
M_H_CPU1_SA_DQ<0>        J32              7        SCONN288_ADR50001P003C01-SCONNA
M_H_CPU1_SA_DQ<0>        U1               DY79     SOCKET4677_AZIFS054P001C01-SOCA
M_H_CPU1_SA_DQ<1>        J31              9        SCONN288_ADR50001P013C01-SCONNA
M_H_CPU1_SA_DQ<1>        J32              9        SCONN288_ADR50001P003C01-SCONNA
M_H_CPU1_SA_DQ<1>        U1               DT77     SOCKET4677_AZIFS054P001C01-SOCA
M_H_CPU1_SA_DQ<2>        J31              152      SCONN288_ADR50001P013C01-SCONNA
M_H_CPU1_SA_DQ<2>        J32              152      SCONN288_ADR50001P003C01-SCONNA
M_H_CPU1_SA_DQ<2>        U1               DW78     SOCKET4677_AZIFS054P001C01-SOCA
M_H_CPU1_SA_DQ<3>        J31              154      SCONN288_ADR50001P013C01-SCONNA
M_H_CPU1_SA_DQ<3>        J32              154      SCONN288_ADR50001P003C01-SCONNA
M_H_CPU1_SA_DQ<3>        U1               DP77     SOCKET4677_AZIFS054P001C01-SOCA
M_H_CPU1_SA_DQ<4>        J31              14       SCONN288_ADR50001P013C01-SCONNA
M_H_CPU1_SA_DQ<4>        J32              14       SCONN288_ADR50001P003C01-SCONNA
M_H_CPU1_SA_DQ<4>        U1               DK75     SOCKET4677_AZIFS054P001C01-SOCA
M_H_CPU1_SA_DQ<5>        J31              16       SCONN288_ADR50001P013C01-SCONNA
M_H_CPU1_SA_DQ<5>        J32              16       SCONN288_ADR50001P003C01-SCONNA
M_H_CPU1_SA_DQ<5>        U1               DL74     SOCKET4677_AZIFS054P001C01-SOCA
M_H_CPU1_SA_DQ<6>        J31              159      SCONN288_ADR50001P013C01-SCONNA
M_H_CPU1_SA_DQ<6>        J32              159      SCONN288_ADR50001P003C01-SCONNA
M_H_CPU1_SA_DQ<6>        U1               DP75     SOCKET4677_AZIFS054P001C01-SOCA
M_H_CPU1_SA_DQ<7>        J31              161      SCONN288_ADR50001P013C01-SCONNA
M_H_CPU1_SA_DQ<7>        J32              161      SCONN288_ADR50001P003C01-SCONNA
M_H_CPU1_SA_DQ<7>        U1               DN74     SOCKET4677_AZIFS054P001C01-SOCA
M_H_CPU1_SA_DQ<8>        J31              18       SCONN288_ADR50001P013C01-SCONNA
M_H_CPU1_SA_DQ<8>        J32              18       SCONN288_ADR50001P003C01-SCONNA
M_H_CPU1_SA_DQ<8>        U1               DD75     SOCKET4677_AZIFS054P001C01-SOCA
M_H_CPU1_SA_DQ<9>        J31              20       SCONN288_ADR50001P013C01-SCONNA
M_H_CPU1_SA_DQ<9>        J32              20       SCONN288_ADR50001P003C01-SCONNA
M_H_CPU1_SA_DQ<9>        U1               DC74     SOCKET4677_AZIFS054P001C01-SOCA
M_H_CPU1_SA_DQ<10>       J31              163      SCONN288_ADR50001P013C01-SCONNA
M_H_CPU1_SA_DQ<10>       J32              163      SCONN288_ADR50001P003C01-SCONNA
M_H_CPU1_SA_DQ<10>       U1               DF75     SOCKET4677_AZIFS054P001C01-SOCA
M_H_CPU1_SA_DQ<11>       J31              165      SCONN288_ADR50001P013C01-SCONNA
M_H_CPU1_SA_DQ<11>       J32              165      SCONN288_ADR50001P003C01-SCONNA
M_H_CPU1_SA_DQ<11>       U1               DG74     SOCKET4677_AZIFS054P001C01-SOCA
M_H_CPU1_SA_DQ<12>       J31              25       SCONN288_ADR50001P013C01-SCONNA
M_H_CPU1_SA_DQ<12>       J32              25       SCONN288_ADR50001P003C01-SCONNA
M_H_CPU1_SA_DQ<12>       U1               DC72     SOCKET4677_AZIFS054P001C01-SOCA
M_H_CPU1_SA_DQ<13>       J31              27       SCONN288_ADR50001P013C01-SCONNA
M_H_CPU1_SA_DQ<13>       J32              27       SCONN288_ADR50001P003C01-SCONNA
M_H_CPU1_SA_DQ<13>       U1               DD71     SOCKET4677_AZIFS054P001C01-SOCA
M_H_CPU1_SA_DQ<14>       J31              170      SCONN288_ADR50001P013C01-SCONNA
M_H_CPU1_SA_DQ<14>       J32              170      SCONN288_ADR50001P003C01-SCONNA
M_H_CPU1_SA_DQ<14>       U1               DG72     SOCKET4677_AZIFS054P001C01-SOCA
M_H_CPU1_SA_DQ<15>       J31              172      SCONN288_ADR50001P013C01-SCONNA
M_H_CPU1_SA_DQ<15>       J32              172      SCONN288_ADR50001P003C01-SCONNA
M_H_CPU1_SA_DQ<15>       U1               DF71     SOCKET4677_AZIFS054P001C01-SOCA
M_H_CPU1_SA_DQ<16>       J31              29       SCONN288_ADR50001P013C01-SCONNA
M_H_CPU1_SA_DQ<16>       J32              29       SCONN288_ADR50001P003C01-SCONNA
M_H_CPU1_SA_DQ<16>       U1               DD69     SOCKET4677_AZIFS054P001C01-SOCA
M_H_CPU1_SA_DQ<17>       J31              31       SCONN288_ADR50001P013C01-SCONNA
M_H_CPU1_SA_DQ<17>       J32              31       SCONN288_ADR50001P003C01-SCONNA
M_H_CPU1_SA_DQ<17>       U1               DC68     SOCKET4677_AZIFS054P001C01-SOCA
M_H_CPU1_SA_DQ<18>       J31              174      SCONN288_ADR50001P013C01-SCONNA
M_H_CPU1_SA_DQ<18>       J32              174      SCONN288_ADR50001P003C01-SCONNA
M_H_CPU1_SA_DQ<18>       U1               DF69     SOCKET4677_AZIFS054P001C01-SOCA
M_H_CPU1_SA_DQ<19>       J31              176      SCONN288_ADR50001P013C01-SCONNA
M_H_CPU1_SA_DQ<19>       J32              176      SCONN288_ADR50001P003C01-SCONNA
M_H_CPU1_SA_DQ<19>       U1               DG68     SOCKET4677_AZIFS054P001C01-SOCA
M_H_CPU1_SA_DQ<20>       J31              36       SCONN288_ADR50001P013C01-SCONNA
M_H_CPU1_SA_DQ<20>       J32              36       SCONN288_ADR50001P003C01-SCONNA
M_H_CPU1_SA_DQ<20>       U1               DC66     SOCKET4677_AZIFS054P001C01-SOCA
M_H_CPU1_SA_DQ<21>       J31              38       SCONN288_ADR50001P013C01-SCONNA
M_H_CPU1_SA_DQ<21>       J32              38       SCONN288_ADR50001P003C01-SCONNA
M_H_CPU1_SA_DQ<21>       U1               DD65     SOCKET4677_AZIFS054P001C01-SOCA
M_H_CPU1_SA_DQ<22>       J31              181      SCONN288_ADR50001P013C01-SCONNA
M_H_CPU1_SA_DQ<22>       J32              181      SCONN288_ADR50001P003C01-SCONNA
M_H_CPU1_SA_DQ<22>       U1               DG66     SOCKET4677_AZIFS054P001C01-SOCA
M_H_CPU1_SA_DQ<23>       J31              183      SCONN288_ADR50001P013C01-SCONNA
M_H_CPU1_SA_DQ<23>       J32              183      SCONN288_ADR50001P003C01-SCONNA
M_H_CPU1_SA_DQ<23>       U1               DF65     SOCKET4677_AZIFS054P001C01-SOCA
M_H_CPU1_SA_DQ<24>       J31              40       SCONN288_ADR50001P013C01-SCONNA
M_H_CPU1_SA_DQ<24>       J32              40       SCONN288_ADR50001P003C01-SCONNA
M_H_CPU1_SA_DQ<24>       U1               DD63     SOCKET4677_AZIFS054P001C01-SOCA
M_H_CPU1_SA_DQ<25>       J31              42       SCONN288_ADR50001P013C01-SCONNA
M_H_CPU1_SA_DQ<25>       J32              42       SCONN288_ADR50001P003C01-SCONNA
M_H_CPU1_SA_DQ<25>       U1               DC62     SOCKET4677_AZIFS054P001C01-SOCA
M_H_CPU1_SA_DQ<26>       J31              185      SCONN288_ADR50001P013C01-SCONNA
M_H_CPU1_SA_DQ<26>       J32              185      SCONN288_ADR50001P003C01-SCONNA
M_H_CPU1_SA_DQ<26>       U1               DF63     SOCKET4677_AZIFS054P001C01-SOCA
M_H_CPU1_SA_DQ<27>       J31              187      SCONN288_ADR50001P013C01-SCONNA
M_H_CPU1_SA_DQ<27>       J32              187      SCONN288_ADR50001P003C01-SCONNA
M_H_CPU1_SA_DQ<27>       U1               DG62     SOCKET4677_AZIFS054P001C01-SOCA
M_H_CPU1_SA_DQ<28>       J31              47       SCONN288_ADR50001P013C01-SCONNA
M_H_CPU1_SA_DQ<28>       J32              47       SCONN288_ADR50001P003C01-SCONNA
M_H_CPU1_SA_DQ<28>       U1               DC60     SOCKET4677_AZIFS054P001C01-SOCA
M_H_CPU1_SA_DQ<29>       J31              49       SCONN288_ADR50001P013C01-SCONNA
M_H_CPU1_SA_DQ<29>       J32              49       SCONN288_ADR50001P003C01-SCONNA
M_H_CPU1_SA_DQ<29>       U1               DD59     SOCKET4677_AZIFS054P001C01-SOCA
M_H_CPU1_SA_DQ<30>       J31              192      SCONN288_ADR50001P013C01-SCONNA
M_H_CPU1_SA_DQ<30>       J32              192      SCONN288_ADR50001P003C01-SCONNA
M_H_CPU1_SA_DQ<30>       U1               DG60     SOCKET4677_AZIFS054P001C01-SOCA
M_H_CPU1_SA_DQ<31>       J31              194      SCONN288_ADR50001P013C01-SCONNA
M_H_CPU1_SA_DQ<31>       J32              194      SCONN288_ADR50001P003C01-SCONNA
M_H_CPU1_SA_DQ<31>       U1               DF59     SOCKET4677_AZIFS054P001C01-SOCA
M_H_CPU1_SA_DQS_DN<0>    J31              12       SCONN288_ADR50001P013C01-SCONNA
M_H_CPU1_SA_DQS_DN<0>    J32              12       SCONN288_ADR50001P003C01-SCONNA
M_H_CPU1_SA_DQS_DN<0>    U1               DJ76     SOCKET4677_AZIFS054P001C01-SOCA
M_H_CPU1_SA_DQS_DN<1>    J31              23       SCONN288_ADR50001P013C01-SCONNA
M_H_CPU1_SA_DQS_DN<1>    J32              23       SCONN288_ADR50001P003C01-SCONNA
M_H_CPU1_SA_DQS_DN<1>    U1               DB73     SOCKET4677_AZIFS054P001C01-SOCA
M_H_CPU1_SA_DQS_DN<2>    J31              34       SCONN288_ADR50001P013C01-SCONNA
M_H_CPU1_SA_DQS_DN<2>    J32              34       SCONN288_ADR50001P003C01-SCONNA
M_H_CPU1_SA_DQS_DN<2>    U1               DD67     SOCKET4677_AZIFS054P001C01-SOCA
M_H_CPU1_SA_DQS_DN<3>    J31              45       SCONN288_ADR50001P013C01-SCONNA
M_H_CPU1_SA_DQS_DN<3>    J32              45       SCONN288_ADR50001P003C01-SCONNA
M_H_CPU1_SA_DQS_DN<3>    U1               DD61     SOCKET4677_AZIFS054P001C01-SOCA
M_H_CPU1_SA_DQS_DN<4>    J31              56       SCONN288_ADR50001P013C01-SCONNA
M_H_CPU1_SA_DQS_DN<4>    J32              56       SCONN288_ADR50001P003C01-SCONNA
M_H_CPU1_SA_DQS_DN<4>    U1               DD55     SOCKET4677_AZIFS054P001C01-SOCA
M_H_CPU1_SA_DQS_DN<5>    J31              156      SCONN288_ADR50001P013C01-SCONNA
M_H_CPU1_SA_DQS_DN<5>    J32              156      SCONN288_ADR50001P003C01-SCONNA
M_H_CPU1_SA_DQS_DN<5>    U1               DR76     SOCKET4677_AZIFS054P001C01-SOCA
M_H_CPU1_SA_DQS_DN<6>    J31              167      SCONN288_ADR50001P013C01-SCONNA
M_H_CPU1_SA_DQS_DN<6>    J32              167      SCONN288_ADR50001P003C01-SCONNA
M_H_CPU1_SA_DQS_DN<6>    U1               DH73     SOCKET4677_AZIFS054P001C01-SOCA
M_H_CPU1_SA_DQS_DN<7>    J31              178      SCONN288_ADR50001P013C01-SCONNA
M_H_CPU1_SA_DQS_DN<7>    J32              178      SCONN288_ADR50001P003C01-SCONNA
M_H_CPU1_SA_DQS_DN<7>    U1               DH67     SOCKET4677_AZIFS054P001C01-SOCA
M_H_CPU1_SA_DQS_DN<8>    J31              189      SCONN288_ADR50001P013C01-SCONNA
M_H_CPU1_SA_DQS_DN<8>    J32              189      SCONN288_ADR50001P003C01-SCONNA
M_H_CPU1_SA_DQS_DN<8>    U1               DH61     SOCKET4677_AZIFS054P001C01-SOCA
M_H_CPU1_SA_DQS_DN<9>    J31              200      SCONN288_ADR50001P013C01-SCONNA
M_H_CPU1_SA_DQS_DN<9>    J32              200      SCONN288_ADR50001P003C01-SCONNA
M_H_CPU1_SA_DQS_DN<9>    U1               DH55     SOCKET4677_AZIFS054P001C01-SOCA
M_H_CPU1_SA_DQS_DP<0>    J31              11       SCONN288_ADR50001P013C01-SCONNA
M_H_CPU1_SA_DQS_DP<0>    J32              11       SCONN288_ADR50001P003C01-SCONNA
M_H_CPU1_SA_DQS_DP<0>    U1               DL76     SOCKET4677_AZIFS054P001C01-SOCA
M_H_CPU1_SA_DQS_DP<1>    J31              22       SCONN288_ADR50001P013C01-SCONNA
M_H_CPU1_SA_DQS_DP<1>    J32              22       SCONN288_ADR50001P003C01-SCONNA
M_H_CPU1_SA_DQS_DP<1>    U1               DD73     SOCKET4677_AZIFS054P001C01-SOCA
M_H_CPU1_SA_DQS_DP<2>    J31              33       SCONN288_ADR50001P013C01-SCONNA
M_H_CPU1_SA_DQS_DP<2>    J32              33       SCONN288_ADR50001P003C01-SCONNA
M_H_CPU1_SA_DQS_DP<2>    U1               DB67     SOCKET4677_AZIFS054P001C01-SOCA
M_H_CPU1_SA_DQS_DP<3>    J31              44       SCONN288_ADR50001P013C01-SCONNA
M_H_CPU1_SA_DQS_DP<3>    J32              44       SCONN288_ADR50001P003C01-SCONNA
M_H_CPU1_SA_DQS_DP<3>    U1               DB61     SOCKET4677_AZIFS054P001C01-SOCA
M_H_CPU1_SA_DQS_DP<4>    J31              55       SCONN288_ADR50001P013C01-SCONNA
M_H_CPU1_SA_DQS_DP<4>    J32              55       SCONN288_ADR50001P003C01-SCONNA
M_H_CPU1_SA_DQS_DP<4>    U1               DB55     SOCKET4677_AZIFS054P001C01-SOCA
M_H_CPU1_SA_DQS_DP<5>    J31              157      SCONN288_ADR50001P013C01-SCONNA
M_H_CPU1_SA_DQS_DP<5>    J32              157      SCONN288_ADR50001P003C01-SCONNA
M_H_CPU1_SA_DQS_DP<5>    U1               DN76     SOCKET4677_AZIFS054P001C01-SOCA
M_H_CPU1_SA_DQS_DP<6>    J31              168      SCONN288_ADR50001P013C01-SCONNA
M_H_CPU1_SA_DQS_DP<6>    J32              168      SCONN288_ADR50001P003C01-SCONNA
M_H_CPU1_SA_DQS_DP<6>    U1               DF73     SOCKET4677_AZIFS054P001C01-SOCA
M_H_CPU1_SA_DQS_DP<7>    J31              179      SCONN288_ADR50001P013C01-SCONNA
M_H_CPU1_SA_DQS_DP<7>    J32              179      SCONN288_ADR50001P003C01-SCONNA
M_H_CPU1_SA_DQS_DP<7>    U1               DF67     SOCKET4677_AZIFS054P001C01-SOCA
M_H_CPU1_SA_DQS_DP<8>    J31              190      SCONN288_ADR50001P013C01-SCONNA
M_H_CPU1_SA_DQS_DP<8>    J32              190      SCONN288_ADR50001P003C01-SCONNA
M_H_CPU1_SA_DQS_DP<8>    U1               DF61     SOCKET4677_AZIFS054P001C01-SOCA
M_H_CPU1_SA_DQS_DP<9>    J31              201      SCONN288_ADR50001P013C01-SCONNA
M_H_CPU1_SA_DQS_DP<9>    J32              201      SCONN288_ADR50001P003C01-SCONNA
M_H_CPU1_SA_DQS_DP<9>    U1               DF55     SOCKET4677_AZIFS054P001C01-SOCA
M_H_CPU1_SA_PAR          J31              74       SCONN288_ADR50001P013C01-SCONNA
M_H_CPU1_SA_PAR          J32              74       SCONN288_ADR50001P003C01-SCONNA
M_H_CPU1_SA_PAR          U1               DD40     SOCKET4677_AZIFS054P001C01-SOCA
M_H_CPU1_SA_RSP<0>       J31              86       SCONN288_ADR50001P013C01-SCONNA
M_H_CPU1_SA_RSP<0>       U1               EG48     SOCKET4677_AZIFS054P001C01-SOCA
M_H_CPU1_SA_RSP<1>       J32              86       SCONN288_ADR50001P003C01-SCONNA
M_H_CPU1_SA_RSP<1>       U1               EH47     SOCKET4677_AZIFS054P001C01-SOCA
M_H_CPU1_SB_CA<0>        J31              76       SCONN288_ADR50001P013C01-SCONNA
M_H_CPU1_SB_CA<0>        J32              76       SCONN288_ADR50001P003C01-SCONNA
M_H_CPU1_SB_CA<0>        U1               DF40     SOCKET4677_AZIFS054P001C01-SOCA
M_H_CPU1_SB_CA<1>        J31              221      SCONN288_ADR50001P013C01-SCONNA
M_H_CPU1_SB_CA<1>        J32              221      SCONN288_ADR50001P003C01-SCONNA
M_H_CPU1_SB_CA<1>        U1               DG41     SOCKET4677_AZIFS054P001C01-SOCA
M_H_CPU1_SB_CA<2>        J31              78       SCONN288_ADR50001P013C01-SCONNA
M_H_CPU1_SB_CA<2>        J32              78       SCONN288_ADR50001P003C01-SCONNA
M_H_CPU1_SB_CA<2>        U1               DL41     SOCKET4677_AZIFS054P001C01-SOCA
M_H_CPU1_SB_CA<3>        J31              223      SCONN288_ADR50001P013C01-SCONNA
M_H_CPU1_SB_CA<3>        J32              223      SCONN288_ADR50001P003C01-SCONNA
M_H_CPU1_SB_CA<3>        U1               DN41     SOCKET4677_AZIFS054P001C01-SOCA
M_H_CPU1_SB_CA<4>        J31              80       SCONN288_ADR50001P013C01-SCONNA
M_H_CPU1_SB_CA<4>        J32              80       SCONN288_ADR50001P003C01-SCONNA
M_H_CPU1_SB_CA<4>        U1               DK40     SOCKET4677_AZIFS054P001C01-SOCA
M_H_CPU1_SB_CA<5>        J31              225      SCONN288_ADR50001P013C01-SCONNA
M_H_CPU1_SB_CA<5>        J32              225      SCONN288_ADR50001P003C01-SCONNA
M_H_CPU1_SB_CA<5>        U1               DP40     SOCKET4677_AZIFS054P001C01-SOCA
M_H_CPU1_SB_CA<6>        J31              82       SCONN288_ADR50001P013C01-SCONNA
M_H_CPU1_SB_CA<6>        J32              82       SCONN288_ADR50001P003C01-SCONNA
M_H_CPU1_SB_CA<6>        U1               DJ39     SOCKET4677_AZIFS054P001C01-SOCA
M_H_CPU1_SB_CB<0>        J31              96       SCONN288_ADR50001P013C01-SCONNA
M_H_CPU1_SB_CB<0>        J32              96       SCONN288_ADR50001P003C01-SCONNA
M_H_CPU1_SB_CB<0>        U1               DC35     SOCKET4677_AZIFS054P001C01-SOCA
M_H_CPU1_SB_CB<1>        J31              98       SCONN288_ADR50001P013C01-SCONNA
M_H_CPU1_SB_CB<1>        J32              98       SCONN288_ADR50001P003C01-SCONNA
M_H_CPU1_SB_CB<1>        U1               DD34     SOCKET4677_AZIFS054P001C01-SOCA
M_H_CPU1_SB_CB<2>        J31              241      SCONN288_ADR50001P013C01-SCONNA
M_H_CPU1_SB_CB<2>        J32              241      SCONN288_ADR50001P003C01-SCONNA
M_H_CPU1_SB_CB<2>        U1               DG35     SOCKET4677_AZIFS054P001C01-SOCA
M_H_CPU1_SB_CB<3>        J31              243      SCONN288_ADR50001P013C01-SCONNA
M_H_CPU1_SB_CB<3>        J32              243      SCONN288_ADR50001P003C01-SCONNA
M_H_CPU1_SB_CB<3>        U1               DF34     SOCKET4677_AZIFS054P001C01-SOCA
M_H_CPU1_SB_CB<4>        J31              89       SCONN288_ADR50001P013C01-SCONNA
M_H_CPU1_SB_CB<4>        J32              89       SCONN288_ADR50001P003C01-SCONNA
M_H_CPU1_SB_CB<4>        U1               DF38     SOCKET4677_AZIFS054P001C01-SOCA
M_H_CPU1_SB_CB<5>        J31              91       SCONN288_ADR50001P013C01-SCONNA
M_H_CPU1_SB_CB<5>        J32              91       SCONN288_ADR50001P003C01-SCONNA
M_H_CPU1_SB_CB<5>        U1               DG37     SOCKET4677_AZIFS054P001C01-SOCA
M_H_CPU1_SB_CB<6>        J31              234      SCONN288_ADR50001P013C01-SCONNA
M_H_CPU1_SB_CB<6>        J32              234      SCONN288_ADR50001P003C01-SCONNA
M_H_CPU1_SB_CB<6>        U1               DD38     SOCKET4677_AZIFS054P001C01-SOCA
M_H_CPU1_SB_CB<7>        J31              236      SCONN288_ADR50001P013C01-SCONNA
M_H_CPU1_SB_CB<7>        J32              236      SCONN288_ADR50001P003C01-SCONNA
M_H_CPU1_SB_CB<7>        U1               DC37     SOCKET4677_AZIFS054P001C01-SOCA
M_H_CPU1_SB_CS_N<0>      J31              84       SCONN288_ADR50001P013C01-SCONNA
M_H_CPU1_SB_CS_N<0>      U1               DL37     SOCKET4677_AZIFS054P001C01-SOCA
M_H_CPU1_SB_CS_N<1>      J31              229      SCONN288_ADR50001P013C01-SCONNA
M_H_CPU1_SB_CS_N<1>      U1               DN37     SOCKET4677_AZIFS054P001C01-SOCA
M_H_CPU1_SB_CS_N<2>      J32              84       SCONN288_ADR50001P003C01-SCONNA
M_H_CPU1_SB_CS_N<2>      U1               DK38     SOCKET4677_AZIFS054P001C01-SOCA
M_H_CPU1_SB_CS_N<3>      J32              229      SCONN288_ADR50001P003C01-SCONNA
M_H_CPU1_SB_CS_N<3>      U1               DP38     SOCKET4677_AZIFS054P001C01-SOCA
M_H_CPU1_SB_DQ<0>        J31              100      SCONN288_ADR50001P013C01-SCONNA
M_H_CPU1_SB_DQ<0>        J32              100      SCONN288_ADR50001P003C01-SCONNA
M_H_CPU1_SB_DQ<0>        U1               DD32     SOCKET4677_AZIFS054P001C01-SOCA
M_H_CPU1_SB_DQ<1>        J31              102      SCONN288_ADR50001P013C01-SCONNA
M_H_CPU1_SB_DQ<1>        J32              102      SCONN288_ADR50001P003C01-SCONNA
M_H_CPU1_SB_DQ<1>        U1               DC31     SOCKET4677_AZIFS054P001C01-SOCA
M_H_CPU1_SB_DQ<2>        J31              245      SCONN288_ADR50001P013C01-SCONNA
M_H_CPU1_SB_DQ<2>        J32              245      SCONN288_ADR50001P003C01-SCONNA
M_H_CPU1_SB_DQ<2>        U1               DF32     SOCKET4677_AZIFS054P001C01-SOCA
M_H_CPU1_SB_DQ<3>        J31              247      SCONN288_ADR50001P013C01-SCONNA
M_H_CPU1_SB_DQ<3>        J32              247      SCONN288_ADR50001P003C01-SCONNA
M_H_CPU1_SB_DQ<3>        U1               DG31     SOCKET4677_AZIFS054P001C01-SOCA
M_H_CPU1_SB_DQ<4>        J31              107      SCONN288_ADR50001P013C01-SCONNA
M_H_CPU1_SB_DQ<4>        J32              107      SCONN288_ADR50001P003C01-SCONNA
M_H_CPU1_SB_DQ<4>        U1               DC29     SOCKET4677_AZIFS054P001C01-SOCA
M_H_CPU1_SB_DQ<5>        J31              109      SCONN288_ADR50001P013C01-SCONNA
M_H_CPU1_SB_DQ<5>        J32              109      SCONN288_ADR50001P003C01-SCONNA
M_H_CPU1_SB_DQ<5>        U1               DF28     SOCKET4677_AZIFS054P001C01-SOCA
M_H_CPU1_SB_DQ<6>        J31              252      SCONN288_ADR50001P013C01-SCONNA
M_H_CPU1_SB_DQ<6>        J32              252      SCONN288_ADR50001P003C01-SCONNA
M_H_CPU1_SB_DQ<6>        U1               DG29     SOCKET4677_AZIFS054P001C01-SOCA
M_H_CPU1_SB_DQ<7>        J31              254      SCONN288_ADR50001P013C01-SCONNA
M_H_CPU1_SB_DQ<7>        J32              254      SCONN288_ADR50001P003C01-SCONNA
M_H_CPU1_SB_DQ<7>        U1               DD28     SOCKET4677_AZIFS054P001C01-SOCA
M_H_CPU1_SB_DQ<8>        J31              111      SCONN288_ADR50001P013C01-SCONNA
M_H_CPU1_SB_DQ<8>        J32              111      SCONN288_ADR50001P003C01-SCONNA
M_H_CPU1_SB_DQ<8>        U1               DD26     SOCKET4677_AZIFS054P001C01-SOCA
M_H_CPU1_SB_DQ<9>        J31              113      SCONN288_ADR50001P013C01-SCONNA
M_H_CPU1_SB_DQ<9>        J32              113      SCONN288_ADR50001P003C01-SCONNA
M_H_CPU1_SB_DQ<9>        U1               DC25     SOCKET4677_AZIFS054P001C01-SOCA
M_H_CPU1_SB_DQ<10>       J31              256      SCONN288_ADR50001P013C01-SCONNA
M_H_CPU1_SB_DQ<10>       J32              256      SCONN288_ADR50001P003C01-SCONNA
M_H_CPU1_SB_DQ<10>       U1               DF26     SOCKET4677_AZIFS054P001C01-SOCA
M_H_CPU1_SB_DQ<11>       J31              258      SCONN288_ADR50001P013C01-SCONNA
M_H_CPU1_SB_DQ<11>       J32              258      SCONN288_ADR50001P003C01-SCONNA
M_H_CPU1_SB_DQ<11>       U1               DG25     SOCKET4677_AZIFS054P001C01-SOCA
M_H_CPU1_SB_DQ<12>       J31              118      SCONN288_ADR50001P013C01-SCONNA
M_H_CPU1_SB_DQ<12>       J32              118      SCONN288_ADR50001P003C01-SCONNA
M_H_CPU1_SB_DQ<12>       U1               DC23     SOCKET4677_AZIFS054P001C01-SOCA
M_H_CPU1_SB_DQ<13>       J31              120      SCONN288_ADR50001P013C01-SCONNA
M_H_CPU1_SB_DQ<13>       J32              120      SCONN288_ADR50001P003C01-SCONNA
M_H_CPU1_SB_DQ<13>       U1               DD22     SOCKET4677_AZIFS054P001C01-SOCA
M_H_CPU1_SB_DQ<14>       J31              263      SCONN288_ADR50001P013C01-SCONNA
M_H_CPU1_SB_DQ<14>       J32              263      SCONN288_ADR50001P003C01-SCONNA
M_H_CPU1_SB_DQ<14>       U1               DG23     SOCKET4677_AZIFS054P001C01-SOCA
M_H_CPU1_SB_DQ<15>       J31              265      SCONN288_ADR50001P013C01-SCONNA
M_H_CPU1_SB_DQ<15>       J32              265      SCONN288_ADR50001P003C01-SCONNA
M_H_CPU1_SB_DQ<15>       U1               DF22     SOCKET4677_AZIFS054P001C01-SOCA
M_H_CPU1_SB_DQ<16>       J31              122      SCONN288_ADR50001P013C01-SCONNA
M_H_CPU1_SB_DQ<16>       J32              122      SCONN288_ADR50001P003C01-SCONNA
M_H_CPU1_SB_DQ<16>       U1               DL23     SOCKET4677_AZIFS054P001C01-SOCA
M_H_CPU1_SB_DQ<17>       J31              124      SCONN288_ADR50001P013C01-SCONNA
M_H_CPU1_SB_DQ<17>       J32              124      SCONN288_ADR50001P003C01-SCONNA
M_H_CPU1_SB_DQ<17>       U1               DK22     SOCKET4677_AZIFS054P001C01-SOCA
M_H_CPU1_SB_DQ<18>       J31              267      SCONN288_ADR50001P013C01-SCONNA
M_H_CPU1_SB_DQ<18>       J32              267      SCONN288_ADR50001P003C01-SCONNA
M_H_CPU1_SB_DQ<18>       U1               DN23     SOCKET4677_AZIFS054P001C01-SOCA
M_H_CPU1_SB_DQ<19>       J31              269      SCONN288_ADR50001P013C01-SCONNA
M_H_CPU1_SB_DQ<19>       J32              269      SCONN288_ADR50001P003C01-SCONNA
M_H_CPU1_SB_DQ<19>       U1               DP22     SOCKET4677_AZIFS054P001C01-SOCA
M_H_CPU1_SB_DQ<20>       J31              129      SCONN288_ADR50001P013C01-SCONNA
M_H_CPU1_SB_DQ<20>       J32              129      SCONN288_ADR50001P003C01-SCONNA
M_H_CPU1_SB_DQ<20>       U1               DK20     SOCKET4677_AZIFS054P001C01-SOCA
M_H_CPU1_SB_DQ<21>       J31              131      SCONN288_ADR50001P013C01-SCONNA
M_H_CPU1_SB_DQ<21>       J32              131      SCONN288_ADR50001P003C01-SCONNA
M_H_CPU1_SB_DQ<21>       U1               DL19     SOCKET4677_AZIFS054P001C01-SOCA
M_H_CPU1_SB_DQ<22>       J31              274      SCONN288_ADR50001P013C01-SCONNA
M_H_CPU1_SB_DQ<22>       J32              274      SCONN288_ADR50001P003C01-SCONNA
M_H_CPU1_SB_DQ<22>       U1               DP20     SOCKET4677_AZIFS054P001C01-SOCA
M_H_CPU1_SB_DQ<23>       J31              276      SCONN288_ADR50001P013C01-SCONNA
M_H_CPU1_SB_DQ<23>       J32              276      SCONN288_ADR50001P003C01-SCONNA
M_H_CPU1_SB_DQ<23>       U1               DN19     SOCKET4677_AZIFS054P001C01-SOCA
M_H_CPU1_SB_DQ<24>       J31              133      SCONN288_ADR50001P013C01-SCONNA
M_H_CPU1_SB_DQ<24>       J32              133      SCONN288_ADR50001P003C01-SCONNA
M_H_CPU1_SB_DQ<24>       U1               DD20     SOCKET4677_AZIFS054P001C01-SOCA
M_H_CPU1_SB_DQ<25>       J31              135      SCONN288_ADR50001P013C01-SCONNA
M_H_CPU1_SB_DQ<25>       J32              135      SCONN288_ADR50001P003C01-SCONNA
M_H_CPU1_SB_DQ<25>       U1               DC19     SOCKET4677_AZIFS054P001C01-SOCA
M_H_CPU1_SB_DQ<26>       J31              278      SCONN288_ADR50001P013C01-SCONNA
M_H_CPU1_SB_DQ<26>       J32              278      SCONN288_ADR50001P003C01-SCONNA
M_H_CPU1_SB_DQ<26>       U1               DF20     SOCKET4677_AZIFS054P001C01-SOCA
M_H_CPU1_SB_DQ<27>       J31              280      SCONN288_ADR50001P013C01-SCONNA
M_H_CPU1_SB_DQ<27>       J32              280      SCONN288_ADR50001P003C01-SCONNA
M_H_CPU1_SB_DQ<27>       U1               DG19     SOCKET4677_AZIFS054P001C01-SOCA
M_H_CPU1_SB_DQ<28>       J31              140      SCONN288_ADR50001P013C01-SCONNA
M_H_CPU1_SB_DQ<28>       J32              140      SCONN288_ADR50001P003C01-SCONNA
M_H_CPU1_SB_DQ<28>       U1               DG17     SOCKET4677_AZIFS054P001C01-SOCA
M_H_CPU1_SB_DQ<29>       J31              142      SCONN288_ADR50001P013C01-SCONNA
M_H_CPU1_SB_DQ<29>       J32              142      SCONN288_ADR50001P003C01-SCONNA
M_H_CPU1_SB_DQ<29>       U1               DA17     SOCKET4677_AZIFS054P001C01-SOCA
M_H_CPU1_SB_DQ<30>       J31              285      SCONN288_ADR50001P013C01-SCONNA
M_H_CPU1_SB_DQ<30>       J32              285      SCONN288_ADR50001P003C01-SCONNA
M_H_CPU1_SB_DQ<30>       U1               DJ17     SOCKET4677_AZIFS054P001C01-SOCA
M_H_CPU1_SB_DQ<31>       J31              287      SCONN288_ADR50001P013C01-SCONNA
M_H_CPU1_SB_DQ<31>       J32              287      SCONN288_ADR50001P003C01-SCONNA
M_H_CPU1_SB_DQ<31>       U1               DC17     SOCKET4677_AZIFS054P001C01-SOCA
M_H_CPU1_SB_DQS_DN<0>    J31              105      SCONN288_ADR50001P013C01-SCONNA
M_H_CPU1_SB_DQS_DN<0>    J32              105      SCONN288_ADR50001P003C01-SCONNA
M_H_CPU1_SB_DQS_DN<0>    U1               DD30     SOCKET4677_AZIFS054P001C01-SOCA
M_H_CPU1_SB_DQS_DN<1>    J31              116      SCONN288_ADR50001P013C01-SCONNA
M_H_CPU1_SB_DQS_DN<1>    J32              116      SCONN288_ADR50001P003C01-SCONNA
M_H_CPU1_SB_DQS_DN<1>    U1               DD24     SOCKET4677_AZIFS054P001C01-SOCA
M_H_CPU1_SB_DQS_DN<2>    J31              127      SCONN288_ADR50001P013C01-SCONNA
M_H_CPU1_SB_DQS_DN<2>    J32              127      SCONN288_ADR50001P003C01-SCONNA
M_H_CPU1_SB_DQS_DN<2>    U1               DL21     SOCKET4677_AZIFS054P001C01-SOCA
M_H_CPU1_SB_DQS_DN<3>    J31              138      SCONN288_ADR50001P013C01-SCONNA
M_H_CPU1_SB_DQS_DN<3>    J32              138      SCONN288_ADR50001P003C01-SCONNA
M_H_CPU1_SB_DQS_DN<3>    U1               DB18     SOCKET4677_AZIFS054P001C01-SOCA
M_H_CPU1_SB_DQS_DN<4>    J31              238      SCONN288_ADR50001P013C01-SCONNA
M_H_CPU1_SB_DQS_DN<4>    J32              238      SCONN288_ADR50001P003C01-SCONNA
M_H_CPU1_SB_DQS_DN<4>    U1               DH36     SOCKET4677_AZIFS054P001C01-SOCA
M_H_CPU1_SB_DQS_DN<5>    J31              249      SCONN288_ADR50001P013C01-SCONNA
M_H_CPU1_SB_DQS_DN<5>    J32              249      SCONN288_ADR50001P003C01-SCONNA
M_H_CPU1_SB_DQS_DN<5>    U1               DH30     SOCKET4677_AZIFS054P001C01-SOCA
M_H_CPU1_SB_DQS_DN<6>    J31              260      SCONN288_ADR50001P013C01-SCONNA
M_H_CPU1_SB_DQS_DN<6>    J32              260      SCONN288_ADR50001P003C01-SCONNA
M_H_CPU1_SB_DQS_DN<6>    U1               DH24     SOCKET4677_AZIFS054P001C01-SOCA
M_H_CPU1_SB_DQS_DN<7>    J31              271      SCONN288_ADR50001P013C01-SCONNA
M_H_CPU1_SB_DQS_DN<7>    J32              271      SCONN288_ADR50001P003C01-SCONNA
M_H_CPU1_SB_DQS_DN<7>    U1               DR21     SOCKET4677_AZIFS054P001C01-SOCA
M_H_CPU1_SB_DQS_DN<8>    J31              282      SCONN288_ADR50001P013C01-SCONNA
M_H_CPU1_SB_DQS_DN<8>    J32              282      SCONN288_ADR50001P003C01-SCONNA
M_H_CPU1_SB_DQS_DN<8>    U1               DF18     SOCKET4677_AZIFS054P001C01-SOCA
M_H_CPU1_SB_DQS_DN<9>    J31              94       SCONN288_ADR50001P013C01-SCONNA
M_H_CPU1_SB_DQS_DN<9>    J32              94       SCONN288_ADR50001P003C01-SCONNA
M_H_CPU1_SB_DQS_DN<9>    U1               DD36     SOCKET4677_AZIFS054P001C01-SOCA
M_H_CPU1_SB_DQS_DP<0>    J31              104      SCONN288_ADR50001P013C01-SCONNA
M_H_CPU1_SB_DQS_DP<0>    J32              104      SCONN288_ADR50001P003C01-SCONNA
M_H_CPU1_SB_DQS_DP<0>    U1               DB30     SOCKET4677_AZIFS054P001C01-SOCA
M_H_CPU1_SB_DQS_DP<1>    J31              115      SCONN288_ADR50001P013C01-SCONNA
M_H_CPU1_SB_DQS_DP<1>    J32              115      SCONN288_ADR50001P003C01-SCONNA
M_H_CPU1_SB_DQS_DP<1>    U1               DB24     SOCKET4677_AZIFS054P001C01-SOCA
M_H_CPU1_SB_DQS_DP<2>    J31              126      SCONN288_ADR50001P013C01-SCONNA
M_H_CPU1_SB_DQS_DP<2>    J32              126      SCONN288_ADR50001P003C01-SCONNA
M_H_CPU1_SB_DQS_DP<2>    U1               DJ21     SOCKET4677_AZIFS054P001C01-SOCA
M_H_CPU1_SB_DQS_DP<3>    J31              137      SCONN288_ADR50001P013C01-SCONNA
M_H_CPU1_SB_DQS_DP<3>    J32              137      SCONN288_ADR50001P003C01-SCONNA
M_H_CPU1_SB_DQS_DP<3>    U1               DD18     SOCKET4677_AZIFS054P001C01-SOCA
M_H_CPU1_SB_DQS_DP<4>    J31              239      SCONN288_ADR50001P013C01-SCONNA
M_H_CPU1_SB_DQS_DP<4>    J32              239      SCONN288_ADR50001P003C01-SCONNA
M_H_CPU1_SB_DQS_DP<4>    U1               DF36     SOCKET4677_AZIFS054P001C01-SOCA
M_H_CPU1_SB_DQS_DP<5>    J31              250      SCONN288_ADR50001P013C01-SCONNA
M_H_CPU1_SB_DQS_DP<5>    J32              250      SCONN288_ADR50001P003C01-SCONNA
M_H_CPU1_SB_DQS_DP<5>    U1               DF30     SOCKET4677_AZIFS054P001C01-SOCA
M_H_CPU1_SB_DQS_DP<6>    J31              261      SCONN288_ADR50001P013C01-SCONNA
M_H_CPU1_SB_DQS_DP<6>    J32              261      SCONN288_ADR50001P003C01-SCONNA
M_H_CPU1_SB_DQS_DP<6>    U1               DF24     SOCKET4677_AZIFS054P001C01-SOCA
M_H_CPU1_SB_DQS_DP<7>    J31              272      SCONN288_ADR50001P013C01-SCONNA
M_H_CPU1_SB_DQS_DP<7>    J32              272      SCONN288_ADR50001P003C01-SCONNA
M_H_CPU1_SB_DQS_DP<7>    U1               DN21     SOCKET4677_AZIFS054P001C01-SOCA
M_H_CPU1_SB_DQS_DP<8>    J31              283      SCONN288_ADR50001P013C01-SCONNA
M_H_CPU1_SB_DQS_DP<8>    J32              283      SCONN288_ADR50001P003C01-SCONNA
M_H_CPU1_SB_DQS_DP<8>    U1               DH18     SOCKET4677_AZIFS054P001C01-SOCA
M_H_CPU1_SB_DQS_DP<9>    J31              93       SCONN288_ADR50001P013C01-SCONNA
M_H_CPU1_SB_DQS_DP<9>    J32              93       SCONN288_ADR50001P003C01-SCONNA
M_H_CPU1_SB_DQS_DP<9>    U1               DB36     SOCKET4677_AZIFS054P001C01-SOCA
M_H_CPU1_SB_PAR          J31              227      SCONN288_ADR50001P013C01-SCONNA
M_H_CPU1_SB_PAR          J32              227      SCONN288_ADR50001P003C01-SCONNA
M_H_CPU1_SB_PAR          U1               DR39     SOCKET4677_AZIFS054P001C01-SOCA
M_H_CPU1_SB_RSP<0>       J31              87       SCONN288_ADR50001P013C01-SCONNA
M_H_CPU1_SB_RSP<0>       U1               EE48     SOCKET4677_AZIFS054P001C01-SOCA
M_H_CPU1_SB_RSP<1>       J32              87       SCONN288_ADR50001P003C01-SCONNA
M_H_CPU1_SB_RSP<1>       U1               ED47     SOCKET4677_AZIFS054P001C01-SOCA
NCSI_BMC_CRS_DV_R        R1291            1        Q_RES_0402LF-22,1%,1/16W,CHIP,A
NCSI_BMC_CRS_DV_R        U67              9        74CBTLV3126PW-74CBTLV3126PW,SMA
NCSI_BMC_RXD0_R          R1292            1        Q_RES_0402LF-22,1%,1/16W,CHIP,A
NCSI_BMC_RXD0_R          U67              5        74CBTLV3126PW-74CBTLV3126PW,SMA
NCSI_BMC_RXD1_R          R1293            1        Q_RES_0402LF-22,1%,1/16W,CHIP,A
NCSI_BMC_RXD1_R          U67              2        74CBTLV3126PW-74CBTLV3126PW,SMA
NCSI_BMC_TXD0_R          R1295            1        Q_RES_0402LF-22,1%,1/16W,CHIP,A
NCSI_BMC_TXD0_R          U68              5        74CBTLV3126PW-74CBTLV3126PW,SMA
NCSI_BMC_TXD1_R          R1296            1        Q_RES_0402LF-22,1%,1/16W,CHIP,A
NCSI_BMC_TXD1_R          U68              2        74CBTLV3126PW-74CBTLV3126PW,SMA
NCSI_BMC_TX_EN_R         R1294            1        Q_RES_0402LF-22,1%,1/16W,CHIP,A
NCSI_BMC_TX_EN_R         U68              9        74CBTLV3126PW-74CBTLV3126PW,SMA
NCSI_OCP_SFF_CRS_DV      J37              OCP_B14  SCONN168_623403212-SCONN168_6-A
NCSI_OCP_SFF_CRS_DV      U67              8        74CBTLV3126PW-74CBTLV3126PW,SMA
NCSI_OCP_SFF_RXD0        J37              OCP_B9   SCONN168_623403212-SCONN168_6-A
NCSI_OCP_SFF_RXD0        U67              6        74CBTLV3126PW-74CBTLV3126PW,SMA
NCSI_OCP_SFF_RXD1        J37              OCP_B8   SCONN168_623403212-SCONN168_6-A
NCSI_OCP_SFF_RXD1        U67              3        74CBTLV3126PW-74CBTLV3126PW,SMA
NCSI_OCP_SFF_TXD0        J37              OCP_A9   SCONN168_623403212-SCONN168_6-A
NCSI_OCP_SFF_TXD0        U68              6        74CBTLV3126PW-74CBTLV3126PW,SMA
NCSI_OCP_SFF_TXD1        J37              OCP_A8   SCONN168_623403212-SCONN168_6-A
NCSI_OCP_SFF_TXD1        U68              3        74CBTLV3126PW-74CBTLV3126PW,SMA
NCSI_OCP_SFF_TX_EN       J37              OCP_A7   SCONN168_623403212-SCONN168_6-A
NCSI_OCP_SFF_TX_EN       U68              8        74CBTLV3126PW-74CBTLV3126PW,SMA
OCP_SFF_AUX_PWR_EN       R923             1        Q_RES_0402LF-33.2,1%,1/16W,CHIA
OCP_SFF_AUX_PWR_EN       R1671            1        Q_RES_0402LF-0,5%,1/16W,CHIP,CA
OCP_SFF_AUX_PWR_EN       R1719            1        Q_RES_0402LF-33.2,1%,1/16W,CHIA
OCP_SFF_AUX_PWR_EN       R1929            2        Q_RES_0402LF-10K,5%,1/16W,CHIPA
OCP_SFF_AUX_PWR_EN       U122             K7       10M04SAU324I7G-10M04SAU324I7G,A
OCP_SFF_AUX_PWR_EN_R     J37              B12      SCONN168_623403212-SCONN168_6-A
OCP_SFF_AUX_PWR_EN_R     R1671            2        Q_RES_0402LF-0,5%,1/16W,CHIP,CA
OCP_SFF_AUX_PWR_EN_R1    R1719            2        Q_RES_0402LF-33.2,1%,1/16W,CHIA
OCP_SFF_AUX_PWR_EN_R1    U66              1        74HC1G126GW-74HC1G126GW,SMLF,IA
OCP_SFF_AUX_PWR_EN_R2    R923             2        Q_RES_0402LF-33.2,1%,1/16W,CHIA
OCP_SFF_AUX_PWR_EN_R2    U77              1        74CBTLV3126PW-74CBTLV3126PW,SMB
OCP_SFF_AUX_PWR_EN_R2    U77              4        74CBTLV3126PW-74CBTLV3126PW,SMB
OCP_SFF_AUX_PWR_EN_R2    U77              10       74CBTLV3126PW-74CBTLV3126PW,SMB
OCP_SFF_BIF0_N           U4               U3       EMMITSBURG_REV0P9-GFNOCPU04302A
OCP_SFF_BIF0_N           U77              9        74CBTLV3126PW-74CBTLV3126PW,SMB
OCP_SFF_BIF0_R_N         J37              B7       SCONN168_623403212-SCONN168_6-A
OCP_SFF_BIF0_R_N         R416             2        Q_RES_0402LF-0,5%,1/16W,CHIP,CA
OCP_SFF_BIF1_N           U4               N2       EMMITSBURG_REV0P9-GFNOCPU04302A
OCP_SFF_BIF1_N           U77              5        74CBTLV3126PW-74CBTLV3126PW,SMB
OCP_SFF_BIF1_R_N         J37              B8       SCONN168_623403212-SCONN168_6-A
OCP_SFF_BIF1_R_N         R417             2        Q_RES_0402LF-0,5%,1/16W,CHIP,CA
OCP_SFF_BIF2_N           U4               P1       EMMITSBURG_REV0P9-GFNOCPU04302A
OCP_SFF_BIF2_N           U77              2        74CBTLV3126PW-74CBTLV3126PW,SMB
OCP_SFF_BIF2_R_N         J37              B9       SCONN168_623403212-SCONN168_6-A
OCP_SFF_BIF2_R_N         R418             2        Q_RES_0402LF-0,5%,1/16W,CHIP,CA
OCP_SFF_ID0              J37              OCP_B7   SCONN168_623403212-SCONN168_6-A
OCP_SFF_ID0              R409             2        Q_RES_0402LF-4.7K,1%,1/16W,EMPA
OCP_SFF_ID0              R410             1        Q_RES_0402LF-4.7K,1%,1/16W,CHIA
OCP_SFF_ID1              J37              OCP_A6   SCONN168_623403212-SCONN168_6-A
OCP_SFF_ID1              R414             2        Q_RES_0402LF-4.7K,1%,1/16W,EMPA
OCP_SFF_ID1              R415             1        Q_RES_0402LF-4.7K,1%,1/16W,CHIA
OCP_SFF_ISO_BIF0_EN      R416             1        Q_RES_0402LF-0,5%,1/16W,CHIP,CA
OCP_SFF_ISO_BIF0_EN      R1896            1        Q_RES_0402LF-100,1%,1/16W,CHIPA
OCP_SFF_ISO_BIF0_EN      U77              8        74CBTLV3126PW-74CBTLV3126PW,SMB
OCP_SFF_ISO_BIF1_EN      R417             1        Q_RES_0402LF-0,5%,1/16W,CHIP,CA
OCP_SFF_ISO_BIF1_EN      R1897            1        Q_RES_0402LF-100,1%,1/16W,CHIPA
OCP_SFF_ISO_BIF1_EN      U77              6        74CBTLV3126PW-74CBTLV3126PW,SMB
OCP_SFF_ISO_BIF2_EN      R418             1        Q_RES_0402LF-0,5%,1/16W,CHIP,CA
OCP_SFF_ISO_BIF2_EN      R1898            1        Q_RES_0402LF-100,1%,1/16W,CHIPA
OCP_SFF_ISO_BIF2_EN      U77              3        74CBTLV3126PW-74CBTLV3126PW,SMB
OCP_SFF_MAIN_PWR_EN      J37              OCP_B2   SCONN168_623403212-SCONN168_6-A
OCP_SFF_MAIN_PWR_EN      R429             2        Q_RES_0402LF-0,5%,1/16W,CHIP,CA
OCP_SFF_MAIN_PWR_EN      R1930            2        Q_RES_0402LF-10K,5%,1/16W,CHIPA
OCP_SFF_PRSNT0_R_N       J37              B42      SCONN168_623403212-SCONN168_6-A
OCP_SFF_PRSNT0_R_N       R1905            2        Q_RES_0402LF-10K,1%,1/16W,CHIPA
OCP_SFF_PRSNT0_R_N       U58              1        SN74LVC2G07DCKR_SMLF-SN74LVC2GA
OCP_SFF_PRSNT1_R_N       J37              A42      SCONN168_623403212-SCONN168_6-A
OCP_SFF_PRSNT1_R_N       R1907            2        Q_RES_0402LF-10K,1%,1/16W,CHIPA
OCP_SFF_PRSNT1_R_N       U58              3        SN74LVC2G07DCKR_SMLF-SN74LVC2GA
OCP_SFF_PRSNT2_R_N       J37              A12      SCONN168_623403212-SCONN168_6-A
OCP_SFF_PRSNT2_R_N       R1906            2        Q_RES_0402LF-10K,1%,1/16W,CHIPA
OCP_SFF_PRSNT2_R_N       U59              1        SN74LVC2G07DCKR_SMLF-SN74LVC2GA
OCP_SFF_PRSNT3_R_N       J37              B70      SCONN168_623403212-SCONN168_6-A
OCP_SFF_PRSNT3_R_N       R1908            2        Q_RES_0402LF-10K,1%,1/16W,CHIPA
OCP_SFF_PRSNT3_R_N       U59              3        SN74LVC2G07DCKR_SMLF-SN74LVC2GA
OCP_SFF_PRSNTA_R_N       J37              A10      SCONN168_623403212-SCONN168_6-A
OCP_SFF_PRSNTA_R_N       R1895            1        Q_RES_0402LF-100,1%,1/16W,CHIPA
OCP_SFF_PWRBRK_BUFF_N    R1593            2        Q_RES_0402LF-4.7K,1%,1/16W,EMPA
OCP_SFF_PWRBRK_BUFF_N    R1595            1        Q_RES_0402LF-33.2,1%,1/16W,CHIA
OCP_SFF_PWRBRK_BUFF_N    U104             4        74LVC1G07GV-74LVC1G07GV,SMLF,IA
OCP_SFF_PWRBRK_N         J37              A70      SCONN168_623403212-SCONN168_6-A
OCP_SFF_PWRBRK_N         R1595            2        Q_RES_0402LF-33.2,1%,1/16W,CHIA
OCP_SFF_RBT_ARB_IN       J37              OCP_A4   SCONN168_623403212-SCONN168_6-A
OCP_SFF_RBT_ARB_IN       R1290            1        Q_RES_0402LF-22,1%,1/16W,CHIP,A
OCP_SFF_RBT_ARB_IN       U67              11       74CBTLV3126PW-74CBTLV3126PW,SMA
OCP_SFF_RBT_ARB_IN       U67              12       74CBTLV3126PW-74CBTLV3126PW,SMA
OCP_SFF_RBT_ARB_OUT      J37              OCP_A5   SCONN168_623403212-SCONN168_6-A
OCP_SFF_RBT_ARB_OUT      R1290            2        Q_RES_0402LF-22,1%,1/16W,CHIP,A
OCP_SFF_RBT_ARB_OUT      U68              11       74CBTLV3126PW-74CBTLV3126PW,SMA
OCP_SFF_RBT_ARB_OUT      U68              12       74CBTLV3126PW-74CBTLV3126PW,SMA
OCP_SFF_USB2_3_DN        J37              A68      SCONN168_623403212-SCONN168_6-A
OCP_SFF_USB2_3_DN        R444             1        Q_RES_0402LF-0,5%,1/16W,CHIP,CA
OCP_SFF_USB2_3_DP        J37              A69      SCONN168_623403212-SCONN168_6-A
OCP_SFF_USB2_3_DP        R445             1        Q_RES_0402LF-0,5%,1/16W,CHIP,CA
OCP_SFF_WAKE_BUFF_N      R1594            1        Q_RES_0402LF-33.2,1%,1/16W,CHIA
OCP_SFF_WAKE_BUFF_N      U82              4        74LVC1G126GW_SMLF-74LVC1G126GWA
P12V_AUX                 C583             1        Q_CAP_C0402-1UF,16V,10%,X6S,CHA
P12V_AUX                 C586             1        Q_CAP_0402-0.1UF,25V,10%,X7R,CA
P12V_AUX                 C1358            1        Q_CAP_0402-0.1UF,25V,10%,X7R,CA
P12V_AUX                 C1359            1        Q_CAP_C0805-10UF,25V,10%,X6S,CA
P12V_AUX                 C1430            1        Q_CAP_0402-0.1UF,25V,10%,X7R,CA
P12V_AUX                 C1431            1        Q_CAP_C0805-10UF,25V,10%,X6S,CA
P12V_AUX                 C1597            1        Q_CAP_0402-0.1UF,25V,10%,X7R,CA
P12V_AUX                 D12              C        DIODE_TVS-SMF14A,SMLF,IC,BCSMFA
P12V_AUX                 J49              6        CONN10_10142708102011LF-CONN10A
P12V_AUX                 J49              7        CONN10_10142708102011LF-CONN10A
P12V_AUX                 J49              8        CONN10_10142708102011LF-CONN10A
P12V_AUX                 J49              9        CONN10_10142708102011LF-CONN10A
P12V_AUX                 J49              10       CONN10_10142708102011LF-CONN10A
P12V_AUX                 J50              6        CONN10_10142708102011LF-CONN10A
P12V_AUX                 J50              7        CONN10_10142708102011LF-CONN10A
P12V_AUX                 J50              8        CONN10_10142708102011LF-CONN10A
P12V_AUX                 J50              9        CONN10_10142708102011LF-CONN10A
P12V_AUX                 J50              10       CONN10_10142708102011LF-CONN10A
P12V_AUX                 PL6              1        Q_INDUCTOR_SMLF-100NH/16A,IND,A
P12V_AUX                 PL14             1        Q_INDUCTOR_SMLF-100NH/16A,IND,A
P12V_AUX                 PL15             1        Q_INDUCTOR_SMLF-50NH/148A,IND,A
P12V_AUX                 PL16             1        Q_INDUCTOR_SMLF-BLM18SN220TN1DA
P12V_AUX                 PL23             1        Q_INDUCTOR_SMLF-100NH/16A,IND,A
P12V_AUX                 PL32             1        Q_INDUCTOR_SMLF-50NH/148A,IND,A
P12V_AUX                 PL43             1        Q_INDUCTOR_SMLF-100NH/16A,IND,A
P12V_AUX                 PL44             1        Q_INDUCTOR_SMLF-100NH/16A,IND,A
P12V_AUX                 PL45             1        Q_INDUCTOR_SMLF-100NH/16A,IND,A
P12V_AUX                 PL64             1        Q_INDUCTOR_SMLF-BLM18SN220TN1DA
P12V_AUX                 PL101            1        Q_INDUCTOR_SMLF-100NH/16A,IND,A
P12V_AUX                 PL110            1        Q_INDUCTOR_SMLF-100NH/16A,IND,A
P12V_AUX                 PR107            1        Q_RES_0402LF-0,5%,1/16W,EMPTY,A
P12V_AUX                 PR108            1        Q_RES_0402LF-0,5%,1/16W,CHIP,CA
P12V_AUX                 PR156            1        Q_RES_0402LF-0,5%,1/16W,CHIP,CA
P12V_AUX                 PR157            1        Q_RES_0402LF-0,5%,1/16W,EMPTY,A
P12V_AUX                 PR260            1        Q_RES_0402LF-0,5%,1/16W,EMPTY,A
P12V_AUX                 PR261            1        Q_RES_0402LF-0,5%,1/16W,CHIP,CA
P12V_AUX                 PR303            1        Q_RES_0402LF-0,5%,1/16W,CHIP,CA
P12V_AUX                 PR304            1        Q_RES_0402LF-0,5%,1/16W,EMPTY,A
P12V_AUX                 PR1945           1        Q_RES_0402LF-510K,5%,1/16W,CHIA
P12V_AUX                 R1642            1        Q_RES_0402LF-10K,5%,1/16W,CHIPA
P12V_AUX                 R1643            1        Q_RES_0402LF-100K,5%,1/16W,CHIA
P12V_AUX                 R1688            1        Q_RES_0402LF-100K,1%,1/16W,CHIA
P12V_AUX                 R1799            1        Q_RES_0402LF-33K    ,1%  ,1/16A
P12V_AUX                 R1837            2        Q_RES_4P_12-0.001,1%,3W,SMLF,CA
P12V_AUX                 R1838            2        Q_RES_4P_12-0.001,1%,3W,SMLF,CA
P12V_AUX                 U57              1        TPS259824ONRGER-TPS259824ONRGEA
P12V_AUX                 U57              2        TPS259824ONRGER-TPS259824ONRGEA
P12V_AUX                 U57              3        TPS259824ONRGER-TPS259824ONRGEA
P12V_AUX                 U57              16       TPS259824ONRGER-TPS259824ONRGEA
P12V_AUX                 U57              25       TPS259824ONRGER-TPS259824ONRGEA
P12V_AUX                 U81              9        MP5981GLUZ-MP5981GLU-Z,SMLF,ICA
P12V_AUX                 U81              10       MP5981GLUZ-MP5981GLU-Z,SMLF,ICA
P12V_AUX                 U81              11       MP5981GLUZ-MP5981GLU-Z,SMLF,ICA
P12V_AUX                 U81              12       MP5981GLUZ-MP5981GLU-Z,SMLF,ICA
P12V_AUX                 U81              13       MP5981GLUZ-MP5981GLU-Z,SMLF,ICA
P12V_AUX                 U81              14       MP5981GLUZ-MP5981GLU-Z,SMLF,ICA
P12V_AUX                 U81              15       MP5981GLUZ-MP5981GLU-Z,SMLF,ICA
P12V_AUX                 U81              16       MP5981GLUZ-MP5981GLU-Z,SMLF,ICA
P12V_AUX                 U107             9        MP5981GLUZ-MP5981GLU-Z,SMLF,ICA
P12V_AUX                 U107             10       MP5981GLUZ-MP5981GLU-Z,SMLF,ICA
P12V_AUX                 U107             11       MP5981GLUZ-MP5981GLU-Z,SMLF,ICA
P12V_AUX                 U107             12       MP5981GLUZ-MP5981GLU-Z,SMLF,ICA
P12V_AUX                 U107             13       MP5981GLUZ-MP5981GLU-Z,SMLF,ICA
P12V_AUX                 U107             14       MP5981GLUZ-MP5981GLU-Z,SMLF,ICA
P12V_AUX                 U107             15       MP5981GLUZ-MP5981GLU-Z,SMLF,ICA
P12V_AUX                 U107             16       MP5981GLUZ-MP5981GLU-Z,SMLF,ICA
P12V_AUX                 U138             3        TPS259540DSGR-TPS259540DSGR,SMA
P12V_AUX                 U138             4        TPS259540DSGR-TPS259540DSGR,SMA
P12V_AUX_SENSE           C1351            1        Q_CAP_0402-0.1UF,25V,10%,X7R,CA
P12V_AUX_SENSE           R1799            2        Q_RES_0402LF-33K    ,1%  ,1/16A
P12V_AUX_SENSE           R1800            1        Q_RES_0402LF-120K,1%,1/16W,CHIA
P12V_AUX_SENSE           U105             7        ADS1015IDGSR-ADS1015IDGSR,SMLFA
P12V_AUX_SENSE           U121             4        MAX11607EUAT-MAX11607EUA+T,SMLA
P12V_E1S_0               C1276            1        Q_CAP_C0805-22UF,16V,20%,X6S,CA
P12V_E1S_0               C1277            1        Q_CAP_C0805-22UF,16V,20%,X6S,CA
P12V_E1S_0               C1278            1        Q_CAP_0402-0.1UF,25V,10%,X7R,CA
P12V_E1S_0               C1279            1        Q_CAP_0402-0.1UF,25V,10%,X7R,CA
P12V_E1S_0               C1506            1        Q_CAP_C0805-10UF,25V,10%,X6S,CA
P12V_E1S_0               J90              B1       CONN56_ME2005602311011-CONN56_A
P12V_E1S_0               J90              B2       CONN56_ME2005602311011-CONN56_A
P12V_E1S_0               J90              B3       CONN56_ME2005602311011-CONN56_A
P12V_E1S_0               J90              B4       CONN56_ME2005602311011-CONN56_A
P12V_E1S_0               J90              B5       CONN56_ME2005602311011-CONN56_A
P12V_E1S_0               J90              B6       CONN56_ME2005602311011-CONN56_A
P12V_E1S_0               U126             5        TPS259540DSGR-TPS259540DSGR,SMA
P12V_E1S_0_DVDT          C1503            1        Q_CAP_C0402-0.047UF,25V,10%,X7A
P12V_E1S_0_DVDT          U126             1        TPS259540DSGR-TPS259540DSGR,SMA
P12V_E1S_0_FLT_N         R2040            2        Q_RES_0402LF-10K,1%,1/16W,CHIPA
P12V_E1S_0_FLT_N         U126             6        TPS259540DSGR-TPS259540DSGR,SMA
P12V_E1S_0_ILM           R2038            1        Q_RES_0402LF-576,1%,1/16W,CHIPA
P12V_E1S_0_ILM           U126             7        TPS259540DSGR-TPS259540DSGR,SMA
P12V_E1S_1               C1280            1        Q_CAP_0402-0.1UF,25V,10%,X7R,CA
P12V_E1S_1               C1281            1        Q_CAP_0402-0.1UF,25V,10%,X7R,CA
P12V_E1S_1               C1489            1        Q_CAP_C0805-22UF,16V,20%,X6S,CA
P12V_E1S_1               C1490            1        Q_CAP_C0805-22UF,16V,20%,X6S,CA
P12V_E1S_1               C1514            1        Q_CAP_C0805-10UF,25V,10%,X6S,CA
P12V_E1S_1               J91              B1       CONN56_ME2005602311011-CONN56_A
P12V_E1S_1               J91              B2       CONN56_ME2005602311011-CONN56_A
P12V_E1S_1               J91              B3       CONN56_ME2005602311011-CONN56_A
P12V_E1S_1               J91              B4       CONN56_ME2005602311011-CONN56_A
P12V_E1S_1               J91              B5       CONN56_ME2005602311011-CONN56_A
P12V_E1S_1               J91              B6       CONN56_ME2005602311011-CONN56_A
P12V_E1S_1               U128             5        TPS259540DSGR-TPS259540DSGR,SMA
P12V_E1S_1_DVDT          C1510            1        Q_CAP_C0402-0.047UF,25V,10%,X7A
P12V_E1S_1_DVDT          U128             1        TPS259540DSGR-TPS259540DSGR,SMA
P12V_E1S_1_FLT_N         R2046            2        Q_RES_0402LF-10K,1%,1/16W,CHIPA
P12V_E1S_1_FLT_N         U128             6        TPS259540DSGR-TPS259540DSGR,SMA
P12V_E1S_1_ILM           R2044            1        Q_RES_0402LF-576,1%,1/16W,CHIPA
P12V_E1S_1_ILM           U128             7        TPS259540DSGR-TPS259540DSGR,SMA
P12V_E1S_2               C1491            1        Q_CAP_C0805-22UF,16V,20%,X6S,CA
P12V_E1S_2               C1493            1        Q_CAP_C0805-22UF,16V,20%,X6S,CA
P12V_E1S_2               C1495            1        Q_CAP_0402-0.1UF,25V,10%,X7R,CA
P12V_E1S_2               C1497            1        Q_CAP_0402-0.1UF,25V,10%,X7R,CA
P12V_E1S_2               C1509            1        Q_CAP_C0805-10UF,25V,10%,X6S,CA
P12V_E1S_2               J92              B1       CONN56_ME2005602311011-CONN56_A
P12V_E1S_2               J92              B2       CONN56_ME2005602311011-CONN56_A
P12V_E1S_2               J92              B3       CONN56_ME2005602311011-CONN56_A
P12V_E1S_2               J92              B4       CONN56_ME2005602311011-CONN56_A
P12V_E1S_2               J92              B5       CONN56_ME2005602311011-CONN56_A
P12V_E1S_2               J92              B6       CONN56_ME2005602311011-CONN56_A
P12V_E1S_2               U127             5        TPS259540DSGR-TPS259540DSGR,SMA
P12V_E1S_2_DVDT          C1504            1        Q_CAP_C0402-0.047UF,25V,10%,X7A
P12V_E1S_2_DVDT          U127             1        TPS259540DSGR-TPS259540DSGR,SMA
P12V_E1S_2_FLT_N         R2041            2        Q_RES_0402LF-10K,1%,1/16W,CHIPA
P12V_E1S_2_FLT_N         U127             6        TPS259540DSGR-TPS259540DSGR,SMA
P12V_E1S_2_ILM           R2039            1        Q_RES_0402LF-576,1%,1/16W,CHIPA
P12V_E1S_2_ILM           U127             7        TPS259540DSGR-TPS259540DSGR,SMA
P12V_E1S_3               C1492            1        Q_CAP_C0805-22UF,16V,20%,X6S,CA
P12V_E1S_3               C1494            1        Q_CAP_C0805-22UF,16V,20%,X6S,CA
P12V_E1S_3               C1496            1        Q_CAP_0402-0.1UF,25V,10%,X7R,CA
P12V_E1S_3               C1498            1        Q_CAP_0402-0.1UF,25V,10%,X7R,CA
P12V_E1S_3               C1515            1        Q_CAP_C0805-10UF,25V,10%,X6S,CA
P12V_E1S_3               J93              B1       CONN56_ME2005602311011-CONN56_A
P12V_E1S_3               J93              B2       CONN56_ME2005602311011-CONN56_A
P12V_E1S_3               J93              B3       CONN56_ME2005602311011-CONN56_A
P12V_E1S_3               J93              B4       CONN56_ME2005602311011-CONN56_A
P12V_E1S_3               J93              B5       CONN56_ME2005602311011-CONN56_A
P12V_E1S_3               J93              B6       CONN56_ME2005602311011-CONN56_A
P12V_E1S_3               U129             5        TPS259540DSGR-TPS259540DSGR,SMA
P12V_E1S_3_DVDT          C1511            1        Q_CAP_C0402-0.047UF,25V,10%,X7A
P12V_E1S_3_DVDT          U129             1        TPS259540DSGR-TPS259540DSGR,SMA
P12V_E1S_3_FLT_N         R2047            2        Q_RES_0402LF-10K,1%,1/16W,CHIPA
P12V_E1S_3_FLT_N         U129             6        TPS259540DSGR-TPS259540DSGR,SMA
P12V_E1S_3_ILM           R2045            1        Q_RES_0402LF-576,1%,1/16W,CHIPA
P12V_E1S_3_ILM           U129             7        TPS259540DSGR-TPS259540DSGR,SMA
P12V_FRONT_CPU           C133             1        Q_CAPP_SMLF-100UF,16V,20%,POSCA
P12V_FRONT_CPU           C134             1        Q_CAP_0402-0.1UF,25V,10%,X7R,CA
P12V_FRONT_CPU           C180             1        Q_CAP_0402-0.1UF,25V,10%,X7R,CA
P12V_FRONT_CPU           C632             1        Q_CAP_C0805-10UF,25V,10%,X6S,CA
P12V_FRONT_CPU           C1432            1        Q_CAP_0402-0.1UF,25V,10%,X7R,CA
P12V_FRONT_CPU           C1433            1        Q_CAP_C0805-10UF,25V,10%,X6S,CA
P12V_FRONT_CPU           C1505            1        Q_CAP_0402-0.1UF,25V,10%,X7R,CA
P12V_FRONT_CPU           C1512            1        Q_CAP_0402-0.1UF,25V,10%,X7R,CA
P12V_FRONT_CPU           C1513            1        Q_CAP_0402-0.1UF,25V,10%,X7R,CA
P12V_FRONT_CPU           C1601            1        Q_CAPP_SMLF-100UF,16V,20%,POSCA
P12V_FRONT_CPU           C1602            1        Q_CAP_0402-0.1UF,25V,10%,X7R,CA
P12V_FRONT_CPU           D8               C        DIODE_TVS-SMF14A,SMLF,IC,BCSMFA
P12V_FRONT_CPU           D9               C        DIODE_TVS-SMF14A,SMLF,IC,BCSMFA
P12V_FRONT_CPU           D10              C        DIODE_TVS-SMF14A,SMLF,IC,BCSMFA
P12V_FRONT_CPU           D11              C        DIODE_TVS-SMF14A,SMLF,IC,BCSMFA
P12V_FRONT_CPU           J89              B1       SCONN280_ME1028040102011-SCONNA
P12V_FRONT_CPU           J89              B2       SCONN280_ME1028040102011-SCONNA
P12V_FRONT_CPU           J89              B3       SCONN280_ME1028040102011-SCONNA
P12V_FRONT_CPU           J89              B4       SCONN280_ME1028040102011-SCONNA
P12V_FRONT_CPU           J89              B5       SCONN280_ME1028040102011-SCONNA
P12V_FRONT_CPU           J89              B6       SCONN280_ME1028040102011-SCONNA
P12V_FRONT_CPU           J89              B7       SCONN280_ME1028040102011-SCONNA
P12V_FRONT_CPU           J89              B13      SCONN280_ME1028040102011-SCONNA
P12V_FRONT_CPU           J89              B14      SCONN280_ME1028040102011-SCONNA
P12V_FRONT_CPU           J89              B15      SCONN280_ME1028040102011-SCONNA
P12V_FRONT_CPU           J89              B16      SCONN280_ME1028040102011-SCONNA
P12V_FRONT_CPU           J89              B17      SCONN280_ME1028040102011-SCONNA
P12V_FRONT_CPU           J89              B18      SCONN280_ME1028040102011-SCONNA
P12V_FRONT_CPU           JP5              1        CONN3_HFK1030G000LAF-CONN3_HFKA
P12V_FRONT_CPU           U81              1        MP5981GLUZ-MP5981GLU-Z,SMLF,ICA
P12V_FRONT_CPU           U81              2        MP5981GLUZ-MP5981GLU-Z,SMLF,ICA
P12V_FRONT_CPU           U81              25       MP5981GLUZ-MP5981GLU-Z,SMLF,ICA
P12V_FRONT_CPU           U81              26       MP5981GLUZ-MP5981GLU-Z,SMLF,ICA
P12V_FRONT_CPU           U81              27       MP5981GLUZ-MP5981GLU-Z,SMLF,ICA
P12V_FRONT_CPU           U81              28       MP5981GLUZ-MP5981GLU-Z,SMLF,ICA
P12V_FRONT_CPU           U81              29       MP5981GLUZ-MP5981GLU-Z,SMLF,ICA
P12V_FRONT_CPU           U81              30       MP5981GLUZ-MP5981GLU-Z,SMLF,ICA
P12V_FRONT_CPU           U81              31       MP5981GLUZ-MP5981GLU-Z,SMLF,ICA
P12V_FRONT_CPU           U81              32       MP5981GLUZ-MP5981GLU-Z,SMLF,ICA
P12V_FRONT_CPU           U126             3        TPS259540DSGR-TPS259540DSGR,SMA
P12V_FRONT_CPU           U126             4        TPS259540DSGR-TPS259540DSGR,SMA
P12V_FRONT_CPU           U127             3        TPS259540DSGR-TPS259540DSGR,SMA
P12V_FRONT_CPU           U127             4        TPS259540DSGR-TPS259540DSGR,SMA
P12V_FRONT_CPU           U128             3        TPS259540DSGR-TPS259540DSGR,SMA
P12V_FRONT_CPU           U128             4        TPS259540DSGR-TPS259540DSGR,SMA
P12V_FRONT_CPU           U129             3        TPS259540DSGR-TPS259540DSGR,SMA
P12V_FRONT_CPU           U129             4        TPS259540DSGR-TPS259540DSGR,SMA
P12V_FRONT_CPU0          C127             1        Q_CAPP_RDLLF-270UF,16V,20%,OSCA
P12V_FRONT_CPU0          C128             1        Q_CAP_0402-0.1UF,25V,10%,X7R,CA
P12V_FRONT_CPU0          J89              A2       SCONN280_ME1028040102011-SCONNA
P12V_FRONT_CPU0          J89              A3       SCONN280_ME1028040102011-SCONNA
P12V_FRONT_CPU0          J89              A4       SCONN280_ME1028040102011-SCONNA
P12V_FRONT_CPU0          J89              A5       SCONN280_ME1028040102011-SCONNA
P12V_FRONT_CPU0          J89              A6       SCONN280_ME1028040102011-SCONNA
P12V_FRONT_CPU0          J89              A7       SCONN280_ME1028040102011-SCONNA
P12V_FRONT_CPU1          J55              A1       SCONN140_G64V3431BHR-SCONN140_A
P12V_FRONT_CPU1          J55              A2       SCONN140_G64V3431BHR-SCONN140_A
P12V_FRONT_CPU1          J55              A3       SCONN140_G64V3431BHR-SCONN140_A
P12V_FRONT_CPU1          J55              A4       SCONN140_G64V3431BHR-SCONN140_A
P12V_FRONT_CPU1          J55              A5       SCONN140_G64V3431BHR-SCONN140_A
P12V_FRONT_CPU1          J55              A6       SCONN140_G64V3431BHR-SCONN140_A
P12V_FRONT_CPU1          J57              A1       SCONN140_G64V3431BHR-SCONN140_A
P12V_FRONT_CPU1          J57              A2       SCONN140_G64V3431BHR-SCONN140_A
P12V_FRONT_CPU1          J57              A3       SCONN140_G64V3431BHR-SCONN140_A
P12V_FRONT_CPU1          J57              A4       SCONN140_G64V3431BHR-SCONN140_A
P12V_FRONT_CPU1          J57              A5       SCONN140_G64V3431BHR-SCONN140_A
P12V_FRONT_CPU1          J57              A6       SCONN140_G64V3431BHR-SCONN140_A
P12V_OCP_DVDT_1          C591             1        Q_CAP_0402-3300PF,50V,10%,X7R,A
P12V_OCP_DVDT_1          U57              15       TPS259824ONRGER-TPS259824ONRGEA
P12V_OCP_ILIM1           R1137            1        Q_RES_0402LF-150,1%,1/16W,CHIPA
P12V_OCP_ILIM1           U57              8        TPS259824ONRGER-TPS259824ONRGEA
P12V_OCP_IMON_1          R1144            1        Q_RES_0402LF-562,1%,1/16W,CHIPA
P12V_OCP_IMON_1          U57              9        TPS259824ONRGER-TPS259824ONRGEA
P12V_OCP_ITIMER_1        C588             1        Q_CAP_C0402-3900PF,50V,10%,X7RA
P12V_OCP_ITIMER_1        U57              7        TPS259824ONRGER-TPS259824ONRGEA
P12V_OCP_LDSTRT11        R1134            1        Q_RES_0402LF-0,5%,1/16W,CHIP,CA
P12V_OCP_LDSTRT11        U57              12       TPS259824ONRGER-TPS259824ONRGEA
P12V_OCP_NRETRY1         R1135            1        Q_RES_0402LF-0,5%,1/16W,EMPTY,A
P12V_OCP_NRETRY1         U57              11       TPS259824ONRGER-TPS259824ONRGEA
P12V_OCP_RETRY1          R1136            1        Q_RES_0402LF-0,5%,1/16W,CHIP,CA
P12V_OCP_RETRY1          U57              10       TPS259824ONRGER-TPS259824ONRGEA
P12V_OCP_SFF             C319             1        Q_CAP_C0805-22UF,16V,20%,X6S,CA
P12V_OCP_SFF             C331             1        Q_CAP_C0805-22UF,16V,20%,X6S,CA
P12V_OCP_SFF             C589             1        Q_CAP_C0402-1UF,16V,10%,X6S,CHA
P12V_OCP_SFF             C1213            1        Q_CAP_C0805-22UF,16V,20%,X6S,CA
P12V_OCP_SFF             C1232            1        Q_CAP_C0805-22UF,16V,20%,X6S,CA
P12V_OCP_SFF             C1233            1        Q_CAP_0402-0.1UF,25V,10%,X7R,CA
P12V_OCP_SFF             C1234            1        Q_CAP_0402-0.1UF,25V,10%,X7R,CA
P12V_OCP_SFF             C1235            1        Q_CAP_0402-0.1UF,25V,10%,X7R,CA
P12V_OCP_SFF             C1236            1        Q_CAP_0402-0.1UF,25V,10%,X7R,CA
P12V_OCP_SFF             D4               C        SCHOTTKY_AC-SX34F,SMLF,IC,BC00A
P12V_OCP_SFF             J37              B1       SCONN168_623403212-SCONN168_6-A
P12V_OCP_SFF             J37              B2       SCONN168_623403212-SCONN168_6-A
P12V_OCP_SFF             J37              B3       SCONN168_623403212-SCONN168_6-A
P12V_OCP_SFF             J37              B4       SCONN168_623403212-SCONN168_6-A
P12V_OCP_SFF             J37              B5       SCONN168_623403212-SCONN168_6-A
P12V_OCP_SFF             J37              B6       SCONN168_623403212-SCONN168_6-A
P12V_OCP_SFF             U57              17       TPS259824ONRGER-TPS259824ONRGEA
P12V_OCP_SFF             U57              18       TPS259824ONRGER-TPS259824ONRGEA
P12V_OCP_SFF             U57              19       TPS259824ONRGER-TPS259824ONRGEA
P12V_OCP_SFF             U57              20       TPS259824ONRGER-TPS259824ONRGEA
P12V_OCP_SFF             U57              21       TPS259824ONRGER-TPS259824ONRGEA
P12V_OCP_SFF             U57              22       TPS259824ONRGER-TPS259824ONRGEA
P12V_OCP_SFF             U57              23       TPS259824ONRGER-TPS259824ONRGEA
P12V_OCP_SFF             U57              24       TPS259824ONRGER-TPS259824ONRGEA
P12V_REAR_CPU            C1047            1        Q_CAP_C0805-22UF,16V,20%,X6S,CA
P12V_REAR_CPU            C1048            1        Q_CAP_0402-0.1UF,25V,10%,X7R,CA
P12V_REAR_CPU            C1049            1        Q_CAP_0402-0.1UF,25V,10%,X7R,CA
P12V_REAR_CPU            C1050            1        Q_CAP_0402-0.1UF,25V,10%,X7R,CA
P12V_REAR_CPU            C1051            1        Q_CAP_0402-0.1UF,25V,10%,X7R,CA
P12V_REAR_CPU            C1052            1        Q_CAP_0402-0.1UF,25V,10%,X7R,CA
P12V_REAR_CPU            C1055            1        Q_CAP_C0805-22UF,16V,20%,X6S,CA
P12V_REAR_CPU            C1056            1        Q_CAP_0402-0.1UF,25V,10%,X7R,CA
P12V_REAR_CPU            C1057            1        Q_CAP_0402-0.1UF,25V,10%,X7R,CA
P12V_REAR_CPU            C1058            1        Q_CAP_0402-0.1UF,25V,10%,X7R,CA
P12V_REAR_CPU            C1059            1        Q_CAP_0402-0.1UF,25V,10%,X7R,CA
P12V_REAR_CPU            C1060            1        Q_CAP_0402-0.1UF,25V,10%,X7R,CA
P12V_REAR_CPU            C1063            1        Q_CAP_C0805-22UF,16V,20%,X6S,CA
P12V_REAR_CPU            C1064            1        Q_CAP_0402-0.1UF,25V,10%,X7R,CA
P12V_REAR_CPU            C1065            1        Q_CAP_0402-0.1UF,25V,10%,X7R,CA
P12V_REAR_CPU            C1066            1        Q_CAP_0402-0.1UF,25V,10%,X7R,CA
P12V_REAR_CPU            C1067            1        Q_CAP_0402-0.1UF,25V,10%,X7R,CA
P12V_REAR_CPU            C1068            1        Q_CAP_0402-0.1UF,25V,10%,X7R,CA
P12V_REAR_CPU            C1360            1        Q_CAP_0402-0.1UF,25V,10%,X7R,CA
P12V_REAR_CPU            C1361            1        Q_CAP_C0805-10UF,25V,10%,X6S,CA
P12V_REAR_CPU            C1439            1        Q_CAP_C0805-22UF,16V,20%,X6S,CA
P12V_REAR_CPU            C1440            1        Q_CAP_0402-0.1UF,25V,10%,X7R,CA
P12V_REAR_CPU            C1441            1        Q_CAP_0402-0.1UF,25V,10%,X7R,CA
P12V_REAR_CPU            C1442            1        Q_CAP_0402-0.1UF,25V,10%,X7R,CA
P12V_REAR_CPU            C1443            1        Q_CAP_0402-0.1UF,25V,10%,X7R,CA
P12V_REAR_CPU            C1444            1        Q_CAP_0402-0.1UF,25V,10%,X7R,CA
P12V_REAR_CPU            C1449            1        Q_CAP_C0805-22UF,16V,20%,X6S,CA
P12V_REAR_CPU            C1450            1        Q_CAP_0402-0.1UF,25V,10%,X7R,CA
P12V_REAR_CPU            C1451            1        Q_CAP_0402-0.1UF,25V,10%,X7R,CA
P12V_REAR_CPU            C1452            1        Q_CAP_0402-0.1UF,25V,10%,X7R,CA
P12V_REAR_CPU            C1453            1        Q_CAP_0402-0.1UF,25V,10%,X7R,CA
P12V_REAR_CPU            C1454            1        Q_CAP_0402-0.1UF,25V,10%,X7R,CA
P12V_REAR_CPU            C1459            1        Q_CAP_C0805-22UF,16V,20%,X6S,CA
P12V_REAR_CPU            C1460            1        Q_CAP_0402-0.1UF,25V,10%,X7R,CA
P12V_REAR_CPU            C1461            1        Q_CAP_0402-0.1UF,25V,10%,X7R,CA
P12V_REAR_CPU            C1462            1        Q_CAP_0402-0.1UF,25V,10%,X7R,CA
P12V_REAR_CPU            C1463            1        Q_CAP_0402-0.1UF,25V,10%,X7R,CA
P12V_REAR_CPU            C1464            1        Q_CAP_0402-0.1UF,25V,10%,X7R,CA
P12V_REAR_CPU            C1469            1        Q_CAP_C0805-22UF,16V,20%,X6S,CA
P12V_REAR_CPU            C1470            1        Q_CAP_0402-0.1UF,25V,10%,X7R,CA
P12V_REAR_CPU            C1471            1        Q_CAP_0402-0.1UF,25V,10%,X7R,CA
P12V_REAR_CPU            C1472            1        Q_CAP_0402-0.1UF,25V,10%,X7R,CA
P12V_REAR_CPU            C1473            1        Q_CAP_0402-0.1UF,25V,10%,X7R,CA
P12V_REAR_CPU            C1474            1        Q_CAP_0402-0.1UF,25V,10%,X7R,CA
P12V_REAR_CPU            J33              B1       SCONN84_123318136-SCONN84_1-23A
P12V_REAR_CPU            J33              B2       SCONN84_123318136-SCONN84_1-23A
P12V_REAR_CPU            J33              B3       SCONN84_123318136-SCONN84_1-23A
P12V_REAR_CPU            J33              B4       SCONN84_123318136-SCONN84_1-23A
P12V_REAR_CPU            J33              B5       SCONN84_123318136-SCONN84_1-23A
P12V_REAR_CPU            J33              B6       SCONN84_123318136-SCONN84_1-23A
P12V_REAR_CPU            J34              B1       SCONN84_123318136-SCONN84_1-23A
P12V_REAR_CPU            J34              B2       SCONN84_123318136-SCONN84_1-23A
P12V_REAR_CPU            J34              B3       SCONN84_123318136-SCONN84_1-23A
P12V_REAR_CPU            J34              B4       SCONN84_123318136-SCONN84_1-23A
P12V_REAR_CPU            J34              B5       SCONN84_123318136-SCONN84_1-23A
P12V_REAR_CPU            J34              B6       SCONN84_123318136-SCONN84_1-23A
P12V_REAR_CPU            J35              B1       SCONN140_G64V3431BHR-SCONN140_B
P12V_REAR_CPU            J35              B2       SCONN140_G64V3431BHR-SCONN140_B
P12V_REAR_CPU            J35              B3       SCONN140_G64V3431BHR-SCONN140_B
P12V_REAR_CPU            J35              B4       SCONN140_G64V3431BHR-SCONN140_B
P12V_REAR_CPU            J35              B5       SCONN140_G64V3431BHR-SCONN140_B
P12V_REAR_CPU            J35              B8       SCONN140_G64V3431BHR-SCONN140_B
P12V_REAR_CPU            J35              B9       SCONN140_G64V3431BHR-SCONN140_B
P12V_REAR_CPU            J35              B10      SCONN140_G64V3431BHR-SCONN140_B
P12V_REAR_CPU            J35              B11      SCONN140_G64V3431BHR-SCONN140_B
P12V_REAR_CPU            J35              B12      SCONN140_G64V3431BHR-SCONN140_B
P12V_REAR_CPU            J61              B1       SCONN84_123318136-SCONN84_1-23A
P12V_REAR_CPU            J61              B2       SCONN84_123318136-SCONN84_1-23A
P12V_REAR_CPU            J61              B3       SCONN84_123318136-SCONN84_1-23A
P12V_REAR_CPU            J61              B4       SCONN84_123318136-SCONN84_1-23A
P12V_REAR_CPU            J61              B5       SCONN84_123318136-SCONN84_1-23A
P12V_REAR_CPU            J61              B6       SCONN84_123318136-SCONN84_1-23A
P12V_REAR_CPU            J62              B1       SCONN84_123318136-SCONN84_1-23A
P12V_REAR_CPU            J62              B2       SCONN84_123318136-SCONN84_1-23A
P12V_REAR_CPU            J62              B3       SCONN84_123318136-SCONN84_1-23A
P12V_REAR_CPU            J62              B4       SCONN84_123318136-SCONN84_1-23A
P12V_REAR_CPU            J62              B5       SCONN84_123318136-SCONN84_1-23A
P12V_REAR_CPU            J62              B6       SCONN84_123318136-SCONN84_1-23A
P12V_REAR_CPU            J87              B1       SCONN84_123318136-SCONN84_1-23A
P12V_REAR_CPU            J87              B2       SCONN84_123318136-SCONN84_1-23A
P12V_REAR_CPU            J87              B3       SCONN84_123318136-SCONN84_1-23A
P12V_REAR_CPU            J87              B4       SCONN84_123318136-SCONN84_1-23A
P12V_REAR_CPU            J87              B5       SCONN84_123318136-SCONN84_1-23A
P12V_REAR_CPU            J87              B6       SCONN84_123318136-SCONN84_1-23A
P12V_REAR_CPU            J88              B1       SCONN84_123318136-SCONN84_1-23A
P12V_REAR_CPU            J88              B2       SCONN84_123318136-SCONN84_1-23A
P12V_REAR_CPU            J88              B3       SCONN84_123318136-SCONN84_1-23A
P12V_REAR_CPU            J88              B4       SCONN84_123318136-SCONN84_1-23A
P12V_REAR_CPU            J88              B5       SCONN84_123318136-SCONN84_1-23A
P12V_REAR_CPU            J88              B6       SCONN84_123318136-SCONN84_1-23A
P12V_REAR_CPU            U107             1        MP5981GLUZ-MP5981GLU-Z,SMLF,ICA
P12V_REAR_CPU            U107             2        MP5981GLUZ-MP5981GLU-Z,SMLF,ICA
P12V_REAR_CPU            U107             25       MP5981GLUZ-MP5981GLU-Z,SMLF,ICA
P12V_REAR_CPU            U107             26       MP5981GLUZ-MP5981GLU-Z,SMLF,ICA
P12V_REAR_CPU            U107             27       MP5981GLUZ-MP5981GLU-Z,SMLF,ICA
P12V_REAR_CPU            U107             28       MP5981GLUZ-MP5981GLU-Z,SMLF,ICA
P12V_REAR_CPU            U107             29       MP5981GLUZ-MP5981GLU-Z,SMLF,ICA
P12V_REAR_CPU            U107             30       MP5981GLUZ-MP5981GLU-Z,SMLF,ICA
P12V_REAR_CPU            U107             31       MP5981GLUZ-MP5981GLU-Z,SMLF,ICA
P12V_REAR_CPU            U107             32       MP5981GLUZ-MP5981GLU-Z,SMLF,ICA
P12V_S3_AUX_CPU0_NVDIMM  C3               1        Q_CAP_C0805-10UF,16V,10%,X7R,CA
P12V_S3_AUX_CPU0_NVDIMM  C4               1        Q_CAP_C0805-10UF,16V,10%,X7R,CA
P12V_S3_AUX_CPU0_NVDIMM  C6               1        Q_CAP_C0805-10UF,16V,10%,X7R,CA
P12V_S3_AUX_CPU0_NVDIMM  C7               1        Q_CAP_C0805-10UF,16V,10%,X7R,CA
P12V_S3_AUX_CPU0_NVDIMM  C9               1        Q_CAP_C0805-10UF,16V,10%,X7R,CA
P12V_S3_AUX_CPU0_NVDIMM  C10              1        Q_CAP_C0805-10UF,16V,10%,X7R,CA
P12V_S3_AUX_CPU0_NVDIMM  C12              1        Q_CAP_C0805-10UF,16V,10%,X7R,CA
P12V_S3_AUX_CPU0_NVDIMM  C13              1        Q_CAP_C0805-10UF,16V,10%,X7R,CA
P12V_S3_AUX_CPU0_NVDIMM  C15              1        Q_CAP_C0805-10UF,16V,10%,X7R,CA
P12V_S3_AUX_CPU0_NVDIMM  C16              1        Q_CAP_C0805-10UF,16V,10%,X7R,CA
P12V_S3_AUX_CPU0_NVDIMM  C18              1        Q_CAP_C0805-10UF,16V,10%,X7R,CA
P12V_S3_AUX_CPU0_NVDIMM  C19              1        Q_CAP_C0805-10UF,16V,10%,X7R,CA
P12V_S3_AUX_CPU0_NVDIMM  C21              1        Q_CAP_C0805-10UF,16V,10%,X7R,CA
P12V_S3_AUX_CPU0_NVDIMM  C22              1        Q_CAP_C0805-10UF,16V,10%,X7R,CA
P12V_S3_AUX_CPU0_NVDIMM  C24              1        Q_CAP_C0805-10UF,16V,10%,X7R,CA
P12V_S3_AUX_CPU0_NVDIMM  C25              1        Q_CAP_C0805-22UF,16V,20%,X6S,CA
P12V_S3_AUX_CPU0_NVDIMM  C27              1        Q_CAP_C0805-10UF,16V,10%,X7R,CA
P12V_S3_AUX_CPU0_NVDIMM  C28              1        Q_CAP_C0805-10UF,16V,10%,X7R,CA
P12V_S3_AUX_CPU0_NVDIMM  C30              1        Q_CAP_C0805-10UF,16V,10%,X7R,CA
P12V_S3_AUX_CPU0_NVDIMM  C31              1        Q_CAP_C0805-10UF,16V,10%,X7R,CA
P12V_S3_AUX_CPU0_NVDIMM  C33              1        Q_CAP_C0805-10UF,16V,10%,X7R,CA
P12V_S3_AUX_CPU0_NVDIMM  C34              1        Q_CAP_C0805-10UF,16V,10%,X7R,CA
P12V_S3_AUX_CPU0_NVDIMM  C36              1        Q_CAP_C0805-10UF,16V,10%,X7R,CA
P12V_S3_AUX_CPU0_NVDIMM  C37              1        Q_CAP_C0805-10UF,16V,10%,X7R,CA
P12V_S3_AUX_CPU0_NVDIMM  C39              1        Q_CAP_C0805-10UF,16V,10%,X7R,CA
P12V_S3_AUX_CPU0_NVDIMM  C40              1        Q_CAP_C0805-10UF,16V,10%,X7R,CA
P12V_S3_AUX_CPU0_NVDIMM  C42              1        Q_CAP_C0805-10UF,16V,10%,X7R,CA
P12V_S3_AUX_CPU0_NVDIMM  C43              1        Q_CAP_C0805-10UF,16V,10%,X7R,CA
P12V_S3_AUX_CPU0_NVDIMM  C45              1        Q_CAP_C0805-10UF,16V,10%,X7R,CA
P12V_S3_AUX_CPU0_NVDIMM  C46              1        Q_CAP_C0805-10UF,16V,10%,X7R,CA
P12V_S3_AUX_CPU0_NVDIMM  C48              1        Q_CAP_C0805-10UF,16V,10%,X7R,CA
P12V_S3_AUX_CPU0_NVDIMM  C49              1        Q_CAP_C0805-10UF,16V,10%,X7R,CA
P12V_S3_AUX_CPU0_NVDIMM  J1               1        SCONN288_ADR50001P013C01-SCONNA
P12V_S3_AUX_CPU0_NVDIMM  J1               145      SCONN288_ADR50001P013C01-SCONNA
P12V_S3_AUX_CPU0_NVDIMM  J1               146      SCONN288_ADR50001P013C01-SCONNA
P12V_S3_AUX_CPU0_NVDIMM  J2               1        SCONN288_ADR50001P003C01-SCONNA
P12V_S3_AUX_CPU0_NVDIMM  J2               145      SCONN288_ADR50001P003C01-SCONNA
P12V_S3_AUX_CPU0_NVDIMM  J2               146      SCONN288_ADR50001P003C01-SCONNA
P12V_S3_AUX_CPU0_NVDIMM  J3               1        SCONN288_ADR50001P013C01-SCONNA
P12V_S3_AUX_CPU0_NVDIMM  J3               145      SCONN288_ADR50001P013C01-SCONNA
P12V_S3_AUX_CPU0_NVDIMM  J3               146      SCONN288_ADR50001P013C01-SCONNA
P12V_S3_AUX_CPU0_NVDIMM  J4               1        SCONN288_ADR50001P003C01-SCONNA
P12V_S3_AUX_CPU0_NVDIMM  J4               145      SCONN288_ADR50001P003C01-SCONNA
P12V_S3_AUX_CPU0_NVDIMM  J4               146      SCONN288_ADR50001P003C01-SCONNA
P12V_S3_AUX_CPU0_NVDIMM  J5               1        SCONN288_ADR50001P013C01-SCONNA
P12V_S3_AUX_CPU0_NVDIMM  J5               145      SCONN288_ADR50001P013C01-SCONNA
P12V_S3_AUX_CPU0_NVDIMM  J5               146      SCONN288_ADR50001P013C01-SCONNA
P12V_S3_AUX_CPU0_NVDIMM  J6               1        SCONN288_ADR50001P003C01-SCONNA
P12V_S3_AUX_CPU0_NVDIMM  J6               145      SCONN288_ADR50001P003C01-SCONNA
P12V_S3_AUX_CPU0_NVDIMM  J6               146      SCONN288_ADR50001P003C01-SCONNA
P12V_S3_AUX_CPU0_NVDIMM  J7               1        SCONN288_ADR50001P013C01-SCONNA
P12V_S3_AUX_CPU0_NVDIMM  J7               145      SCONN288_ADR50001P013C01-SCONNA
P12V_S3_AUX_CPU0_NVDIMM  J7               146      SCONN288_ADR50001P013C01-SCONNA
P12V_S3_AUX_CPU0_NVDIMM  J8               1        SCONN288_ADR50001P003C01-SCONNA
P12V_S3_AUX_CPU0_NVDIMM  J8               145      SCONN288_ADR50001P003C01-SCONNA
P12V_S3_AUX_CPU0_NVDIMM  J8               146      SCONN288_ADR50001P003C01-SCONNA
P12V_S3_AUX_CPU0_NVDIMM  J9               1        SCONN288_ADR50001P013C01-SCONNA
P12V_S3_AUX_CPU0_NVDIMM  J9               145      SCONN288_ADR50001P013C01-SCONNA
P12V_S3_AUX_CPU0_NVDIMM  J9               146      SCONN288_ADR50001P013C01-SCONNA
P12V_S3_AUX_CPU0_NVDIMM  J10              1        SCONN288_ADR50001P003C01-SCONNA
P12V_S3_AUX_CPU0_NVDIMM  J10              145      SCONN288_ADR50001P003C01-SCONNA
P12V_S3_AUX_CPU0_NVDIMM  J10              146      SCONN288_ADR50001P003C01-SCONNA
P12V_S3_AUX_CPU0_NVDIMM  J11              1        SCONN288_ADR50001P013C01-SCONNA
P12V_S3_AUX_CPU0_NVDIMM  J11              145      SCONN288_ADR50001P013C01-SCONNA
P12V_S3_AUX_CPU0_NVDIMM  J11              146      SCONN288_ADR50001P013C01-SCONNA
P12V_S3_AUX_CPU0_NVDIMM  J12              1        SCONN288_ADR50001P003C01-SCONNA
P12V_S3_AUX_CPU0_NVDIMM  J12              145      SCONN288_ADR50001P003C01-SCONNA
P12V_S3_AUX_CPU0_NVDIMM  J12              146      SCONN288_ADR50001P003C01-SCONNA
P12V_S3_AUX_CPU0_NVDIMM  J13              1        SCONN288_ADR50001P013C01-SCONNA
P12V_S3_AUX_CPU0_NVDIMM  J13              145      SCONN288_ADR50001P013C01-SCONNA
P12V_S3_AUX_CPU0_NVDIMM  J13              146      SCONN288_ADR50001P013C01-SCONNA
P12V_S3_AUX_CPU0_NVDIMM  J14              1        SCONN288_ADR50001P003C01-SCONNA
P12V_S3_AUX_CPU0_NVDIMM  J14              145      SCONN288_ADR50001P003C01-SCONNA
P12V_S3_AUX_CPU0_NVDIMM  J14              146      SCONN288_ADR50001P003C01-SCONNA
P12V_S3_AUX_CPU0_NVDIMM  J15              1        SCONN288_ADR50001P013C01-SCONNA
P12V_S3_AUX_CPU0_NVDIMM  J15              145      SCONN288_ADR50001P013C01-SCONNA
P12V_S3_AUX_CPU0_NVDIMM  J15              146      SCONN288_ADR50001P013C01-SCONNA
P12V_S3_AUX_CPU0_NVDIMM  J16              1        SCONN288_ADR50001P003C01-SCONNA
P12V_S3_AUX_CPU0_NVDIMM  J16              145      SCONN288_ADR50001P003C01-SCONNA
P12V_S3_AUX_CPU0_NVDIMM  J16              146      SCONN288_ADR50001P003C01-SCONNA
P12V_S3_AUX_CPU0_NVDIMM  R1838            1        Q_RES_4P_12-0.001,1%,3W,SMLF,CA
P12V_S3_AUX_CPU0_NVDIMM_ISENSE_ PR1390           1        Q_RES_0402LF-49.9     ,1%  ,1/A
P12V_S3_AUX_CPU0_NVDIMM_ISENSE_ R1838            3        Q_RES_4P_12-0.001,1%,3W,SMLF,CA
P12V_S3_AUX_CPU0_NVDIMM_ISENSE_ U102             4        MAX9634FEUKT-MAX9634FEUK+T,SMLA
P12V_S3_AUX_CPU0_NVDIMM_ISENS_1 PR1380           1        Q_RES_0402LF-49.9     ,1%  ,1/A
P12V_S3_AUX_CPU0_NVDIMM_ISENS_1 R1838            4        Q_RES_4P_12-0.001,1%,3W,SMLF,CA
P12V_S3_AUX_CPU0_NVDIMM_ISENS_1 U102             5        MAX9634FEUKT-MAX9634FEUK+T,SMLA
P12V_S3_AUX_CPU1_NVDIMM  C51              1        Q_CAP_C0805-10UF,16V,10%,X7R,CA
P12V_S3_AUX_CPU1_NVDIMM  C52              1        Q_CAP_C0805-10UF,16V,10%,X7R,CA
P12V_S3_AUX_CPU1_NVDIMM  C54              1        Q_CAP_C0805-10UF,16V,10%,X7R,CA
P12V_S3_AUX_CPU1_NVDIMM  C55              1        Q_CAP_C0805-10UF,16V,10%,X7R,CA
P12V_S3_AUX_CPU1_NVDIMM  C57              1        Q_CAP_C0805-10UF,16V,10%,X7R,CA
P12V_S3_AUX_CPU1_NVDIMM  C58              1        Q_CAP_C0805-10UF,16V,10%,X7R,CA
P12V_S3_AUX_CPU1_NVDIMM  C60              1        Q_CAP_C0805-10UF,16V,10%,X7R,CA
P12V_S3_AUX_CPU1_NVDIMM  C61              1        Q_CAP_C0805-10UF,16V,10%,X7R,CA
P12V_S3_AUX_CPU1_NVDIMM  C63              1        Q_CAP_C0805-10UF,16V,10%,X7R,CA
P12V_S3_AUX_CPU1_NVDIMM  C64              1        Q_CAP_C0805-10UF,16V,10%,X7R,CA
P12V_S3_AUX_CPU1_NVDIMM  C66              1        Q_CAP_C0805-10UF,16V,10%,X7R,CA
P12V_S3_AUX_CPU1_NVDIMM  C67              1        Q_CAP_C0805-10UF,16V,10%,X7R,CA
P12V_S3_AUX_CPU1_NVDIMM  C69              1        Q_CAP_C0805-10UF,16V,10%,X7R,CA
P12V_S3_AUX_CPU1_NVDIMM  C70              1        Q_CAP_C0805-10UF,16V,10%,X7R,CA
P12V_S3_AUX_CPU1_NVDIMM  C73              1        Q_CAP_C0805-10UF,16V,10%,X7R,CA
P12V_S3_AUX_CPU1_NVDIMM  C74              1        Q_CAP_C0805-10UF,16V,10%,X7R,CA
P12V_S3_AUX_CPU1_NVDIMM  C76              1        Q_CAP_C0805-10UF,16V,10%,X7R,CA
P12V_S3_AUX_CPU1_NVDIMM  C77              1        Q_CAP_C0805-10UF,16V,10%,X7R,CA
P12V_S3_AUX_CPU1_NVDIMM  C79              1        Q_CAP_C0805-10UF,16V,10%,X7R,CA
P12V_S3_AUX_CPU1_NVDIMM  C80              1        Q_CAP_C0805-10UF,16V,10%,X7R,CA
P12V_S3_AUX_CPU1_NVDIMM  C82              1        Q_CAP_C0805-10UF,16V,10%,X7R,CA
P12V_S3_AUX_CPU1_NVDIMM  C83              1        Q_CAP_C0805-10UF,16V,10%,X7R,CA
P12V_S3_AUX_CPU1_NVDIMM  C85              1        Q_CAP_C0805-10UF,16V,10%,X7R,CA
P12V_S3_AUX_CPU1_NVDIMM  C86              1        Q_CAP_C0805-10UF,16V,10%,X7R,CA
P12V_S3_AUX_CPU1_NVDIMM  C88              1        Q_CAP_C0805-10UF,16V,10%,X7R,CA
P12V_S3_AUX_CPU1_NVDIMM  C89              1        Q_CAP_C0805-10UF,16V,10%,X7R,CA
P12V_S3_AUX_CPU1_NVDIMM  C91              1        Q_CAP_C0805-10UF,16V,10%,X7R,CA
P12V_S3_AUX_CPU1_NVDIMM  C92              1        Q_CAP_C0805-10UF,16V,10%,X7R,CA
P12V_S3_AUX_CPU1_NVDIMM  C94              1        Q_CAP_C0805-10UF,16V,10%,X7R,CA
P12V_S3_AUX_CPU1_NVDIMM  C95              1        Q_CAP_C0805-10UF,16V,10%,X7R,CA
P12V_S3_AUX_CPU1_NVDIMM  C97              1        Q_CAP_C0805-10UF,16V,10%,X7R,CA
P12V_S3_AUX_CPU1_NVDIMM  C98              1        Q_CAP_C0805-10UF,16V,10%,X7R,CA
P12V_S3_AUX_CPU1_NVDIMM  J17              1        SCONN288_ADR50001P013C01-SCONNA
P12V_S3_AUX_CPU1_NVDIMM  J17              145      SCONN288_ADR50001P013C01-SCONNA
P12V_S3_AUX_CPU1_NVDIMM  J17              146      SCONN288_ADR50001P013C01-SCONNA
P12V_S3_AUX_CPU1_NVDIMM  J18              1        SCONN288_ADR50001P003C01-SCONNA
P12V_S3_AUX_CPU1_NVDIMM  J18              145      SCONN288_ADR50001P003C01-SCONNA
P12V_S3_AUX_CPU1_NVDIMM  J18              146      SCONN288_ADR50001P003C01-SCONNA
P12V_S3_AUX_CPU1_NVDIMM  J19              1        SCONN288_ADR50001P013C01-SCONNA
P12V_S3_AUX_CPU1_NVDIMM  J19              145      SCONN288_ADR50001P013C01-SCONNA
P12V_S3_AUX_CPU1_NVDIMM  J19              146      SCONN288_ADR50001P013C01-SCONNA
P12V_S3_AUX_CPU1_NVDIMM  J20              1        SCONN288_ADR50001P003C01-SCONNA
P12V_S3_AUX_CPU1_NVDIMM  J20              145      SCONN288_ADR50001P003C01-SCONNA
P12V_S3_AUX_CPU1_NVDIMM  J20              146      SCONN288_ADR50001P003C01-SCONNA
P12V_S3_AUX_CPU1_NVDIMM  J21              1        SCONN288_ADR50001P013C01-SCONNA
P12V_S3_AUX_CPU1_NVDIMM  J21              145      SCONN288_ADR50001P013C01-SCONNA
P12V_S3_AUX_CPU1_NVDIMM  J21              146      SCONN288_ADR50001P013C01-SCONNA
P12V_S3_AUX_CPU1_NVDIMM  J22              1        SCONN288_ADR50001P003C01-SCONNA
P12V_S3_AUX_CPU1_NVDIMM  J22              145      SCONN288_ADR50001P003C01-SCONNA
P12V_S3_AUX_CPU1_NVDIMM  J22              146      SCONN288_ADR50001P003C01-SCONNA
P12V_S3_AUX_CPU1_NVDIMM  J23              1        SCONN288_ADR50001P013C01-SCONNA
P12V_S3_AUX_CPU1_NVDIMM  J23              145      SCONN288_ADR50001P013C01-SCONNA
P12V_S3_AUX_CPU1_NVDIMM  J23              146      SCONN288_ADR50001P013C01-SCONNA
P12V_S3_AUX_CPU1_NVDIMM  J24              1        SCONN288_ADR50001P003C01-SCONNA
P12V_S3_AUX_CPU1_NVDIMM  J24              145      SCONN288_ADR50001P003C01-SCONNA
P12V_S3_AUX_CPU1_NVDIMM  J24              146      SCONN288_ADR50001P003C01-SCONNA
P12V_S3_AUX_CPU1_NVDIMM  J25              1        SCONN288_ADR50001P013C01-SCONNA
P12V_S3_AUX_CPU1_NVDIMM  J25              145      SCONN288_ADR50001P013C01-SCONNA
P12V_S3_AUX_CPU1_NVDIMM  J25              146      SCONN288_ADR50001P013C01-SCONNA
P12V_S3_AUX_CPU1_NVDIMM  J26              1        SCONN288_ADR50001P003C01-SCONNA
P12V_S3_AUX_CPU1_NVDIMM  J26              145      SCONN288_ADR50001P003C01-SCONNA
P12V_S3_AUX_CPU1_NVDIMM  J26              146      SCONN288_ADR50001P003C01-SCONNA
P12V_S3_AUX_CPU1_NVDIMM  J27              1        SCONN288_ADR50001P013C01-SCONNA
P12V_S3_AUX_CPU1_NVDIMM  J27              145      SCONN288_ADR50001P013C01-SCONNA
P12V_S3_AUX_CPU1_NVDIMM  J27              146      SCONN288_ADR50001P013C01-SCONNA
P12V_S3_AUX_CPU1_NVDIMM  J28              1        SCONN288_ADR50001P003C01-SCONNA
P12V_S3_AUX_CPU1_NVDIMM  J28              145      SCONN288_ADR50001P003C01-SCONNA
P12V_S3_AUX_CPU1_NVDIMM  J28              146      SCONN288_ADR50001P003C01-SCONNA
P12V_S3_AUX_CPU1_NVDIMM  J29              1        SCONN288_ADR50001P013C01-SCONNA
P12V_S3_AUX_CPU1_NVDIMM  J29              145      SCONN288_ADR50001P013C01-SCONNA
P12V_S3_AUX_CPU1_NVDIMM  J29              146      SCONN288_ADR50001P013C01-SCONNA
P12V_S3_AUX_CPU1_NVDIMM  J30              1        SCONN288_ADR50001P003C01-SCONNA
P12V_S3_AUX_CPU1_NVDIMM  J30              145      SCONN288_ADR50001P003C01-SCONNA
P12V_S3_AUX_CPU1_NVDIMM  J30              146      SCONN288_ADR50001P003C01-SCONNA
P12V_S3_AUX_CPU1_NVDIMM  J31              1        SCONN288_ADR50001P013C01-SCONNA
P12V_S3_AUX_CPU1_NVDIMM  J31              145      SCONN288_ADR50001P013C01-SCONNA
P12V_S3_AUX_CPU1_NVDIMM  J31              146      SCONN288_ADR50001P013C01-SCONNA
P12V_S3_AUX_CPU1_NVDIMM  J32              1        SCONN288_ADR50001P003C01-SCONNA
P12V_S3_AUX_CPU1_NVDIMM  J32              145      SCONN288_ADR50001P003C01-SCONNA
P12V_S3_AUX_CPU1_NVDIMM  J32              146      SCONN288_ADR50001P003C01-SCONNA
P12V_S3_AUX_CPU1_NVDIMM  R1837            1        Q_RES_4P_12-0.001,1%,3W,SMLF,CA
P12V_S3_AUX_CPU1_NVDIMM_ISENSE_ PR1410           1        Q_RES_0402LF-49.9     ,1%  ,1/A
P12V_S3_AUX_CPU1_NVDIMM_ISENSE_ R1837            3        Q_RES_4P_12-0.001,1%,3W,SMLF,CA
P12V_S3_AUX_CPU1_NVDIMM_ISENSE_ U103             4        MAX9634FEUKT-MAX9634FEUK+T,SMLA
P12V_S3_AUX_CPU1_NVDIMM_ISENS_1 PR1400           1        Q_RES_0402LF-49.9     ,1%  ,1/A
P12V_S3_AUX_CPU1_NVDIMM_ISENS_1 R1837            4        Q_RES_4P_12-0.001,1%,3W,SMLF,CA
P12V_S3_AUX_CPU1_NVDIMM_ISENS_1 U103             5        MAX9634FEUKT-MAX9634FEUK+T,SMLA
P12V_SCM                 C1598            1        Q_CAP_C0805-10UF,25V,10%,X6S,CA
P12V_SCM                 J41              OCP_A1   SCONN168_623403212-SCONN168_6-A
P12V_SCM                 J41              OCP_A2   SCONN168_623403212-SCONN168_6-A
P12V_SCM                 J41              OCP_B1   SCONN168_623403212-SCONN168_6-A
P12V_SCM                 J41              OCP_B2   SCONN168_623403212-SCONN168_6-A
P12V_SCM                 U138             5        TPS259540DSGR-TPS259540DSGR,SMA
P12V_SCM_DVDT            C1596            1        Q_CAP_C0402-0.047UF,25V,10%,X7A
P12V_SCM_DVDT            U138             1        TPS259540DSGR-TPS259540DSGR,SMA
P12V_SCM_EN_N            Q39              3        MOSFET_NCH_DUAL-2N7002KDW,SMLFA
P12V_SCM_EN_N            R1857            2        Q_RES_0402LF-10K,1%,1/16W,CHIPA
P12V_SCM_EN_N            R2135            2        Q_RES_0402LF-0,5%,1/16W,CHIP,CA
P12V_SCM_EN_N            U138             2        TPS259540DSGR-TPS259540DSGR,SMA
P12V_SCM_FLT_N           R2138            2        Q_RES_0402LF-10K,1%,1/16W,CHIPA
P12V_SCM_FLT_N           U138             6        TPS259540DSGR-TPS259540DSGR,SMA
P12V_SCM_ILM             R2137            1        Q_RES_0402LF-576,1%,1/16W,CHIPA
P12V_SCM_ILM             U138             7        TPS259540DSGR-TPS259540DSGR,SMA
P1V05_PCH_AUX            C547             1        Q_CAP_C0402-1UF,25V,10%,X6S,CHA
P1V05_PCH_AUX            C1178            1        Q_CAP_C0603-22UF,4V,20%,X6S,CHA
P1V05_PCH_AUX            C1182            1        Q_CAP_C0603-22UF,4V,20%,X6S,CHA
P1V05_PCH_AUX            C1183            1        Q_CAP_C0402-2.2UF,10V,10%,X6S,A
P1V05_PCH_AUX            C1185            1        Q_CAP_C0603-22UF,4V,20%,X6S,CHA
P1V05_PCH_AUX            C1187            1        Q_CAP_C0603-22UF,4V,20%,X6S,CHA
P1V05_PCH_AUX            C1189            1        Q_CAP_C0402-2.2UF,10V,10%,X6S,A
P1V05_PCH_AUX            C1192            1        Q_CAP_C0603-22UF,4V,20%,X6S,CHA
P1V05_PCH_AUX            C1198            1        Q_CAP_C0603-22UF,4V,20%,X6S,CHA
P1V05_PCH_AUX            C1200            1        Q_CAP_C0402-2.2UF,10V,10%,X6S,A
P1V05_PCH_AUX            C1203            1        Q_CAP_C0402-10UF,6.3V,20%,X6S,A
P1V05_PCH_AUX            C1204            1        Q_CAP_C0402-2.2UF,10V,10%,X6S,A
P1V05_PCH_AUX            C1205            1        Q_CAP_C0402-10UF,6.3V,20%,X6S,A
P1V05_PCH_AUX            C1210            1        Q_CAP_C0402-10UF,6.3V,20%,X6S,A
P1V05_PCH_AUX            C1214            1        Q_CAP_C0402-2.2UF,10V,10%,X6S,A
P1V05_PCH_AUX            C1228            1        Q_CAP_C0402-10UF,6.3V,20%,X6S,A
P1V05_PCH_AUX            C1231            1        Q_CAP_C0402-10UF,6.3V,20%,X6S,A
P1V05_PCH_AUX            C1242            1        Q_CAP_C0402-2.2UF,10V,10%,X6S,A
P1V05_PCH_AUX            C1244            1        Q_CAP_0805-47UF,4V,20%,X6S,CH6A
P1V05_PCH_AUX            C1246            1        Q_CAP_0805-47UF,4V,20%,X6S,CH6A
P1V05_PCH_AUX            C1247            1        Q_CAP_0805-47UF,4V,20%,X6S,CH6A
P1V05_PCH_AUX            C1248            1        Q_CAP_0805-47UF,4V,20%,X6S,CH6A
P1V05_PCH_AUX            C1249            1        Q_CAP_0805-47UF,4V,20%,X6S,CH6A
P1V05_PCH_AUX            C1250            1        Q_CAP_0402-1UF,6.3V,10%,EMPTY,A
P1V05_PCH_AUX            J42              1        SCONN60_QSH03001LDAKTR-SCONN60A
P1V05_PCH_AUX            L2               1        Q_INDUCTOR_SMLF-BLM18PG121SN1DA
P1V05_PCH_AUX            PC117            1        Q_CAPP_SMLF-470UF,2V,20%,POSCAA
P1V05_PCH_AUX            PC1224           1        Q_CAP_0402-0.1UF,25V,10%,X7R,CA
P1V05_PCH_AUX            PC1225           1        Q_CAP_0805-47UF,4V,20%,X6S,CH6A
P1V05_PCH_AUX            PC1226           1        Q_CAP_0805-47UF,4V,20%,X6S,CH6A
P1V05_PCH_AUX            PC1227           1        Q_CAPP_THLF-560UF,2.5V,20%,OSCA
P1V05_PCH_AUX            PC1229           1        Q_CAPP_SMLF-470UF,2V,20%,EMPTYA
P1V05_PCH_AUX            PC1230           1        Q_CAPP_THLF-560UF,2.5V,20%,OSCA
P1V05_PCH_AUX            PJ62             2        Q_SHORT_SM-EMPTY,SHORT6
P1V05_PCH_AUX            PL150            2        Q_INDUCTOR_SMLF-300NH/33A,IND,A
P1V05_PCH_AUX            R382             1        Q_RES_0402LF-1K,5%,1/16W,EMPTYA
P1V05_PCH_AUX            R747             1        Q_RES_0402LF-150,1%,1/16W,CHIPA
P1V05_PCH_AUX            R748             1        Q_RES_0402LF-75,1%,1/16W,CHIP,A
P1V05_PCH_AUX            R749             1        Q_RES_0402LF-75,1%,1/16W,CHIP,A
P1V05_PCH_AUX            R750             1        Q_RES_0402LF-150,1%,1/16W,CHIPA
P1V05_PCH_AUX            R751             1        Q_RES_0402LF-150,1%,1/16W,CHIPA
P1V05_PCH_AUX            R1026            2        Q_RES_0402LF-1K,1%,1/16W,CHIP,A
P1V05_PCH_AUX            R1260            1        Q_RES_0402LF-10K,1%,1/16W,EMPTA
P1V05_PCH_AUX            R1261            1        Q_RES_0402LF-10K,1%,1/16W,EMPTA
P1V05_PCH_AUX            R1262            1        Q_RES_0402LF-10K,1%,1/16W,EMPTA
P1V05_PCH_AUX            R1266            1        Q_RES_0402LF-49.9     ,1%  ,1/B
P1V05_PCH_AUX            R1298            1        Q_RES_0402LF-1K,5%,1/16W,EMPTYA
P1V05_PCH_AUX            R1315            1        Q_RES_0402LF-1K,5%,1/16W,EMPTYA
P1V05_PCH_AUX            R1317            1        Q_RES_0402LF-1K,1%,1/16W,CHIP,A
P1V05_PCH_AUX            R1342            1        Q_RES_0402LF-10K,1%,1/16W,CHIPA
P1V05_PCH_AUX            R1343            1        Q_RES_0402LF-10K,1%,1/16W,CHIPA
P1V05_PCH_AUX            R1463            1        Q_RES_0402LF-0,5%,1/16W,CHIP,CA
P1V05_PCH_AUX            U4               AB19     EMMITSBURG_REV0P9-GFNOCPU04302A
P1V05_PCH_AUX            U4               AB20     EMMITSBURG_REV0P9-GFNOCPU04302A
P1V05_PCH_AUX            U4               AB22     EMMITSBURG_REV0P9-GFNOCPU04302A
P1V05_PCH_AUX            U4               AB24     EMMITSBURG_REV0P9-GFNOCPU04302A
P1V05_PCH_AUX            U4               AD25     EMMITSBURG_REV0P9-GFNOCPU04302A
P1V05_PCH_AUX            U4               AD27     EMMITSBURG_REV0P9-GFNOCPU04302A
P1V05_PCH_AUX            U4               AF20     EMMITSBURG_REV0P9-GFNOCPU04302A
P1V05_PCH_AUX            U4               AF22     EMMITSBURG_REV0P9-GFNOCPU04302A
P1V05_PCH_AUX            U4               AF25     EMMITSBURG_REV0P9-GFNOCPU04302A
P1V05_PCH_AUX            U4               AF27     EMMITSBURG_REV0P9-GFNOCPU04302A
P1V05_PCH_AUX            U4               AG20     EMMITSBURG_REV0P9-GFNOCPU04302A
P1V05_PCH_AUX            U4               AG22     EMMITSBURG_REV0P9-GFNOCPU04302A
P1V05_PCH_AUX            U4               AG25     EMMITSBURG_REV0P9-GFNOCPU04302A
P1V05_PCH_AUX            U4               AG27     EMMITSBURG_REV0P9-GFNOCPU04302A
P1V05_PCH_AUX            U4               AJ20     EMMITSBURG_REV0P9-GFNOCPU04302A
P1V05_PCH_AUX            U4               AJ22     EMMITSBURG_REV0P9-GFNOCPU04302A
P1V05_PCH_AUX            U4               AJ25     EMMITSBURG_REV0P9-GFNOCPU04302A
P1V05_PCH_AUX            U4               AJ27     EMMITSBURG_REV0P9-GFNOCPU04302A
P1V05_PCH_AUX            U4               AL20     EMMITSBURG_REV0P9-GFNOCPU04302A
P1V05_PCH_AUX            U4               AL22     EMMITSBURG_REV0P9-GFNOCPU04302A
P1V05_PCH_AUX            U4               AN23     EMMITSBURG_REV0P9-GFNOCPU04302A
P1V05_PCH_AUX            U4               AP21     EMMITSBURG_REV0P9-GFNOCPU04302A
P1V05_PCH_AUX            U4               AR23     EMMITSBURG_REV0P9-GFNOCPU04302A
P1V05_PCH_AUX            U4               AR26     EMMITSBURG_REV0P9-GFNOCPU04302A
P1V05_PCH_AUX            U4               M24      EMMITSBURG_REV0P9-GFNOCPU04302A
P1V05_PCH_AUX            U4               N23      EMMITSBURG_REV0P9-GFNOCPU04302A
P1V05_PCH_AUX            U4               N26      EMMITSBURG_REV0P9-GFNOCPU04302A
P1V05_PCH_AUX            U4               P15      EMMITSBURG_REV0P9-GFNOCPU04302A
P1V05_PCH_AUX            U4               W17      EMMITSBURG_REV0P9-GFNOCPU04302A
P1V05_PCH_AUX            U4               W19      EMMITSBURG_REV0P9-GFNOCPU04302A
P1V05_PCH_AUX            U4               W20      EMMITSBURG_REV0P9-GFNOCPU04302A
P1V05_PCH_AUX            U4               W22      EMMITSBURG_REV0P9-GFNOCPU04302A
P1V05_PCH_AUX            U4               W24      EMMITSBURG_REV0P9-GFNOCPU04302A
P1V05_PCH_AUX            U87              D        MOSFET_N_SMLF-BSS138K,BSS138K,A
P1V05_PCH_AUX_CS         PR1327           1        Q_RES_0402LF-6.81K,1%,1/16W,CHA
P1V05_PCH_AUX_CS         PU73             3        MPQ8633BGLEC838Z-MPQ8633BGLE-CA
P1V05_PCH_AUX_FB         PC1223           1        Q_CAP_C0402-470PF,50V,5%,NPO,CA
P1V05_PCH_AUX_FB         PR187            1        Q_RES_0402LF-10K,1%,1/16W,CHIPA
P1V05_PCH_AUX_FB         PR1328           1        Q_RES_0402LF-7.32K,1%,1/16W,CHA
P1V05_PCH_AUX_FB         PU73             7        MPQ8633BGLEC838Z-MPQ8633BGLE-CA
P1V05_PCH_AUX_REF        PC1221           1        Q_CAP_0402-0.1UF,25V,10%,X7R,CA
P1V05_PCH_AUX_REF        PC2000           1        Q_CAP_0402-0.022UF,16V,10%,X7RA
P1V05_PCH_AUX_REF        PU73             5        MPQ8633BGLEC838Z-MPQ8633BGLE-CA
P1V05_PCH_AUX_VCC        PC113            1        Q_CAP_C0402-1UF,25V,10%,X6S,CHA
P1V05_PCH_AUX_VCC        PR1326           2        Q_RES_0402LF-0,5%,1/16W,CHIP,CA
P1V05_PCH_AUX_VCC        PU73             4        MPQ8633BGLEC838Z-MPQ8633BGLE-CA
P1V05_PCH_AUX_VCC        PU73             19       MPQ8633BGLEC838Z-MPQ8633BGLE-CA
P1V05_PCH_PLL_AUX        C1251            1        Q_CAP_C0603-10UF,6.3V,20%,X6S,A
P1V05_PCH_PLL_AUX        C1254            1        Q_CAP_C0603-10UF,6.3V,20%,X6S,A
P1V05_PCH_PLL_AUX        C1256            1        Q_CAP_0402-1UF,6.3V,10%,EMPTY,A
P1V05_PCH_PLL_AUX        C1258            1        Q_CAP_0805-47UF,4V,20%,X6S,CH6A
P1V05_PCH_PLL_AUX        C1260            1        Q_CAP_C0603-10UF,6.3V,20%,X6S,A
P1V05_PCH_PLL_AUX        C1262            1        Q_CAP_C0402-10UF,6.3V,20%,X6S,A
P1V05_PCH_PLL_AUX        C1264            1        Q_CAP_0402-1UF,6.3V,10%,EMPTY,A
P1V05_PCH_PLL_AUX        C1272            1        Q_CAP_0805-47UF,4V,20%,X6S,CH6A
P1V05_PCH_PLL_AUX        L2               2        Q_INDUCTOR_SMLF-BLM18PG121SN1DA
P1V05_PCH_PLL_AUX        R1463            2        Q_RES_0402LF-0,5%,1/16W,CHIP,CA
P1V05_PCH_PLL_AUX        U4               AA29     EMMITSBURG_REV0P9-GFNOCPU04302A
P1V05_PCH_PLL_AUX        U4               AB27     EMMITSBURG_REV0P9-GFNOCPU04302A
P1V05_PCH_PLL_AUX        U4               AE29     EMMITSBURG_REV0P9-GFNOCPU04302A
P1V05_PCH_PLL_AUX        U4               AG29     EMMITSBURG_REV0P9-GFNOCPU04302A
P1V05_PCH_PLL_AUX        U4               AL25     EMMITSBURG_REV0P9-GFNOCPU04302A
P1V05_PCH_PLL_AUX        U4               R23      EMMITSBURG_REV0P9-GFNOCPU04302A
P1V05_PCH_PLL_AUX        U4               R26      EMMITSBURG_REV0P9-GFNOCPU04302A
P1V05_PCH_PLL_AUX        U4               R29      EMMITSBURG_REV0P9-GFNOCPU04302A
P1V05_PCH_PLL_AUX        U4               U27      EMMITSBURG_REV0P9-GFNOCPU04302A
P1V8_PCH_AUX             C550             1        Q_CAP_C0402-1UF,25V,10%,X6S,CHA
P1V8_PCH_AUX             C1181            1        Q_CAP_C0603-22UF,4V,20%,X6S,CHA
P1V8_PCH_AUX             C1186            1        Q_CAP_C0603-22UF,4V,20%,X6S,CHA
P1V8_PCH_AUX             C1197            1        Q_CAP_C0603-22UF,4V,20%,X6S,CHA
P1V8_PCH_AUX             C1202            1        Q_CAP_C0603-22UF,4V,20%,X6S,CHA
P1V8_PCH_AUX             C1207            1        Q_CAP_C0402-10UF,6.3V,20%,X6S,A
P1V8_PCH_AUX             C1253            1        Q_CAP_0402-1UF,6.3V,10%,EMPTY,A
P1V8_PCH_AUX             C1323            1        Q_CAP_0402-0.1UF,25V,10%,X7R,CA
P1V8_PCH_AUX             J42              12       SCONN60_QSH03001LDAKTR-SCONN60A
P1V8_PCH_AUX             L10              1        Q_INDUCTOR_SMLF-BLM18PG121SN1DA
P1V8_PCH_AUX             PC1236           1        Q_CAP_C0402-100NF,50V,10%,X7R,A
P1V8_PCH_AUX             PC1237           1        Q_CAP_0805-22UF,4V,20%,X6S,TMPA
P1V8_PCH_AUX             PC1238           1        Q_CAP_0805-22UF,4V,20%,X6S,TMPA
P1V8_PCH_AUX             PC1239           1        Q_CAP_0805-22UF,4V,20%,X6S,TMPA
P1V8_PCH_AUX             PC1240           1        Q_CAP_0805-22UF,4V,20%,X6S,TMPA
P1V8_PCH_AUX             PC1241           1        Q_CAP_0805-22UF,4V,20%,X6S,TMPA
P1V8_PCH_AUX             PL170            2        Q_INDUCTOR_SMLF-1UH,IND,CV-10BA
P1V8_PCH_AUX             PU74             12       NB695GDZ-NB695GD-Z,SMLF,IC,AL0A
P1V8_PCH_AUX             R401             1        Q_RES_0402LF-10K,1%,1/16W,EMPTA
P1V8_PCH_AUX             R623             1        Q_RES_0402LF-1K,5%,1/16W,EMPTYA
P1V8_PCH_AUX             R1464            1        Q_RES_0402LF-0,5%,1/16W,CHIP,CA
P1V8_PCH_AUX             R1700            1        Q_RES_0402LF-4.7K,5%,1/16W,CHIA
P1V8_PCH_AUX             R1702            1        Q_RES_0402LF-4.7K,5%,1/16W,CHIA
P1V8_PCH_AUX             R1703            1        Q_RES_0402LF-4.7K,5%,1/16W,CHIA
P1V8_PCH_AUX             R1747            1        Q_RES_0805LF-0,5%,1/8W,CHIP,CSA
P1V8_PCH_AUX             U4               N20      EMMITSBURG_REV0P9-GFNOCPU04302A
P1V8_PCH_AUX             U4               U17      EMMITSBURG_REV0P9-GFNOCPU04302A
P1V8_PCH_AUX             U4               U19      EMMITSBURG_REV0P9-GFNOCPU04302A
P1V8_PCH_AUX             U4               U20      EMMITSBURG_REV0P9-GFNOCPU04302A
P1V8_PCH_AUX             U4               U22      EMMITSBURG_REV0P9-GFNOCPU04302A
P1V8_PCH_AUX             U4               U24      EMMITSBURG_REV0P9-GFNOCPU04302A
P1V8_PCH_AUX             U98              2        PCA9306DCTR-PCA9306DCTR,SMLF,IA
P1V8_PCH_AUX_MODE        PR1330           1        Q_RES_0402LF-150K,1%,1/16W,CHIA
P1V8_PCH_AUX_MODE        PU74             7        NB695GDZ-NB695GD-Z,SMLF,IC,AL0A
P1V8_PCH_AUX_VCC         PC1642           1        Q_CAP_C0402-1UF,25V,10%,X6S,CHA
P1V8_PCH_AUX_VCC         PR1329           2        Q_RES_0402LF-5.1,5%,1/16W,CHIPA
P1V8_PCH_AUX_VCC         PU74             3        NB695GDZ-NB695GD-Z,SMLF,IC,AL0A
P1V8_PCH_AUX_VCC         PU74             6        NB695GDZ-NB695GD-Z,SMLF,IC,AL0A
P1V8_PCH_AUX_VCC         PU74             10       NB695GDZ-NB695GD-Z,SMLF,IC,AL0A
P1V8_PCH_PLL_AUX         C1252            1        Q_CAP_C0603-10UF,6.3V,20%,X6S,A
P1V8_PCH_PLL_AUX         C1255            1        Q_CAP_C0603-10UF,6.3V,20%,X6S,A
P1V8_PCH_PLL_AUX         C1257            1        Q_CAP_0402-1UF,6.3V,10%,EMPTY,A
P1V8_PCH_PLL_AUX         C1259            1        Q_CAP_0805-47UF,4V,20%,X6S,CH6A
P1V8_PCH_PLL_AUX         C1261            1        Q_CAP_C0603-10UF,6.3V,20%,X6S,A
P1V8_PCH_PLL_AUX         C1263            1        Q_CAP_C0402-10UF,6.3V,20%,X6S,A
P1V8_PCH_PLL_AUX         C1265            1        Q_CAP_0402-1UF,6.3V,10%,EMPTY,A
P1V8_PCH_PLL_AUX         C1266            1        Q_CAP_C0402-10UF,6.3V,20%,X6S,A
P1V8_PCH_PLL_AUX         C1273            1        Q_CAP_0805-47UF,4V,20%,X6S,CH6A
P1V8_PCH_PLL_AUX         L10              2        Q_INDUCTOR_SMLF-BLM18PG121SN1DA
P1V8_PCH_PLL_AUX         R1464            2        Q_RES_0402LF-0,5%,1/16W,CHIP,CA
P1V8_PCH_PLL_AUX         U4               AB31     EMMITSBURG_REV0P9-GFNOCPU04302A
P1V8_PCH_PLL_AUX         U4               AB34     EMMITSBURG_REV0P9-GFNOCPU04302A
P1V8_PCH_PLL_AUX         U4               U29      EMMITSBURG_REV0P9-GFNOCPU04302A
P1V8_PCH_PLL_AUX         U4               W27      EMMITSBURG_REV0P9-GFNOCPU04302A
P1V8_PCH_PLL_AUX         U4               W29      EMMITSBURG_REV0P9-GFNOCPU04302A
P3E_PCH_BMC_RX_DN        J41              A19      SCONN168_623403212-SCONN168_6-A
P3E_PCH_BMC_RX_DN        U4               M41      EMMITSBURG_REV0P9-GFNOCPU04302A
P3E_PCH_BMC_RX_DP        J41              A18      SCONN168_623403212-SCONN168_6-A
P3E_PCH_BMC_RX_DP        U4               M43      EMMITSBURG_REV0P9-GFNOCPU04302A
P3E_PCH_BMC_TX_C_DN      C644             2        Q_CAP_DIFFBUS_C0402-DIFF BUS_0A
P3E_PCH_BMC_TX_C_DN      J41              A16      SCONN168_623403212-SCONN168_6-A
P3E_PCH_BMC_TX_C_DP      C643             2        Q_CAP_DIFFBUS_C0402-DIFF BUS_0A
P3E_PCH_BMC_TX_C_DP      J41              A15      SCONN168_623403212-SCONN168_6-A
P3E_PCH_BMC_TX_DN        C644             1        Q_CAP_DIFFBUS_C0402-DIFF BUS_0A
P3E_PCH_BMC_TX_DN        U4               W36      EMMITSBURG_REV0P9-GFNOCPU04302A
P3E_PCH_BMC_TX_DP        C643             1        Q_CAP_DIFFBUS_C0402-DIFF BUS_0A
P3E_PCH_BMC_TX_DP        U4               Y37      EMMITSBURG_REV0P9-GFNOCPU04302A
P3E_PCH_M2_RX_C_DN<3>    C1420            1        Q_CAP_DIFFBUS_C0201-DIFF BUS_0B
P3E_PCH_M2_RX_C_DN<3>    J59              43       SCONN75K_APCI0155P004A-SCONN75A
P3E_PCH_M2_RX_C_DP<3>    C1421            1        Q_CAP_DIFFBUS_C0201-DIFF BUS_0B
P3E_PCH_M2_RX_C_DP<3>    J59              41       SCONN75K_APCI0155P004A-SCONN75A
P3E_PCH_M2_RX_DN<0>      J59              5        SCONN75K_APCI0155P004A-SCONN75A
P3E_PCH_M2_RX_DN<0>      U4               AE41     EMMITSBURG_REV0P9-GFNOCPU04302A
P3E_PCH_M2_RX_DN<1>      J59              17       SCONN75K_APCI0155P004A-SCONN75A
P3E_PCH_M2_RX_DN<1>      U4               AD40     EMMITSBURG_REV0P9-GFNOCPU04302A
P3E_PCH_M2_RX_DN<2>      J59              29       SCONN75K_APCI0155P004A-SCONN75A
P3E_PCH_M2_RX_DN<2>      U4               AC41     EMMITSBURG_REV0P9-GFNOCPU04302A
P3E_PCH_M2_RX_DN<3>      C1420            2        Q_CAP_DIFFBUS_C0201-DIFF BUS_0B
P3E_PCH_M2_RX_DN<3>      U4               AB40     EMMITSBURG_REV0P9-GFNOCPU04302A
P3E_PCH_M2_RX_DN<4>      J41              A60      SCONN168_623403212-SCONN168_6-A
P3E_PCH_M2_RX_DN<4>      U4               AA41     EMMITSBURG_REV0P9-GFNOCPU04302A
P3E_PCH_M2_RX_DP<0>      J59              7        SCONN75K_APCI0155P004A-SCONN75A
P3E_PCH_M2_RX_DP<0>      U4               AE43     EMMITSBURG_REV0P9-GFNOCPU04302A
P3E_PCH_M2_RX_DP<1>      J59              19       SCONN75K_APCI0155P004A-SCONN75A
P3E_PCH_M2_RX_DP<1>      U4               AD42     EMMITSBURG_REV0P9-GFNOCPU04302A
P3E_PCH_M2_RX_DP<2>      J59              31       SCONN75K_APCI0155P004A-SCONN75A
P3E_PCH_M2_RX_DP<2>      U4               AC43     EMMITSBURG_REV0P9-GFNOCPU04302A
P3E_PCH_M2_RX_DP<3>      C1421            2        Q_CAP_DIFFBUS_C0201-DIFF BUS_0B
P3E_PCH_M2_RX_DP<3>      U4               AB42     EMMITSBURG_REV0P9-GFNOCPU04302A
P3E_PCH_M2_RX_DP<4>      J41              A59      SCONN168_623403212-SCONN168_6-A
P3E_PCH_M2_RX_DP<4>      U4               AA43     EMMITSBURG_REV0P9-GFNOCPU04302A
P3E_PCH_M2_TX_C_DN<0>    C1105            2        Q_CAP_DIFFBUS_C0201-DIFF BUS_0A
P3E_PCH_M2_TX_C_DN<0>    J59              13       SCONN75K_APCI0155P004A-SCONN75A
P3E_PCH_M2_TX_C_DN<1>    C1103            2        Q_CAP_DIFFBUS_C0201-DIFF BUS_0A
P3E_PCH_M2_TX_C_DN<1>    J59              25       SCONN75K_APCI0155P004A-SCONN75A
P3E_PCH_M2_TX_C_DN<2>    C1101            2        Q_CAP_DIFFBUS_C0201-DIFF BUS_0A
P3E_PCH_M2_TX_C_DN<2>    J59              37       SCONN75K_APCI0155P004A-SCONN75A
P3E_PCH_M2_TX_C_DN<3>    C1099            2        Q_CAP_DIFFBUS_C0201-DIFF BUS_0A
P3E_PCH_M2_TX_C_DN<3>    J59              47       SCONN75K_APCI0155P004A-SCONN75A
P3E_PCH_M2_TX_C_DN<4>    C1097            2        Q_CAP_DIFFBUS_C0201-DIFF BUS_0A
P3E_PCH_M2_TX_C_DN<4>    J41              B60      SCONN168_623403212-SCONN168_6-A
P3E_PCH_M2_TX_C_DP<0>    C1104            2        Q_CAP_DIFFBUS_C0201-DIFF BUS_0A
P3E_PCH_M2_TX_C_DP<0>    J59              11       SCONN75K_APCI0155P004A-SCONN75A
P3E_PCH_M2_TX_C_DP<1>    C1102            2        Q_CAP_DIFFBUS_C0201-DIFF BUS_0A
P3E_PCH_M2_TX_C_DP<1>    J59              23       SCONN75K_APCI0155P004A-SCONN75A
P3E_PCH_M2_TX_C_DP<2>    C1100            2        Q_CAP_DIFFBUS_C0201-DIFF BUS_0A
P3E_PCH_M2_TX_C_DP<2>    J59              35       SCONN75K_APCI0155P004A-SCONN75A
P3E_PCH_M2_TX_C_DP<3>    C1098            2        Q_CAP_DIFFBUS_C0201-DIFF BUS_0A
P3E_PCH_M2_TX_C_DP<3>    J59              49       SCONN75K_APCI0155P004A-SCONN75A
P3E_PCH_M2_TX_C_DP<4>    C1096            2        Q_CAP_DIFFBUS_C0201-DIFF BUS_0A
P3E_PCH_M2_TX_C_DP<4>    J41              B59      SCONN168_623403212-SCONN168_6-A
P3E_PCH_M2_TX_DN<0>      C1105            1        Q_CAP_DIFFBUS_C0201-DIFF BUS_0A
P3E_PCH_M2_TX_DN<0>      U4               AL32     EMMITSBURG_REV0P9-GFNOCPU04302A
P3E_PCH_M2_TX_DN<1>      C1103            1        Q_CAP_DIFFBUS_C0201-DIFF BUS_0A
P3E_PCH_M2_TX_DN<1>      U4               AN36     EMMITSBURG_REV0P9-GFNOCPU04302A
P3E_PCH_M2_TX_DN<2>      C1101            1        Q_CAP_DIFFBUS_C0201-DIFF BUS_0A
P3E_PCH_M2_TX_DN<2>      U4               AR36     EMMITSBURG_REV0P9-GFNOCPU04302A
P3E_PCH_M2_TX_DN<3>      C1099            1        Q_CAP_DIFFBUS_C0201-DIFF BUS_0A
P3E_PCH_M2_TX_DN<3>      U4               AK34     EMMITSBURG_REV0P9-GFNOCPU04302A
P3E_PCH_M2_TX_DN<4>      C1097            1        Q_CAP_DIFFBUS_C0201-DIFF BUS_0A
P3E_PCH_M2_TX_DN<4>      U4               AL36     EMMITSBURG_REV0P9-GFNOCPU04302A
P3E_PCH_M2_TX_DP<0>      C1104            1        Q_CAP_DIFFBUS_C0201-DIFF BUS_0A
P3E_PCH_M2_TX_DP<0>      U4               AK31     EMMITSBURG_REV0P9-GFNOCPU04302A
P3E_PCH_M2_TX_DP<1>      C1102            1        Q_CAP_DIFFBUS_C0201-DIFF BUS_0A
P3E_PCH_M2_TX_DP<1>      U4               AP34     EMMITSBURG_REV0P9-GFNOCPU04302A
P3E_PCH_M2_TX_DP<2>      C1100            1        Q_CAP_DIFFBUS_C0201-DIFF BUS_0A
P3E_PCH_M2_TX_DP<2>      U4               AT37     EMMITSBURG_REV0P9-GFNOCPU04302A
P3E_PCH_M2_TX_DP<3>      C1098            1        Q_CAP_DIFFBUS_C0201-DIFF BUS_0A
P3E_PCH_M2_TX_DP<3>      U4               AM34     EMMITSBURG_REV0P9-GFNOCPU04302A
P3E_PCH_M2_TX_DP<4>      C1096            1        Q_CAP_DIFFBUS_C0201-DIFF BUS_0A
P3E_PCH_M2_TX_DP<4>      U4               AM37     EMMITSBURG_REV0P9-GFNOCPU04302A
P3V3                     C129             1        Q_CAPP_SMLF-100UF,16V,20%,POSCA
P3V3                     C130             1        Q_CAP_0402-0.1UF,25V,10%,X7R,CA
P3V3                     C135             1        Q_CAPP_SMLF-100UF,16V,20%,POSCA
P3V3                     C136             1        Q_CAP_0402-0.1UF,25V,10%,X7R,CA
P3V3                     C1078            1        Q_CAP_C0603-22UF,6.3V,20%,X6S,A
P3V3                     C1080            1        Q_CAP_C0603-22UF,6.3V,20%,X6S,A
P3V3                     C1082            1        Q_CAP_C0603-22UF,6.3V,20%,X6S,A
P3V3                     C1084            1        Q_CAP_0402-0.1UF,25V,10%,X7R,CA
P3V3                     C1086            1        Q_CAP_0402-0.1UF,25V,10%,X7R,CA
P3V3                     C1088            1        Q_CAP_0402-0.1UF,25V,10%,X7R,CA
P3V3                     C1208            1        Q_CAP_0402-0.1UF,25V,10%,X7R,CA
P3V3                     C1215            1        Q_CAP_0402-0.1UF,25V,10%,X7R,CA
P3V3                     C1216            1        Q_CAP_0402-0.1UF,25V,10%,X7R,CA
P3V3                     C1217            1        Q_CAP_0402-0.1UF,25V,10%,X7R,CA
P3V3                     C1218            1        Q_CAP_0402-0.1UF,25V,10%,X7R,CA
P3V3                     C1219            1        Q_CAP_0402-0.1UF,25V,10%,X7R,CA
P3V3                     C1339            1        Q_CAP_C0402-100NF,50V,10%,X7R,A
P3V3                     C1340            1        Q_CAP_C0805-10UF,16V,10%,X6S,CA
P3V3                     C1446            1        Q_CAP_0402-0.1UF,25V,10%,X7R,CA
P3V3                     C1447            1        Q_CAP_0402-0.1UF,25V,10%,X7R,CA
P3V3                     C1456            1        Q_CAP_0402-0.1UF,25V,10%,X7R,CA
P3V3                     C1457            1        Q_CAP_0402-0.1UF,25V,10%,X7R,CA
P3V3                     C1466            1        Q_CAP_0402-0.1UF,25V,10%,X7R,CA
P3V3                     C1467            1        Q_CAP_0402-0.1UF,25V,10%,X7R,CA
P3V3                     C1476            1        Q_CAP_0402-0.1UF,25V,10%,X7R,CA
P3V3                     C1477            1        Q_CAP_0402-0.1UF,25V,10%,X7R,CA
P3V3                     C1603            1        Q_CAPP_SMLF-100UF,16V,20%,POSCA
P3V3                     C1604            1        Q_CAP_0402-0.1UF,25V,10%,X7R,CA
P3V3                     D7               1        BAT547F-BAT547F,SMLF,IC,BC0BATA
P3V3                     J33              A42      SCONN84_123318136-SCONN84_1-23A
P3V3                     J34              A42      SCONN84_123318136-SCONN84_1-23A
P3V3                     J35              A3       SCONN140_G64V3431BHR-SCONN140_B
P3V3                     J35              A4       SCONN140_G64V3431BHR-SCONN140_B
P3V3                     J55              A68      SCONN140_G64V3431BHR-SCONN140_A
P3V3                     J55              A69      SCONN140_G64V3431BHR-SCONN140_A
P3V3                     J55              B69      SCONN140_G64V3431BHR-SCONN140_A
P3V3                     J57              A68      SCONN140_G64V3431BHR-SCONN140_A
P3V3                     J57              A69      SCONN140_G64V3431BHR-SCONN140_A
P3V3                     J57              B69      SCONN140_G64V3431BHR-SCONN140_A
P3V3                     J59              2        SCONN75K_APCI0155P004A-SCONN75A
P3V3                     J59              4        SCONN75K_APCI0155P004A-SCONN75A
P3V3                     J59              12       SCONN75K_APCI0155P004A-SCONN75A
P3V3                     J59              14       SCONN75K_APCI0155P004A-SCONN75A
P3V3                     J59              16       SCONN75K_APCI0155P004A-SCONN75A
P3V3                     J59              18       SCONN75K_APCI0155P004A-SCONN75A
P3V3                     J59              70       SCONN75K_APCI0155P004A-SCONN75A
P3V3                     J59              72       SCONN75K_APCI0155P004A-SCONN75A
P3V3                     J59              74       SCONN75K_APCI0155P004A-SCONN75A
P3V3                     J61              A7       SCONN84_123318136-SCONN84_1-23A
P3V3                     J61              A8       SCONN84_123318136-SCONN84_1-23A
P3V3                     J61              A9       SCONN84_123318136-SCONN84_1-23A
P3V3                     J89              B135     SCONN280_ME1028040102011-SCONNA
P3V3                     J89              B136     SCONN280_ME1028040102011-SCONNA
P3V3                     J89              B137     SCONN280_ME1028040102011-SCONNA
P3V3                     J89              B138     SCONN280_ME1028040102011-SCONNA
P3V3                     J89              B139     SCONN280_ME1028040102011-SCONNA
P3V3                     J89              B140     SCONN280_ME1028040102011-SCONNA
P3V3                     L3               1        Q_INDUCTOR_SMLF-BLM18SG331TN1DA
P3V3                     L4               1        Q_INDUCTOR_SMLF-BLM18SG331TN1DA
P3V3                     PQ2              1        MOSFET_NCH_1D3S-PSMNR58-30YLH,A
P3V3                     PQ2              2        MOSFET_NCH_1D3S-PSMNR58-30YLH,A
P3V3                     PQ2              3        MOSFET_NCH_1D3S-PSMNR58-30YLH,A
P3V3                     PR403            1        Q_RES_0402LF-0,5%,1/16W,EMPTY,A
P3V3                     PR441            1        Q_RES_0402LF-0,5%,1/16W,EMPTY,A
P3V3                     PR443            1        Q_RES_0402LF-0,5%,1/16W,EMPTY,A
P3V3                     PR632            1        Q_RES_0402LF-0,5%,1/16W,EMPTY,A
P3V3                     PR633            1        Q_RES_0402LF-0,5%,1/16W,EMPTY,A
P3V3                     PR636            1        Q_RES_0402LF-0,5%,1/16W,EMPTY,A
P3V3                     PR640            1        Q_RES_0402LF-0,5%,1/16W,EMPTY,A
P3V3                     PR677            1        Q_RES_0402LF-0,5%,1/16W,EMPTY,A
P3V3                     PR699            1        Q_RES_0402LF-0,5%,1/16W,EMPTY,A
P3V3                     PR703            1        Q_RES_0402LF-0,5%,1/16W,EMPTY,A
P3V3                     PR704            1        Q_RES_0402LF-0,5%,1/16W,EMPTY,A
P3V3                     PR707            1        Q_RES_0402LF-0,5%,1/16W,EMPTY,A
P3V3                     R112             1        Q_RES_0402LF-10K,1%,1/16W,EMPTA
P3V3                     R241             1        Q_RES_0402LF-1K,1%,1/16W,EMPTYA
P3V3                     R242             1        Q_RES_0402LF-1K,1%,1/16W,EMPTYA
P3V3                     R484             1        Q_RES_0402LF-4.7K,1%,1/16W,EMPA
P3V3                     R567             1        Q_RES_0402LF-4.7K,1%,1/16W,EMPA
P3V3                     R569             1        Q_RES_0402LF-4.7K,1%,1/16W,EMPA
P3V3                     R573             1        Q_RES_0402LF-4.7K,1%,1/16W,EMPA
P3V3                     R1000            1        Q_RES_0402LF-4.7K,5%,1/16W,CHIA
P3V3                     R1001            1        Q_RES_0402LF-4.7K,5%,1/16W,CHIA
P3V3                     R1002            1        Q_RES_0402LF-4.7K,5%,1/16W,CHIA
P3V3                     R1003            1        Q_RES_0402LF-4.7K,5%,1/16W,CHIA
P3V3                     R1542            1        Q_RES_0402LF-10K,1%,1/16W,CHIPA
P3V3                     R1706            1        Q_RES_0402LF-4.7K,5%,1/16W,EMPA
P3V3                     R1788            1        Q_RES_0402LF-0,1%,1/16W,CHIP,TA
P3V3                     U79              3        SLG55221120010VTR-SLG55221-120A
P3V3                     U79              6        SLG55221120010VTR-SLG55221-120A
P3V3_AUX                 C1               1        Q_CAP_C0402-10UF,6.3V,20%,X6S,A
P3V3_AUX                 C2               1        Q_CAP_C0402-2.2UF,6.3V,20%,X6SA
P3V3_AUX                 C5               1        Q_CAP_C0402-2.2UF,6.3V,20%,X6SA
P3V3_AUX                 C8               1        Q_CAP_C0402-2.2UF,6.3V,20%,X6SA
P3V3_AUX                 C11              1        Q_CAP_C0402-2.2UF,6.3V,20%,X6SA
P3V3_AUX                 C14              1        Q_CAP_C0402-2.2UF,6.3V,20%,X6SA
P3V3_AUX                 C17              1        Q_CAP_C0402-2.2UF,6.3V,20%,X6SA
P3V3_AUX                 C20              1        Q_CAP_C0402-2.2UF,6.3V,20%,X6SA
P3V3_AUX                 C23              1        Q_CAP_C0402-2.2UF,6.3V,20%,X6SA
P3V3_AUX                 C26              1        Q_CAP_C0402-2.2UF,6.3V,20%,X6SA
P3V3_AUX                 C29              1        Q_CAP_C0402-2.2UF,6.3V,20%,X6SA
P3V3_AUX                 C32              1        Q_CAP_C0402-2.2UF,6.3V,20%,X6SA
P3V3_AUX                 C35              1        Q_CAP_C0402-2.2UF,6.3V,20%,X6SA
P3V3_AUX                 C38              1        Q_CAP_C0402-2.2UF,6.3V,20%,X6SA
P3V3_AUX                 C41              1        Q_CAP_C0402-2.2UF,6.3V,20%,X6SA
P3V3_AUX                 C44              1        Q_CAP_C0402-2.2UF,6.3V,20%,X6SA
P3V3_AUX                 C47              1        Q_CAP_C0402-2.2UF,6.3V,20%,X6SA
P3V3_AUX                 C50              1        Q_CAP_C0402-2.2UF,6.3V,20%,X6SA
P3V3_AUX                 C53              1        Q_CAP_C0402-2.2UF,6.3V,20%,X6SA
P3V3_AUX                 C56              1        Q_CAP_C0402-2.2UF,6.3V,20%,X6SA
P3V3_AUX                 C59              1        Q_CAP_C0402-2.2UF,6.3V,20%,X6SA
P3V3_AUX                 C62              1        Q_CAP_C0402-2.2UF,6.3V,20%,X6SA
P3V3_AUX                 C65              1        Q_CAP_C0402-2.2UF,6.3V,20%,X6SA
P3V3_AUX                 C68              1        Q_CAP_C0402-2.2UF,6.3V,20%,X6SA
P3V3_AUX                 C71              1        Q_CAP_C0402-10UF,6.3V,20%,X6S,A
P3V3_AUX                 C72              1        Q_CAP_C0402-2.2UF,6.3V,20%,X6SA
P3V3_AUX                 C75              1        Q_CAP_C0402-2.2UF,6.3V,20%,X6SA
P3V3_AUX                 C78              1        Q_CAP_C0402-2.2UF,6.3V,20%,X6SA
P3V3_AUX                 C81              1        Q_CAP_C0402-2.2UF,6.3V,20%,X6SA
P3V3_AUX                 C84              1        Q_CAP_C0402-2.2UF,6.3V,20%,X6SA
P3V3_AUX                 C87              1        Q_CAP_C0402-2.2UF,6.3V,20%,X6SA
P3V3_AUX                 C90              1        Q_CAP_C0402-2.2UF,6.3V,20%,X6SA
P3V3_AUX                 C93              1        Q_CAP_C0402-2.2UF,6.3V,20%,X6SA
P3V3_AUX                 C96              1        Q_CAP_C0402-2.2UF,6.3V,20%,X6SA
P3V3_AUX                 C131             1        Q_CAP_C0402-1UF,25V,10%,X6S,CHA
P3V3_AUX                 C132             1        Q_CAP_0402-0.1UF,25V,10%,X7R,CA
P3V3_AUX                 C137             1        Q_CAP_C0402-1UF,25V,10%,X6S,CHA
P3V3_AUX                 C138             1        Q_CAP_0402-0.1UF,25V,10%,X7R,CA
P3V3_AUX                 C174             1        Q_CAP_0402-0.1UF,25V,10%,X7R,CA
P3V3_AUX                 C188             1        Q_CAP_0402-0.1UF,25V,10%,X7R,CA
P3V3_AUX                 C536             1        Q_CAP_0402-0.1UF,25V,10%,X7R,CA
P3V3_AUX                 C537             1        Q_CAP_0402-0.1UF,25V,10%,X7R,CA
P3V3_AUX                 C538             1        Q_CAP_0402-0.1UF,25V,10%,X7R,CA
P3V3_AUX                 C539             1        Q_CAP_0402-0.1UF,25V,10%,X7R,CA
P3V3_AUX                 C540             1        Q_CAP_0402-0.1UF,25V,10%,X7R,CA
P3V3_AUX                 C541             1        Q_CAP_C0402-1UF,25V,10%,X6S,CHA
P3V3_AUX                 C542             1        Q_CAP_C0402-1UF,25V,10%,X6S,CHA
P3V3_AUX                 C543             1        Q_CAP_0402-0.1UF,25V,10%,X7R,CA
P3V3_AUX                 C544             1        Q_CAP_0402-0.1UF,25V,10%,X7R,CA
P3V3_AUX                 C545             1        Q_CAP_C0402-1UF,25V,10%,X6S,CHA
P3V3_AUX                 C546             1        Q_CAP_C0402-1UF,25V,10%,X6S,CHA
P3V3_AUX                 C551             1        Q_CAP_C0402-1UF,25V,10%,X6S,CHA
P3V3_AUX                 C553             1        Q_CAP_0402-0.1UF,25V,10%,X7R,CA
P3V3_AUX                 C554             1        Q_CAP_0402-0.1UF,25V,10%,X7R,CA
P3V3_AUX                 C561             1        Q_CAP_0402-0.1UF,25V,10%,X7R,CA
P3V3_AUX                 C562             1        Q_CAP_0402-0.1UF,25V,10%,X7R,CA
P3V3_AUX                 C563             1        Q_CAP_C0805-10UF,25V,10%,X6S,CA
P3V3_AUX                 C569             1        Q_CAP_0402-0.1UF,25V,10%,X7R,CA
P3V3_AUX                 C570             1        Q_CAP_0402-0.1UF,25V,10%,X7R,CA
P3V3_AUX                 C578             1        Q_CAP_0402-0.1UF,25V,10%,X7R,CA
P3V3_AUX                 C579             1        Q_CAP_0402-0.1UF,25V,10%,X7R,CA
P3V3_AUX                 C580             1        Q_CAP_0402-0.1UF,25V,10%,X7R,CA
P3V3_AUX                 C581             1        Q_CAP_0402-0.1UF,25V,10%,X7R,CA
P3V3_AUX                 C592             1        Q_CAP_0402-0.1UF,25V,10%,X7R,CA
P3V3_AUX                 C593             1        Q_CAP_0402-0.1UF,25V,10%,X7R,CA
P3V3_AUX                 C629             1        Q_CAP_0402-0.1UF,25V,10%,X7R,CA
P3V3_AUX                 C630             1        Q_CAP_0402-0.1UF,25V,10%,X7R,CA
P3V3_AUX                 C631             1        Q_CAP_0402-0.1UF,25V,10%,X7R,CA
P3V3_AUX                 C639             1        Q_CAP_0402-0.1UF,25V,10%,X7R,CA
P3V3_AUX                 C640             1        Q_CAP_0402-0.1UF,25V,10%,X7R,CA
P3V3_AUX                 C641             1        Q_CAP_0402-0.1UF,25V,10%,X7R,CA
P3V3_AUX                 C1046            1        Q_CAP_C0805-22UF,16V,20%,X6S,CA
P3V3_AUX                 C1053            1        Q_CAP_C0805-22UF,16V,20%,X6S,CA
P3V3_AUX                 C1054            1        Q_CAP_C0805-22UF,16V,20%,X6S,CA
P3V3_AUX                 C1061            1        Q_CAP_C0805-22UF,16V,20%,X6S,CA
P3V3_AUX                 C1069            1        Q_CAP_C0805-22UF,16V,20%,X6S,CA
P3V3_AUX                 C1107            1        Q_CAP_0402-0.1UF,25V,10%,X7R,CA
P3V3_AUX                 C1108            1        Q_CAP_0402-0.1UF,25V,10%,X7R,CA
P3V3_AUX                 C1110            1        Q_CAP_0402-0.1UF,25V,10%,X7R,CA
P3V3_AUX                 C1111            1        Q_CAP_0402-0.1UF,25V,10%,X7R,CA
P3V3_AUX                 C1113            1        Q_CAP_0402-0.1UF,25V,10%,X7R,CA
P3V3_AUX                 C1114            1        Q_CAP_0402-0.1UF,25V,10%,X7R,CA
P3V3_AUX                 C1118            1        Q_CAP_0402-0.1UF,25V,10%,X7R,CA
P3V3_AUX                 C1119            1        Q_CAP_0402-0.1UF,25V,10%,X7R,CA
P3V3_AUX                 C1122            1        Q_CAP_0402-0.1UF,25V,10%,X7R,CA
P3V3_AUX                 C1123            1        Q_CAP_0402-0.1UF,25V,10%,X7R,CA
P3V3_AUX                 C1127            1        Q_CAP_0402-0.1UF,25V,10%,X7R,CA
P3V3_AUX                 C1128            1        Q_CAP_0402-0.1UF,25V,10%,X7R,CA
P3V3_AUX                 C1133            1        Q_CAP_0402-0.1UF,25V,10%,X7R,CA
P3V3_AUX                 C1134            1        Q_CAP_0402-0.1UF,25V,10%,X7R,CA
P3V3_AUX                 C1138            1        Q_CAP_0402-0.1UF,25V,10%,X7R,CA
P3V3_AUX                 C1139            1        Q_CAP_0402-0.1UF,25V,10%,X7R,CA
P3V3_AUX                 C1142            1        Q_CAP_0402-0.1UF,25V,10%,X7R,CA
P3V3_AUX                 C1143            1        Q_CAP_0402-0.1UF,25V,10%,X7R,CA
P3V3_AUX                 C1146            1        Q_CAP_0402-0.1UF,25V,10%,X7R,CA
P3V3_AUX                 C1147            1        Q_CAP_0402-0.1UF,25V,10%,X7R,CA
P3V3_AUX                 C1150            1        Q_CAP_0402-0.1UF,25V,10%,X7R,CA
P3V3_AUX                 C1151            1        Q_CAP_0402-0.1UF,25V,10%,X7R,CA
P3V3_AUX                 C1152            1        Q_CAP_0402-0.1UF,25V,10%,X7R,CA
P3V3_AUX                 C1153            1        Q_CAP_0402-0.1UF,25V,10%,X7R,CA
P3V3_AUX                 C1154            1        Q_CAP_0402-0.1UF,25V,10%,X7R,CA
P3V3_AUX                 C1155            1        Q_CAP_0402-0.1UF,25V,10%,X7R,CA
P3V3_AUX                 C1156            1        Q_CAP_0402-0.1UF,25V,10%,X7R,CA
P3V3_AUX                 C1157            1        Q_CAP_0402-0.1UF,25V,10%,X7R,CA
P3V3_AUX                 C1158            1        Q_CAP_0402-0.1UF,25V,10%,X7R,CA
P3V3_AUX                 C1159            1        Q_CAP_0402-0.1UF,25V,10%,X7R,CA
P3V3_AUX                 C1161            1        Q_CAP_0402-0.1UF,25V,10%,X7R,CA
P3V3_AUX                 C1162            1        Q_CAP_0402-0.1UF,25V,10%,X7R,CA
P3V3_AUX                 C1163            1        Q_CAP_0402-0.1UF,25V,10%,X7R,CA
P3V3_AUX                 C1164            1        Q_CAP_0402-0.1UF,25V,10%,X7R,CA
P3V3_AUX                 C1165            1        Q_CAP_0402-0.1UF,25V,10%,X7R,CA
P3V3_AUX                 C1167            1        Q_CAP_0402-0.1UF,25V,10%,X7R,CA
P3V3_AUX                 C1168            1        Q_CAP_0402-0.1UF,25V,10%,X7R,CA
P3V3_AUX                 C1173            1        Q_CAP_0402-0.1UF,25V,10%,X7R,CA
P3V3_AUX                 C1175            1        Q_CAP_0402-0.1UF,25V,10%,X7R,CA
P3V3_AUX                 C1184            1        Q_CAP_C0603-22UF,4V,20%,X6S,CHA
P3V3_AUX                 C1191            1        Q_CAP_C0603-22UF,4V,20%,X6S,CHA
P3V3_AUX                 C1201            1        Q_CAP_C0603-22UF,4V,20%,X6S,CHA
P3V3_AUX                 C1206            1        Q_CAP_C0402-10UF,6.3V,20%,X6S,A
P3V3_AUX                 C1241            1        Q_CAP_0402-0.1UF,25V,10%,X7R,CA
P3V3_AUX                 C1243            1        Q_CAP_0805-47UF,4V,20%,X6S,CH6A
P3V3_AUX                 C1245            1        Q_CAP_0805-47UF,4V,20%,X6S,CH6A
P3V3_AUX                 C1274            1        Q_CAP_0402-0.1UF,25V,10%,X7R,CA
P3V3_AUX                 C1275            1        Q_CAP_0402-0.1UF,25V,10%,X7R,CA
P3V3_AUX                 C1288            1        Q_CAP_0402-0.1UF,25V,10%,X7R,CA
P3V3_AUX                 C1289            1        Q_CAP_C0402-1UF,25V,10%,X6S,CHA
P3V3_AUX                 C1290            1        Q_CAP_C0402-1UF,25V,10%,X6S,CHA
P3V3_AUX                 C1291            1        Q_CAP_C0402-1UF,25V,10%,X6S,CHA
P3V3_AUX                 C1292            1        Q_CAP_0402-0.1UF,25V,10%,X7R,CA
P3V3_AUX                 C1305            1        Q_CAP_0402-0.1UF,25V,10%,X7R,CA
P3V3_AUX                 C1315            1        Q_CAP_C0402-1UF,25V,10%,X6S,CHA
P3V3_AUX                 C1317            1        Q_CAP_0402-0.1UF,25V,10%,X7R,CA
P3V3_AUX                 C1320            1        Q_CAP_0402-0.1UF,25V,10%,X7R,CA
P3V3_AUX                 C1321            1        Q_CAP_0402-0.1UF,25V,10%,X7R,CA
P3V3_AUX                 C1322            1        Q_CAP_0402-0.1UF,25V,10%,X7R,CA
P3V3_AUX                 C1332            1        Q_CAP_C0402-100NF,50V,10%,X7R,A
P3V3_AUX                 C1333            1        Q_CAP_C0805-10UF,16V,10%,X6S,CA
P3V3_AUX                 C1338            1        Q_CAP_C0805-10UF,16V,10%,EMPTYA
P3V3_AUX                 C1347            1        Q_CAP_0402-0.1UF,25V,10%,X7R,CA
P3V3_AUX                 C1438            1        Q_CAP_C0805-22UF,16V,20%,X6S,CA
P3V3_AUX                 C1445            1        Q_CAP_C0805-22UF,16V,20%,X6S,CA
P3V3_AUX                 C1448            1        Q_CAP_C0805-22UF,16V,20%,X6S,CA
P3V3_AUX                 C1455            1        Q_CAP_C0805-22UF,16V,20%,X6S,CA
P3V3_AUX                 C1465            1        Q_CAP_C0805-22UF,16V,20%,X6S,CA
P3V3_AUX                 C1475            1        Q_CAP_C0805-22UF,16V,20%,X6S,CA
P3V3_AUX                 C1481            1        Q_CAP_0402-0.1UF,25V,10%,X7R,CA
P3V3_AUX                 C1482            1        Q_CAP_0402-0.1UF,25V,10%,X7R,CA
P3V3_AUX                 C1485            1        Q_CAP_0402-0.1UF,25V,10%,X7R,CA
P3V3_AUX                 C1486            1        Q_CAP_0402-0.1UF,25V,10%,X7R,CA
P3V3_AUX                 C1588            1        Q_CAP_0402-0.1UF,25V,10%,X7R,CA
P3V3_AUX                 C1589            1        Q_CAP_0402-0.1UF,25V,10%,X7R,CA
P3V3_AUX                 C1590            1        Q_CAP_0402-0.1UF,25V,10%,X7R,CA
P3V3_AUX                 C1591            1        Q_CAP_0402-0.1UF,25V,10%,X7R,CA
P3V3_AUX                 C1592            1        Q_CAP_0402-0.1UF,25V,10%,X7R,CA
P3V3_AUX                 C1593            1        Q_CAP_0402-0.1UF,25V,10%,X7R,CA
P3V3_AUX                 C1594            1        Q_CAP_0402-0.1UF,25V,10%,X7R,CA
P3V3_AUX                 C1595            1        Q_CAP_0402-0.1UF,25V,10%,X7R,CA
P3V3_AUX                 C1599            1        Q_CAP_C0805-22UF,10V,20%,X6S,CA
P3V3_AUX                 C1600            1        Q_CAP_C0805-22UF,10V,20%,X6S,CA
P3V3_AUX                 C1605            1        Q_CAP_C0402-1UF,25V,10%,X6S,CHA
P3V3_AUX                 C1606            1        Q_CAP_0402-0.1UF,25V,10%,X7R,CA
P3V3_AUX                 C1607            1        Q_CAP_0402-0.1UF,25V,10%,X7R,CA
P3V3_AUX                 J1               3        SCONN288_ADR50001P013C01-SCONNA
P3V3_AUX                 J2               3        SCONN288_ADR50001P003C01-SCONNA
P3V3_AUX                 J3               3        SCONN288_ADR50001P013C01-SCONNA
P3V3_AUX                 J4               3        SCONN288_ADR50001P003C01-SCONNA
P3V3_AUX                 J5               3        SCONN288_ADR50001P013C01-SCONNA
P3V3_AUX                 J6               3        SCONN288_ADR50001P003C01-SCONNA
P3V3_AUX                 J7               3        SCONN288_ADR50001P013C01-SCONNA
P3V3_AUX                 J8               3        SCONN288_ADR50001P003C01-SCONNA
P3V3_AUX                 J9               3        SCONN288_ADR50001P013C01-SCONNA
P3V3_AUX                 J10              3        SCONN288_ADR50001P003C01-SCONNA
P3V3_AUX                 J11              3        SCONN288_ADR50001P013C01-SCONNA
P3V3_AUX                 J12              3        SCONN288_ADR50001P003C01-SCONNA
P3V3_AUX                 J13              3        SCONN288_ADR50001P013C01-SCONNA
P3V3_AUX                 J14              3        SCONN288_ADR50001P003C01-SCONNA
P3V3_AUX                 J15              3        SCONN288_ADR50001P013C01-SCONNA
P3V3_AUX                 J16              3        SCONN288_ADR50001P003C01-SCONNA
P3V3_AUX                 J17              3        SCONN288_ADR50001P013C01-SCONNA
P3V3_AUX                 J18              3        SCONN288_ADR50001P003C01-SCONNA
P3V3_AUX                 J19              3        SCONN288_ADR50001P013C01-SCONNA
P3V3_AUX                 J20              3        SCONN288_ADR50001P003C01-SCONNA
P3V3_AUX                 J21              3        SCONN288_ADR50001P013C01-SCONNA
P3V3_AUX                 J22              3        SCONN288_ADR50001P003C01-SCONNA
P3V3_AUX                 J23              3        SCONN288_ADR50001P013C01-SCONNA
P3V3_AUX                 J24              3        SCONN288_ADR50001P003C01-SCONNA
P3V3_AUX                 J25              3        SCONN288_ADR50001P013C01-SCONNA
P3V3_AUX                 J26              3        SCONN288_ADR50001P003C01-SCONNA
P3V3_AUX                 J27              3        SCONN288_ADR50001P013C01-SCONNA
P3V3_AUX                 J28              3        SCONN288_ADR50001P003C01-SCONNA
P3V3_AUX                 J29              3        SCONN288_ADR50001P013C01-SCONNA
P3V3_AUX                 J30              3        SCONN288_ADR50001P003C01-SCONNA
P3V3_AUX                 J31              3        SCONN288_ADR50001P013C01-SCONNA
P3V3_AUX                 J32              3        SCONN288_ADR50001P003C01-SCONNA
P3V3_AUX                 J33              B11      SCONN84_123318136-SCONN84_1-23A
P3V3_AUX                 J34              B11      SCONN84_123318136-SCONN84_1-23A
P3V3_AUX                 J35              B15      SCONN140_G64V3431BHR-SCONN140_B
P3V3_AUX                 J42              52       SCONN60_QSH03001LDAKTR-SCONN60A
P3V3_AUX                 J43              4        CONN10_G2100HT0038071-CONN10_GA
P3V3_AUX                 J44              1        CONN24_52SH90245BRD-CONN24_52SA
P3V3_AUX                 J44              3        CONN24_52SH90245BRD-CONN24_52SA
P3V3_AUX                 J55              A11      SCONN140_G64V3431BHR-SCONN140_A
P3V3_AUX                 J57              A11      SCONN140_G64V3431BHR-SCONN140_A
P3V3_AUX                 J61              B11      SCONN84_123318136-SCONN84_1-23A
P3V3_AUX                 J62              B11      SCONN84_123318136-SCONN84_1-23A
P3V3_AUX                 J87              B11      SCONN84_123318136-SCONN84_1-23A
P3V3_AUX                 J88              B11      SCONN84_123318136-SCONN84_1-23A
P3V3_AUX                 J89              B22      SCONN280_ME1028040102011-SCONNA
P3V3_AUX                 L1               1        Q_INDUCTOR_SMLF-FCM2012KF-601TA
P3V3_AUX                 L13              1        Q_INDUCTOR_SMLF-FCM2012KF-601TA
P3V3_AUX                 L14              1        Q_INDUCTOR_SMLF-FCM2012KF-601TA
P3V3_AUX                 L36              1        Q_INDUCTOR_SMLF-BLM18PG121SN1DA
P3V3_AUX                 OSC1             4        OSC4_SIT1602AI2233E50000000D-5A
P3V3_AUX                 OSC2             4        Q_OSC4P_SMLF-25MHZ,OSC,BF62500A
P3V3_AUX                 PC569            2        Q_CAP_0402-10PF,50V,1%,NPO,TMPA
P3V3_AUX                 PC1866           1        Q_CAPP_THLF-560UF,6.3V,20%,OSCA
P3V3_AUX                 PC1867           1        Q_CAPP_THLF-560UF,6.3V,20%,OSCA
P3V3_AUX                 PC1868           1        Q_CAP_C0805-22UF,10V,20%,X6S,CA
P3V3_AUX                 PC1869           1        Q_CAP_0402-0.1UF,25V,10%,X7R,CA
P3V3_AUX                 PL66             2        Q_INDUCTOR_SMLF-1.5UH/53A,IND,A
P3V3_AUX                 PQ2              5        MOSFET_NCH_1D3S-PSMNR58-30YLH,A
P3V3_AUX                 PR73             1        Q_RES_0402LF-10K,5%,1/16W,CHIPA
P3V3_AUX                 PR109            1        Q_RES_0402LF-1K,1%,1/16W,CHIP,A
P3V3_AUX                 PR117            1        Q_RES_0402LF-1K,1%,1/16W,CHIP,A
P3V3_AUX                 PR130            2        Q_RES_0402LF-1,1%,1/16W,CHIP,CA
P3V3_AUX                 PR131            1        Q_RES_0402LF-1K,1%,1/16W,CHIP,A
P3V3_AUX                 PR160            1        Q_RES_0402LF-1K,1%,1/16W,CHIP,A
P3V3_AUX                 PR169            1        Q_RES_0402LF-1K,1%,1/16W,CHIP,A
P3V3_AUX                 PR172            1        Q_RES_0402LF-1K,1%,1/16W,CHIP,A
P3V3_AUX                 PR176            2        Q_RES_0402LF-1,1%,1/16W,CHIP,CA
P3V3_AUX                 PR177            1        Q_RES_0402LF-1K,1%,1/16W,CHIP,A
P3V3_AUX                 PR186            1        Q_RES_0402LF-10K,1%,1/16W,CHIPA
P3V3_AUX                 PR206            1        Q_RES_0402LF-1K,1%,1/16W,CHIP,A
P3V3_AUX                 PR215            1        Q_RES_0402LF-1K,1%,1/16W,CHIP,A
P3V3_AUX                 PR217            1        Q_RES_0402LF-1K,1%,1/16W,CHIP,A
P3V3_AUX                 PR220            2        Q_RES_0402LF-1,1%,1/16W,CHIP,CA
P3V3_AUX                 PR223            1        Q_RES_0402LF-1K,1%,1/16W,CHIP,A
P3V3_AUX                 PR232            1        Q_RES_0402LF-1K,1%,1/16W,CHIP,A
P3V3_AUX                 PR241            1        Q_RES_0402LF-1K,1%,1/16W,CHIP,A
P3V3_AUX                 PR243            1        Q_RES_0402LF-1K,1%,1/16W,CHIP,A
P3V3_AUX                 PR249            1        Q_RES_0402LF-1K,1%,1/16W,CHIP,A
P3V3_AUX                 PR262            1        Q_RES_0402LF-1K,1%,1/16W,CHIP,A
P3V3_AUX                 PR270            1        Q_RES_0402LF-1K,1%,1/16W,CHIP,A
P3V3_AUX                 PR283            2        Q_RES_0402LF-1,1%,1/16W,CHIP,CA
P3V3_AUX                 PR284            1        Q_RES_0402LF-1K,1%,1/16W,CHIP,A
P3V3_AUX                 PR307            1        Q_RES_0402LF-1K,1%,1/16W,CHIP,A
P3V3_AUX                 PR323            2        Q_RES_0402LF-1,1%,1/16W,CHIP,CA
P3V3_AUX                 PR335            1        Q_RES_0402LF-1K,1%,1/16W,CHIP,A
P3V3_AUX                 PR361            1        Q_RES_0402LF-1K,1%,1/16W,CHIP,A
P3V3_AUX                 PR370            1        Q_RES_0402LF-1K,1%,1/16W,CHIP,A
P3V3_AUX                 PR372            1        Q_RES_0402LF-1K,1%,1/16W,CHIP,A
P3V3_AUX                 PR375            2        Q_RES_0402LF-1,1%,1/16W,CHIP,CA
P3V3_AUX                 PR378            1        Q_RES_0402LF-1K,1%,1/16W,CHIP,A
P3V3_AUX                 PR395            1        Q_RES_0402LF-0,5%,1/16W,CHIP,CA
P3V3_AUX                 PR523            1        Q_RES_0402LF-1K,1%,1/16W,CHIP,A
P3V3_AUX                 PR524            1        Q_RES_0402LF-1K,1%,1/16W,CHIP,A
P3V3_AUX                 PR570            1        Q_RES_0402LF-1K,1%,1/16W,CHIP,A
P3V3_AUX                 PR571            1        Q_RES_0402LF-1K,1%,1/16W,CHIP,A
P3V3_AUX                 PR831            2        Q_RES_0402LF-100K,1%,1/16W,CHIA
P3V3_AUX                 PR836            2        Q_RES_0402LF-1K,1%,1/16W,CHIP,A
P3V3_AUX                 PR1302           1        Q_RES_0402LF-10K,1%,1/16W,CHIPA
P3V3_AUX                 PR1309           1        Q_RES_0402LF-10K,1%,1/16W,EMPTA
P3V3_AUX                 PR1313           1        Q_RES_0402LF-10K,1%,1/16W,CHIPA
P3V3_AUX                 PR1317           1        Q_RES_0402LF-10K,1%,1/16W,CHIPA
P3V3_AUX                 PR1320           1        Q_RES_0402LF-10K,1%,1/16W,CHIPA
P3V3_AUX                 PR1326           1        Q_RES_0402LF-0,5%,1/16W,CHIP,CA
P3V3_AUX                 PR1335           1        Q_RES_0402LF-0,5%,1/16W,EMPTY,A
P3V3_AUX                 PR1338           1        Q_RES_0402LF-0,5%,1/16W,CHIP,CA
P3V3_AUX                 PR1647           1        Q_RES_0402LF-10K,1%,1/16W,EMPTA
P3V3_AUX                 Q33              D        MOSFET_PCH_GDS_ESD_PROTECTED-PA
P3V3_AUX                 R8               1        Q_RES_0402LF-10K,1%,1/16W,CHIPA
P3V3_AUX                 R71              1        Q_RES_0402LF-10K,1%,1/16W,CHIPA
P3V3_AUX                 R85              1        Q_RES_0402LF-10K,5%,1/16W,EMPTA
P3V3_AUX                 R86              1        Q_RES_0402LF-10K,5%,1/16W,EMPTA
P3V3_AUX                 R87              1        Q_RES_0402LF-1K,5%,1/16W,EMPTYA
P3V3_AUX                 R111             1        Q_RES_0402LF-10K,1%,1/16W,CHIPA
P3V3_AUX                 R139             2        Q_RES_0402LF-10K,1%,1/16W,CHIPA
P3V3_AUX                 R270             1        Q_RES_0402LF-10K,1%,1/16W,CHIPA
P3V3_AUX                 R271             1        Q_RES_0402LF-10K,1%,1/16W,CHIPA
P3V3_AUX                 R272             1        Q_RES_0402LF-10K,1%,1/16W,CHIPA
P3V3_AUX                 R273             1        Q_RES_0402LF-10K,1%,1/16W,CHIPA
P3V3_AUX                 R274             1        Q_RES_0402LF-10K,1%,1/16W,CHIPA
P3V3_AUX                 R283             1        Q_RES_0402LF-10K,1%,1/16W,CHIPA
P3V3_AUX                 R284             1        Q_RES_0402LF-10K,1%,1/16W,CHIPA
P3V3_AUX                 R285             1        Q_RES_0402LF-10K,1%,1/16W,CHIPA
P3V3_AUX                 R286             1        Q_RES_0402LF-10K,1%,1/16W,CHIPA
P3V3_AUX                 R287             1        Q_RES_0402LF-10K,1%,1/16W,CHIPA
P3V3_AUX                 R319             1        Q_RES_0402LF-10K,1%,1/16W,CHIPA
P3V3_AUX                 R320             1        Q_RES_0402LF-10K,1%,1/16W,CHIPA
P3V3_AUX                 R321             1        Q_RES_0402LF-10K,1%,1/16W,CHIPA
P3V3_AUX                 R325             1        Q_RES_0402LF-10K,1%,1/16W,CHIPA
P3V3_AUX                 R326             1        Q_RES_0402LF-10K,1%,1/16W,CHIPA
P3V3_AUX                 R327             1        Q_RES_0402LF-10K,1%,1/16W,CHIPA
P3V3_AUX                 R331             1        Q_RES_0402LF-1K,1%,1/16W,EMPTYA
P3V3_AUX                 R333             1        Q_RES_0402LF-1K,1%,1/16W,EMPTYA
P3V3_AUX                 R335             1        Q_RES_0402LF-1K,1%,1/16W,EMPTYA
P3V3_AUX                 R367             1        Q_RES_0402LF-1K,5%,1/16W,CHIP,A
P3V3_AUX                 R369             1        Q_RES_0402LF-1K,5%,1/16W,CHIP,A
P3V3_AUX                 R371             1        Q_RES_0402LF-1K,5%,1/16W,EMPTYA
P3V3_AUX                 R374             1        Q_RES_0402LF-1K,5%,1/16W,EMPTYA
P3V3_AUX                 R378             1        Q_RES_0402LF-1K,5%,1/16W,EMPTYA
P3V3_AUX                 R380             1        Q_RES_0402LF-1K,5%,1/16W,EMPTYA
P3V3_AUX                 R388             1        Q_RES_0402LF-10K,1%,1/16W,CHIPA
P3V3_AUX                 R391             1        Q_RES_0402LF-10K,1%,1/16W,CHIPA
P3V3_AUX                 R392             1        Q_RES_0402LF-10K,5%,1/16W,CHIPA
P3V3_AUX                 R394             2        Q_RES_0402LF-4.7K,5%,1/16W,CHIA
P3V3_AUX                 R395             2        Q_RES_0402LF-10K,1%,1/16W,CHIPA
P3V3_AUX                 R398             2        Q_RES_0402LF-4.7K,5%,1/16W,CHIA
P3V3_AUX                 R399             2        Q_RES_0402LF-10K,1%,1/16W,CHIPA
P3V3_AUX                 R402             2        Q_RES_0402LF-4.7K,5%,1/16W,CHIA
P3V3_AUX                 R453             1        Q_RES_0402LF-10K,1%,1/16W,CHIPA
P3V3_AUX                 R456             1        Q_RES_0402LF-10K,1%,1/16W,CHIPA
P3V3_AUX                 R463             1        Q_RES_0402LF-10K,1%,1/16W,CHIPA
P3V3_AUX                 R478             1        Q_RES_0402LF-4.7K,1%,1/16W,CHIA
P3V3_AUX                 R487             1        Q_RES_0402LF-1K,1%,1/16W,EMPTYA
P3V3_AUX                 R494             1        Q_RES_0402LF-4.75K,1%,1/16W,CHA
P3V3_AUX                 R498             1        Q_RES_0402LF-10K,1%,1/16W,CHIPA
P3V3_AUX                 R502             1        Q_RES_0402LF-20K,5%,1/16W,EMPTA
P3V3_AUX                 R512             1        Q_RES_1206LF-0,5%,1/4W,EMPTY,CA
P3V3_AUX                 R514             1        Q_RES_1206LF-0,5%,1/4W,EMPTY,CA
P3V3_AUX                 R536             1        Q_RES_0402LF-10K,1%,1/16W,EMPTA
P3V3_AUX                 R538             1        Q_RES_0402LF-10K,1%,1/16W,EMPTA
P3V3_AUX                 R540             1        Q_RES_0402LF-10K,1%,1/16W,EMPTA
P3V3_AUX                 R562             1        Q_RES_0402LF-4.75K,1%,1/16W,EMA
P3V3_AUX                 R592             2        Q_RES_0402LF-2.2K ,5%,1/16W,CHA
P3V3_AUX                 R601             2        Q_RES_0402LF-2.2K ,5%,1/16W,CHA
P3V3_AUX                 R606             2        Q_RES_0402LF-2.2K ,5%,1/16W,CHA
P3V3_AUX                 R607             1        Q_RES_0402LF-1K,5%,1/16W,EMPTYA
P3V3_AUX                 R609             1        Q_RES_0402LF-1K,5%,1/16W,EMPTYA
P3V3_AUX                 R611             1        Q_RES_0402LF-1K,5%,1/16W,CHIP,A
P3V3_AUX                 R613             1        Q_RES_0402LF-10K,1%,1/16W,CHIPA
P3V3_AUX                 R615             1        Q_RES_0402LF-1K,5%,1/16W,CHIP,A
P3V3_AUX                 R617             1        Q_RES_0402LF-1K,5%,1/16W,EMPTYA
P3V3_AUX                 R619             1        Q_RES_0402LF-10K,1%,1/16W,CHIPA
P3V3_AUX                 R621             1        Q_RES_0402LF-1K,5%,1/16W,EMPTYA
P3V3_AUX                 R625             1        Q_RES_0402LF-1K,1%,1/16W,EMPTYA
P3V3_AUX                 R627             1        Q_RES_0402LF-1K,1%,1/16W,EMPTYA
P3V3_AUX                 R629             1        Q_RES_0402LF-1K,1%,1/16W,CHIP,A
P3V3_AUX                 R635             2        Q_RES_0402LF-10K,1%,1/16W,CHIPA
P3V3_AUX                 R640             2        Q_RES_0402LF-4.7K,5%,1/16W,EMPA
P3V3_AUX                 R641             1        Q_RES_0402LF-10K,1%,1/16W,EMPTA
P3V3_AUX                 R643             1        Q_RES_0402LF-10K,1%,1/16W,EMPTA
P3V3_AUX                 R645             1        Q_RES_0402LF-10K,1%,1/16W,CHIPA
P3V3_AUX                 R649             2        Q_RES_0402LF-2.2K ,5%,1/16W,CHA
P3V3_AUX                 R650             1        Q_RES_0402LF-1K,1%,1/16W,CHIP,A
P3V3_AUX                 R651             1        Q_RES_0402LF-2.2K ,5%,1/16W,CHA
P3V3_AUX                 R652             1        Q_RES_0402LF-2.2K ,5%,1/16W,CHA
P3V3_AUX                 R653             1        Q_RES_0402LF-2.2K ,5%,1/16W,CHA
P3V3_AUX                 R654             1        Q_RES_0402LF-2.2K ,5%,1/16W,CHA
P3V3_AUX                 R696             1        Q_RES_0402LF-4.75K,1%,1/16W,CHA
P3V3_AUX                 R711             1        Q_RES_0402LF-10K,1%,1/16W,EMPTA
P3V3_AUX                 R713             1        Q_RES_0402LF-10K,1%,1/16W,EMPTA
P3V3_AUX                 R715             1        Q_RES_0402LF-10K,1%,1/16W,EMPTA
P3V3_AUX                 R717             1        Q_RES_0402LF-10K,1%,1/16W,EMPTA
P3V3_AUX                 R719             1        Q_RES_0402LF-10K,1%,1/16W,CHIPA
P3V3_AUX                 R721             1        Q_RES_0402LF-10K,1%,1/16W,CHIPA
P3V3_AUX                 R727             2        Q_RES_0402LF-10K,1%,1/16W,CHIPA
P3V3_AUX                 R728             1        Q_RES_0402LF-10K,1%,1/16W,EMPTA
P3V3_AUX                 R730             1        Q_RES_0402LF-10K,1%,1/16W,CHIPA
P3V3_AUX                 R732             1        Q_RES_0402LF-10K,1%,1/16W,EMPTA
P3V3_AUX                 R735             1        Q_RES_0402LF-10K,1%,1/16W,CHIPA
P3V3_AUX                 R739             1        Q_RES_0402LF-10K,1%,1/16W,CHIPA
P3V3_AUX                 R740             1        Q_RES_0402LF-10K,1%,1/16W,CHIPA
P3V3_AUX                 R766             1        Q_RES_0402LF-1K,1%,1/16W,EMPTYA
P3V3_AUX                 R767             1        Q_RES_0402LF-1K,1%,1/16W,CHIP,A
P3V3_AUX                 R768             1        Q_RES_0402LF-1K,1%,1/16W,CHIP,A
P3V3_AUX                 R770             2        Q_RES_0402LF-10K,1%,1/16W,CHIPA
P3V3_AUX                 R778             1        Q_RES_0402LF-1K,1%,1/16W,CHIP,A
P3V3_AUX                 R781             1        Q_RES_0402LF-10K,1%,1/16W,EMPTA
P3V3_AUX                 R783             1        Q_RES_0402LF-10K,1%,1/16W,CHIPA
P3V3_AUX                 R785             1        Q_RES_0402LF-10K,1%,1/16W,EMPTA
P3V3_AUX                 R791             1        Q_RES_0402LF-2.2K ,5%,1/16W,CHA
P3V3_AUX                 R792             1        Q_RES_0402LF-2.2K ,5%,1/16W,CHA
P3V3_AUX                 R793             1        Q_RES_0402LF-2.2K ,5%,1/16W,CHA
P3V3_AUX                 R794             1        Q_RES_0402LF-2.2K ,5%,1/16W,CHA
P3V3_AUX                 R795             1        Q_RES_0402LF-2.2K ,5%,1/16W,CHA
P3V3_AUX                 R796             1        Q_RES_0402LF-2.2K ,5%,1/16W,CHA
P3V3_AUX                 R797             1        Q_RES_0402LF-2.2K ,5%,1/16W,CHA
P3V3_AUX                 R798             1        Q_RES_0402LF-2.2K ,5%,1/16W,CHA
P3V3_AUX                 R912             1        Q_RES_0402LF-4.75K,1%,1/16W,EMA
P3V3_AUX                 R913             2        Q_RES_0402LF-10K,1%,1/16W,CHIPA
P3V3_AUX                 R914             1        Q_RES_0402LF-2.2K ,5%,1/16W,CHA
P3V3_AUX                 R919             1        Q_RES_0402LF-10K,1%,1/16W,CHIPA
P3V3_AUX                 R927             1        Q_RES_0402LF-10K,1%,1/16W,CHIPA
P3V3_AUX                 R928             1        Q_RES_0402LF-10K,1%,1/16W,CHIPA
P3V3_AUX                 R929             1        Q_RES_0402LF-10K,1%,1/16W,CHIPA
P3V3_AUX                 R940             1        Q_RES_0402LF-1K,1%,1/16W,CHIP,A
P3V3_AUX                 R941             1        Q_RES_0402LF-1K,1%,1/16W,CHIP,A
P3V3_AUX                 R942             1        Q_RES_0402LF-1K,1%,1/16W,CHIP,A
P3V3_AUX                 R943             1        Q_RES_0402LF-1K,1%,1/16W,CHIP,A
P3V3_AUX                 R944             1        Q_RES_0402LF-1K,1%,1/16W,CHIP,A
P3V3_AUX                 R945             1        Q_RES_0402LF-1K,1%,1/16W,CHIP,A
P3V3_AUX                 R946             1        Q_RES_0402LF-1K,1%,1/16W,CHIP,A
P3V3_AUX                 R947             1        Q_RES_0402LF-1K,1%,1/16W,CHIP,A
P3V3_AUX                 R952             1        Q_RES_0402LF-4.7K,1%,1/16W,EMPA
P3V3_AUX                 R965             1        Q_RES_0402LF-1K,1%,1/16W,CHIP,A
P3V3_AUX                 R966             1        Q_RES_0402LF-1K,1%,1/16W,CHIP,A
P3V3_AUX                 R967             1        Q_RES_0402LF-1K,1%,1/16W,CHIP,A
P3V3_AUX                 R968             1        Q_RES_0402LF-1K,1%,1/16W,CHIP,A
P3V3_AUX                 R977             1        Q_RES_0402LF-412,1%,1/16W,CHIPA
P3V3_AUX                 R978             1        Q_RES_0402LF-412,1%,1/16W,CHIPA
P3V3_AUX                 R979             1        Q_RES_0402LF-412,1%,1/16W,CHIPA
P3V3_AUX                 R980             1        Q_RES_0402LF-412,1%,1/16W,CHIPA
P3V3_AUX                 R1004            1        Q_RES_0402LF-1K,1%,1/16W,CHIP,A
P3V3_AUX                 R1065            1        Q_RES_0402LF-2.2K ,5%,1/16W,EMA
P3V3_AUX                 R1066            1        Q_RES_0402LF-2.2K ,5%,1/16W,EMA
P3V3_AUX                 R1067            1        Q_RES_0402LF-2.2K ,5%,1/16W,EMA
P3V3_AUX                 R1068            1        Q_RES_0402LF-2.2K ,5%,1/16W,EMA
P3V3_AUX                 R1069            1        Q_RES_0402LF-2.2K ,5%,1/16W,EMA
P3V3_AUX                 R1070            1        Q_RES_0402LF-2.2K ,5%,1/16W,EMA
P3V3_AUX                 R1071            1        Q_RES_0402LF-2.2K ,5%,1/16W,EMA
P3V3_AUX                 R1072            1        Q_RES_0402LF-2.2K ,5%,1/16W,EMA
P3V3_AUX                 R1089            1        Q_RES_0402LF-2.2K ,5%,1/16W,CHA
P3V3_AUX                 R1090            1        Q_RES_0402LF-2.2K ,5%,1/16W,CHA
P3V3_AUX                 R1091            1        Q_RES_0402LF-2.2K ,5%,1/16W,CHA
P3V3_AUX                 R1092            1        Q_RES_0402LF-2.2K ,5%,1/16W,CHA
P3V3_AUX                 R1099            1        Q_RES_0402LF-10K,1%,1/16W,CHIPA
P3V3_AUX                 R1104            1        Q_RES_0402LF-10K,1%,1/16W,CHIPA
P3V3_AUX                 R1106            1        Q_RES_0402LF-10K,1%,1/16W,CHIPA
P3V3_AUX                 R1123            1        Q_RES_0402LF-1K,5%,1/16W,EMPTYA
P3V3_AUX                 R1125            1        Q_RES_0402LF-1K,5%,1/16W,EMPTYA
P3V3_AUX                 R1127            1        Q_RES_0402LF-1K,5%,1/16W,EMPTYA
P3V3_AUX                 R1129            1        Q_RES_0402LF-1K,5%,1/16W,CHIP,A
P3V3_AUX                 R1133            1        Q_RES_0402LF-10K,1%,1/16W,CHIPA
P3V3_AUX                 R1138            1        Q_RES_0402LF-10K,1%,1/16W,CHIPA
P3V3_AUX                 R1143            1        Q_RES_0402LF-10K,1%,1/16W,CHIPA
P3V3_AUX                 R1146            1        Q_RES_0402LF-1K,1%,1/16W,CHIP,A
P3V3_AUX                 R1149            1        Q_RES_0402LF-10K,1%,1/16W,CHIPA
P3V3_AUX                 R1150            1        Q_RES_0402LF-10K,1%,1/16W,CHIPA
P3V3_AUX                 R1194            1        Q_RES_0402LF-4.75K,1%,1/16W,EMA
P3V3_AUX                 R1195            1        Q_RES_0402LF-750,1%,1/16W,CHIPA
P3V3_AUX                 R1198            1        Q_RES_0402LF-10K,1%,1/16W,CHIPA
P3V3_AUX                 R1204            1        Q_RES_0402LF-10K,1%,1/16W,EMPTA
P3V3_AUX                 R1216            1        Q_RES_0402LF-10K,1%,1/16W,CHIPA
P3V3_AUX                 R1217            1        Q_RES_0402LF-10K,1%,1/16W,CHIPA
P3V3_AUX                 R1220            1        Q_RES_0402LF-1K,1%,1/16W,EMPTYA
P3V3_AUX                 R1222            1        Q_RES_0402LF-5.11K,1%,1/16W,CHA
P3V3_AUX                 R1223            2        Q_RES_0402LF-10K,1%,1/16W,EMPTA
P3V3_AUX                 R1224            2        Q_RES_0402LF-10K,1%,1/16W,CHIPA
P3V3_AUX                 R1225            2        Q_RES_0402LF-10K,1%,1/16W,CHIPA
P3V3_AUX                 R1256            1        Q_RES_0402LF-10K,1%,1/16W,CHIPA
P3V3_AUX                 R1257            1        Q_RES_0402LF-10K,1%,1/16W,CHIPA
P3V3_AUX                 R1258            1        Q_RES_0402LF-10K,1%,1/16W,CHIPA
P3V3_AUX                 R1259            1        Q_RES_0402LF-10K,1%,1/16W,CHIPA
P3V3_AUX                 R1305            1        Q_RES_0402LF-10K,1%,1/16W,EMPTA
P3V3_AUX                 R1314            1        Q_RES_0402LF-2.2K ,5%,1/16W,CHA
P3V3_AUX                 R1319            2        Q_RES_0402LF-2K,1%,1/16W,CHIP,A
P3V3_AUX                 R1320            1        Q_RES_0402LF-1K,1%,1/16W,CHIP,A
P3V3_AUX                 R1321            2        Q_RES_0402LF-2K,1%,1/16W,CHIP,A
P3V3_AUX                 R1325            1        Q_RES_0402LF-1K,1%,1/16W,CHIP,A
P3V3_AUX                 R1331            1        Q_RES_0402LF-4.7K,5%,1/16W,CHIA
P3V3_AUX                 R1332            1        Q_RES_0402LF-4.7K,5%,1/16W,CHIA
P3V3_AUX                 R1336            2        Q_RES_0402LF-2.2K ,5%,1/16W,CHA
P3V3_AUX                 R1339            1        Q_RES_0402LF-10K,1%,1/16W,CHIPA
P3V3_AUX                 R1370            1        Q_RES_0402LF-100,1%,1/16W,EMPTA
P3V3_AUX                 R1376            1        Q_RES_0402LF-1K,1%,1/16W,CHIP,A
P3V3_AUX                 R1377            1        Q_RES_0402LF-1K,1%,1/16W,CHIP,A
P3V3_AUX                 R1380            1        Q_RES_0402LF-1K,1%,1/16W,CHIP,A
P3V3_AUX                 R1381            1        Q_RES_0402LF-1K,1%,1/16W,CHIP,A
P3V3_AUX                 R1382            1        Q_RES_0402LF-1K,1%,1/16W,CHIP,A
P3V3_AUX                 R1383            1        Q_RES_0402LF-1K,1%,1/16W,CHIP,A
P3V3_AUX                 R1384            2        Q_RES_0402LF-2K,1%,1/16W,CHIP,A
P3V3_AUX                 R1385            2        Q_RES_0402LF-2K,1%,1/16W,CHIP,A
P3V3_AUX                 R1386            2        Q_RES_0402LF-2K,1%,1/16W,CHIP,A
P3V3_AUX                 R1387            2        Q_RES_0402LF-2K,1%,1/16W,CHIP,A
P3V3_AUX                 R1396            2        Q_RES_0402LF-10K,1%,1/16W,CHIPA
P3V3_AUX                 R1399            2        Q_RES_0402LF-10K,1%,1/16W,CHIPA
P3V3_AUX                 R1401            2        Q_RES_0402LF-10K,1%,1/16W,CHIPA
P3V3_AUX                 R1434            2        Q_RES_0402LF-10K,1%,1/16W,CHIPA
P3V3_AUX                 R1435            2        Q_RES_0402LF-10K,1%,1/16W,CHIPA
P3V3_AUX                 R1436            2        Q_RES_0402LF-10K,1%,1/16W,CHIPA
P3V3_AUX                 R1437            2        Q_RES_0402LF-10K,1%,1/16W,CHIPA
P3V3_AUX                 R1438            2        Q_RES_0402LF-10K,1%,1/16W,CHIPA
P3V3_AUX                 R1439            2        Q_RES_0402LF-10K,1%,1/16W,CHIPA
P3V3_AUX                 R1440            2        Q_RES_0402LF-10K,1%,1/16W,EMPTA
P3V3_AUX                 R1449            1        Q_RES_0402LF-10K,1%,1/16W,CHIPA
P3V3_AUX                 R1450            1        Q_RES_0402LF-10K,1%,1/16W,CHIPA
P3V3_AUX                 R1451            2        Q_RES_0402LF-2K,1%,1/16W,CHIP,A
P3V3_AUX                 R1452            2        Q_RES_0402LF-2K,1%,1/16W,CHIP,A
P3V3_AUX                 R1453            2        Q_RES_0402LF-2K,1%,1/16W,CHIP,A
P3V3_AUX                 R1454            2        Q_RES_0402LF-2K,1%,1/16W,CHIP,A
P3V3_AUX                 R1458            1        Q_RES_0402LF-10K,1%,1/16W,CHIPA
P3V3_AUX                 R1459            1        Q_RES_0402LF-10K,1%,1/16W,CHIPA
P3V3_AUX                 R1460            2        Q_RES_0402LF-2.2K ,5%,1/16W,CHA
P3V3_AUX                 R1465            1        Q_RES_0402LF-10K,1%,1/16W,EMPTA
P3V3_AUX                 R1467            1        Q_RES_0402LF-4.7K,1%,1/16W,CHIA
P3V3_AUX                 R1471            1        Q_RES_0402LF-4.75K,1%,1/16W,CHA
P3V3_AUX                 R1473            2        Q_RES_0402LF-1K,1%,1/16W,CHIP,A
P3V3_AUX                 R1474            2        Q_RES_0402LF-1K,1%,1/16W,CHIP,A
P3V3_AUX                 R1475            1        Q_RES_0402LF-1K,1%,1/16W,EMPTYA
P3V3_AUX                 R1477            1        Q_RES_0402LF-1K,1%,1/16W,EMPTYA
P3V3_AUX                 R1483            1        Q_RES_0402LF-10K,1%,1/16W,EMPTA
P3V3_AUX                 R1488            2        Q_RES_0402LF-10K,1%,1/16W,CHIPA
P3V3_AUX                 R1492            2        Q_RES_0402LF-10K,1%,1/16W,EMPTA
P3V3_AUX                 R1493            2        Q_RES_0402LF-1K,1%,1/16W,EMPTYA
P3V3_AUX                 R1496            1        Q_RES_0402LF-10K,1%,1/16W,CHIPA
P3V3_AUX                 R1498            1        Q_RES_0402LF-1K,1%,1/16W,EMPTYA
P3V3_AUX                 R1522            1        Q_RES_0402LF-10K,1%,1/16W,CHIPA
P3V3_AUX                 R1528            2        Q_RES_0402LF-4.7K,5%,1/16W,EMPA
P3V3_AUX                 R1529            2        Q_RES_0402LF-4.7K,5%,1/16W,EMPA
P3V3_AUX                 R1532            2        Q_RES_0402LF-4.7K,5%,1/16W,EMPA
P3V3_AUX                 R1533            2        Q_RES_0402LF-4.7K,5%,1/16W,EMPA
P3V3_AUX                 R1534            2        Q_RES_0402LF-4.7K,5%,1/16W,EMPA
P3V3_AUX                 R1540            1        Q_RES_0402LF-100K,1%,1/16W,EMPB
P3V3_AUX                 R1545            2        Q_RES_0402LF-2K,1%,1/16W,CHIP,A
P3V3_AUX                 R1546            2        Q_RES_0402LF-2K,1%,1/16W,CHIP,A
P3V3_AUX                 R1549            1        Q_RES_0402LF-4.7K,1%,1/16W,CHIA
P3V3_AUX                 R1550            1        Q_RES_0402LF-4.7K,1%,1/16W,CHIA
P3V3_AUX                 R1551            1        Q_RES_0402LF-4.7K,1%,1/16W,CHIA
P3V3_AUX                 R1554            1        Q_RES_0402LF-10K,1%,1/16W,CHIPA
P3V3_AUX                 R1558            2        Q_RES_0402LF-10K,1%,1/16W,CHIPA
P3V3_AUX                 R1575            1        Q_RES_0402LF-10K,5%,1/16W,CHIPA
P3V3_AUX                 R1576            1        Q_RES_0402LF-10K,5%,1/16W,CHIPA
P3V3_AUX                 R1579            1        Q_RES_0402LF-10K,5%,1/16W,CHIPA
P3V3_AUX                 R1580            1        Q_RES_0402LF-10K,5%,1/16W,CHIPA
P3V3_AUX                 R1581            2        Q_RES_0402LF-2K,1%,1/16W,CHIP,A
P3V3_AUX                 R1582            2        Q_RES_0402LF-2K,1%,1/16W,CHIP,A
P3V3_AUX                 R1583            2        Q_RES_0402LF-10K,1%,1/16W,CHIPA
P3V3_AUX                 R1584            1        Q_RES_0402LF-10K,5%,1/16W,EMPTA
P3V3_AUX                 R1586            1        Q_RES_0402LF-10K,5%,1/16W,EMPTA
P3V3_AUX                 R1588            1        Q_RES_0402LF-10K,5%,1/16W,EMPTA
P3V3_AUX                 R1593            1        Q_RES_0402LF-4.7K,1%,1/16W,EMPA
P3V3_AUX                 R1601            2        Q_RES_0402LF-10K,1%,1/16W,CHIPA
P3V3_AUX                 R1608            1        Q_RES_0402LF-4.7K,1%,1/16W,EMPA
P3V3_AUX                 R1609            1        Q_RES_0402LF-10K,1%,1/16W,CHIPA
P3V3_AUX                 R1610            1        Q_RES_0402LF-10K,1%,1/16W,CHIPA
P3V3_AUX                 R1613            2        Q_RES_0402LF-4.7K,5%,1/16W,CHIA
P3V3_AUX                 R1615            2        Q_RES_0402LF-4.7K,5%,1/16W,CHIA
P3V3_AUX                 R1617            2        Q_RES_0402LF-4.7K,5%,1/16W,CHIA
P3V3_AUX                 R1645            1        Q_RES_0402LF-4.7K,5%,1/16W,EMPA
P3V3_AUX                 R1658            2        Q_RES_0402LF-10K,1%,1/16W,CHIPA
P3V3_AUX                 R1659            2        Q_RES_0402LF-10K,1%,1/16W,CHIPA
P3V3_AUX                 R1660            2        Q_RES_0402LF-10K,1%,1/16W,EMPTA
P3V3_AUX                 R1667            1        Q_RES_0402LF-10K,1%,1/16W,CHIPA
P3V3_AUX                 R1675            2        Q_RES_0402LF-2.49K,1%,1/16W,CHA
P3V3_AUX                 R1681            1        Q_RES_0402LF-10K,1%,1/16W,CHIPA
P3V3_AUX                 R1690            1        Q_RES_0402LF-10K,1%,1/16W,CHIPA
P3V3_AUX                 R1691            1        Q_RES_0402LF-10K,1%,1/16W,EMPTA
P3V3_AUX                 R1694            1        Q_RES_0402LF-10K,1%,1/16W,CHIPA
P3V3_AUX                 R1712            2        Q_RES_0402LF-1K,1%,1/16W,CHIP,A
P3V3_AUX                 R1713            2        Q_RES_0402LF-1K,1%,1/16W,CHIP,A
P3V3_AUX                 R1731            2        Q_RES_0402LF-2K,1%,1/16W,CHIP,A
P3V3_AUX                 R1732            2        Q_RES_0402LF-2K,1%,1/16W,CHIP,A
P3V3_AUX                 R1741            2        Q_RES_0402LF-1K,1%,1/16W,CHIP,A
P3V3_AUX                 R1765            2        Q_RES_0805LF-0,5%,1/8W,EMPTY,CA
P3V3_AUX                 R1784            1        Q_RES_0402LF-4.7K,1%,1/16W,EMPA
P3V3_AUX                 R1786            1        Q_RES_0402LF-0,1%,1/16W,CHIP,TA
P3V3_AUX                 R1794            1        Q_RES_0402LF-4.7K,1%,1/16W,EMPA
P3V3_AUX                 R1809            1        Q_RES_0402LF-20K,1%,1/16W,CHIPA
P3V3_AUX                 R1813            1        Q_RES_0402LF-10K,1%,1/16W,EMPTA
P3V3_AUX                 R1820            1        Q_RES_0402LF-10K,1%,1/16W,CHIPA
P3V3_AUX                 R1822            1        Q_RES_0402LF-10K,1%,1/16W,CHIPA
P3V3_AUX                 R1823            1        Q_RES_0402LF-1K,1%,1/16W,CHIP,A
P3V3_AUX                 R1828            2        Q_RES_0402LF-10K,1%,1/16W,CHIPA
P3V3_AUX                 R1841            1        Q_RES_0402LF-10K,1%,1/16W,EMPTA
P3V3_AUX                 R1854            1        Q_RES_0402LF-10K,1%,1/16W,CHIPA
P3V3_AUX                 R1857            1        Q_RES_0402LF-10K,1%,1/16W,CHIPA
P3V3_AUX                 R1905            1        Q_RES_0402LF-10K,1%,1/16W,CHIPA
P3V3_AUX                 R1906            1        Q_RES_0402LF-10K,1%,1/16W,CHIPA
P3V3_AUX                 R1907            1        Q_RES_0402LF-10K,1%,1/16W,CHIPA
P3V3_AUX                 R1908            1        Q_RES_0402LF-10K,1%,1/16W,CHIPA
P3V3_AUX                 R1955            1        Q_RES_0402LF-10K,1%,1/16W,CHIPA
P3V3_AUX                 R1958            1        Q_RES_0402LF-10K,1%,1/16W,CHIPA
P3V3_AUX                 R1963            1        Q_RES_0402LF-10K,1%,1/16W,CHIPA
P3V3_AUX                 R1964            1        Q_RES_0402LF-10K,5%,1/16W,EMPTA
P3V3_AUX                 R1967            2        Q_RES_0402LF-4.7K,5%,1/16W,CHIA
P3V3_AUX                 R1968            2        Q_RES_0402LF-4.7K,5%,1/16W,CHIA
P3V3_AUX                 R1973            1        Q_RES_0402LF-10K,1%,1/16W,CHIPA
P3V3_AUX                 R1974            1        Q_RES_0402LF-10K,5%,1/16W,EMPTA
P3V3_AUX                 R1977            2        Q_RES_0402LF-4.7K,5%,1/16W,CHIA
P3V3_AUX                 R1978            2        Q_RES_0402LF-4.7K,5%,1/16W,CHIA
P3V3_AUX                 R1979            2        Q_RES_0402LF-10K,1%,1/16W,CHIPA
P3V3_AUX                 R1983            1        Q_RES_0402LF-10K,1%,1/16W,CHIPA
P3V3_AUX                 R1984            1        Q_RES_0402LF-10K,5%,1/16W,EMPTA
P3V3_AUX                 R1987            2        Q_RES_0402LF-4.7K,5%,1/16W,CHIA
P3V3_AUX                 R1988            2        Q_RES_0402LF-4.7K,5%,1/16W,CHIA
P3V3_AUX                 R1989            2        Q_RES_0402LF-10K,1%,1/16W,CHIPA
P3V3_AUX                 R1993            1        Q_RES_0402LF-10K,1%,1/16W,CHIPA
P3V3_AUX                 R2000            2        Q_RES_0402LF-4.7K,5%,1/16W,CHIA
P3V3_AUX                 R2001            2        Q_RES_0402LF-10K,1%,1/16W,CHIPA
P3V3_AUX                 R2014            1        Q_RES_0402LF-100K,1%,1/16W,EMPA
P3V3_AUX                 R2015            1        Q_RES_0402LF-100K,1%,1/16W,EMPA
P3V3_AUX                 R2017            1        Q_RES_0402LF-10K,1%,1/16W,CHIPA
P3V3_AUX                 R2018            1        Q_RES_0402LF-100K,1%,1/16W,EMPA
P3V3_AUX                 R2019            1        Q_RES_0402LF-100K,1%,1/16W,EMPA
P3V3_AUX                 R2022            1        Q_RES_0402LF-10K,1%,1/16W,CHIPA
P3V3_AUX                 R2023            1        Q_RES_0402LF-10K,1%,1/16W,CHIPA
P3V3_AUX                 R2036            1        Q_RES_0402LF-100K,1%,1/16W,EMPA
P3V3_AUX                 R2037            1        Q_RES_0402LF-100K,1%,1/16W,EMPA
P3V3_AUX                 R2040            1        Q_RES_0402LF-10K,1%,1/16W,CHIPA
P3V3_AUX                 R2041            1        Q_RES_0402LF-10K,1%,1/16W,CHIPA
P3V3_AUX                 R2042            1        Q_RES_0402LF-100K,1%,1/16W,EMPA
P3V3_AUX                 R2043            1        Q_RES_0402LF-100K,1%,1/16W,EMPA
P3V3_AUX                 R2046            1        Q_RES_0402LF-10K,1%,1/16W,CHIPA
P3V3_AUX                 R2047            1        Q_RES_0402LF-10K,1%,1/16W,CHIPA
P3V3_AUX                 R2051            1        Q_RES_0402LF-2.2K ,5%,1/16W,CHA
P3V3_AUX                 R2052            1        Q_RES_0402LF-2.2K ,5%,1/16W,CHA
P3V3_AUX                 R2053            1        Q_RES_0402LF-2.2K ,5%,1/16W,CHA
P3V3_AUX                 R2054            1        Q_RES_0402LF-2.2K ,5%,1/16W,CHA
P3V3_AUX                 R2055            1        Q_RES_0402LF-2.2K ,5%,1/16W,CHA
P3V3_AUX                 R2056            1        Q_RES_0402LF-2.2K ,5%,1/16W,CHA
P3V3_AUX                 R2057            1        Q_RES_0402LF-2.2K ,5%,1/16W,CHA
P3V3_AUX                 R2058            1        Q_RES_0402LF-2.2K ,5%,1/16W,CHA
P3V3_AUX                 R2079            2        Q_RES_0402LF-4.7K,5%,1/16W,EMPA
P3V3_AUX                 R2080            2        Q_RES_0402LF-4.7K,5%,1/16W,EMPA
P3V3_AUX                 R2081            2        Q_RES_0402LF-4.7K,5%,1/16W,EMPA
P3V3_AUX                 R2089            1        Q_RES_0402LF-1K,5%,1/16W,EMPTYA
P3V3_AUX                 R2091            1        Q_RES_0402LF-1K,5%,1/16W,EMPTYA
P3V3_AUX                 R2093            1        Q_RES_0402LF-1K,5%,1/16W,EMPTYA
P3V3_AUX                 R2095            1        Q_RES_0402LF-1K,5%,1/16W,EMPTYA
P3V3_AUX                 R2097            1        Q_RES_0402LF-1K,5%,1/16W,EMPTYA
P3V3_AUX                 R2099            1        Q_RES_0402LF-1K,5%,1/16W,EMPTYA
P3V3_AUX                 R2121            1        Q_RES_0402LF-4.7K,5%,1/16W,CHIA
P3V3_AUX                 R2122            1        Q_RES_0402LF-4.7K,5%,1/16W,CHIA
P3V3_AUX                 R2123            1        Q_RES_0402LF-4.7K,5%,1/16W,CHIA
P3V3_AUX                 R2124            1        Q_RES_0402LF-4.7K,5%,1/16W,CHIA
P3V3_AUX                 R2125            1        Q_RES_0402LF-4.7K,5%,1/16W,CHIA
P3V3_AUX                 R2126            1        Q_RES_0402LF-4.7K,5%,1/16W,CHIA
P3V3_AUX                 R2127            1        Q_RES_0402LF-4.7K,5%,1/16W,CHIA
P3V3_AUX                 R2128            1        Q_RES_0402LF-4.7K,5%,1/16W,CHIA
P3V3_AUX                 R2133            1        Q_RES_0402LF-1K,1%,1/16W,CHIP,A
P3V3_AUX                 R2138            1        Q_RES_0402LF-10K,1%,1/16W,CHIPA
P3V3_AUX                 R2140            1        Q_RES_0402LF-10K,5%,1/16W,CHIPA
P3V3_AUX                 R2157            1        Q_RES_0402LF-4.7K,1%,1/16W,CHIA
P3V3_AUX                 R2158            1        Q_RES_0402LF-10K,5%,1/16W,CHIPA
P3V3_AUX                 R2167            1        Q_RES_0402LF-10K,1%,1/16W,CHIPA
P3V3_AUX                 R2168            1        Q_RES_0402LF-10K,5%,1/16W,EMPTA
P3V3_AUX                 R2170            1        Q_RES_0402LF-10K,5%,1/16W,CHIPA
P3V3_AUX                 R2173            1        Q_RES_0402LF-10K,5%,1/16W,CHIPA
P3V3_AUX                 R2174            1        Q_RES_0402LF-10K,5%,1/16W,CHIPA
P3V3_AUX                 R2175            2        Q_RES_0402LF-4.7K,5%,1/16W,EMPA
P3V3_AUX                 R2176            2        Q_RES_0402LF-4.7K,5%,1/16W,EMPA
P3V3_AUX                 R2177            2        Q_RES_0402LF-4.7K,5%,1/16W,EMPA
P3V3_AUX                 R2180            1        Q_RES_0402LF-10K,1%,1/16W,CHIPA
P3V3_AUX                 R2191            1        Q_RES_0402LF-10K,1%,1/16W,EMPTA
P3V3_AUX                 R2193            1        Q_RES_0402LF-10K,1%,1/16W,CHIPA
P3V3_AUX                 R2195            1        Q_RES_0402LF-10K,1%,1/16W,EMPTA
P3V3_AUX                 R2197            1        Q_RES_0402LF-10K,1%,1/16W,CHIPA
P3V3_AUX                 R2198            1        Q_RES_0402LF-2.2K ,5%,1/16W,CHA
P3V3_AUX                 R2199            1        Q_RES_0402LF-2.2K ,5%,1/16W,CHA
P3V3_AUX                 R2200            1        Q_RES_0402LF-2.2K ,5%,1/16W,CHA
P3V3_AUX                 R2201            1        Q_RES_0402LF-2.2K ,5%,1/16W,CHA
P3V3_AUX                 R2202            1        Q_RES_0402LF-2.2K ,5%,1/16W,CHA
P3V3_AUX                 R2203            1        Q_RES_0402LF-2.2K ,5%,1/16W,CHA
P3V3_AUX                 R2204            1        Q_RES_0402LF-2.2K ,5%,1/16W,CHA
P3V3_AUX                 R2205            1        Q_RES_0402LF-2.2K ,5%,1/16W,CHA
P3V3_AUX                 R2206            1        Q_RES_0402LF-2.2K ,5%,1/16W,CHA
P3V3_AUX                 R2207            1        Q_RES_0402LF-2.2K ,5%,1/16W,CHA
P3V3_AUX                 R2212            2        Q_RES_0402LF-2.2K ,5%,1/16W,CHA
P3V3_AUX                 R2213            2        Q_RES_0402LF-2.2K ,5%,1/16W,CHA
P3V3_AUX                 R2330            1        Q_RES_0402LF-10K,1%,1/16W,EMPTA
P3V3_AUX                 R2338            1        Q_RES_0402LF-10K,1%,1/16W,EMPTA
P3V3_AUX                 R2367            1        Q_RES_0402LF-10K,1%,1/16W,EMPTA
P3V3_AUX                 R2384            1        Q_RES_0402LF-10K,1%,1/16W,EMPTA
P3V3_AUX                 U1               BA21     SOCKET4677_AZIFS054P001C01-SOCA
P3V3_AUX                 U1               BC21     SOCKET4677_AZIFS054P001C01-SOCA
P3V3_AUX                 U2               BA21     SOCKET4677_AZIFS054P001C01-SOCA
P3V3_AUX                 U2               BC21     SOCKET4677_AZIFS054P001C01-SOCA
P3V3_AUX                 U4               AD15     EMMITSBURG_REV0P9-GFNOCPU04302A
P3V3_AUX                 U4               AD17     EMMITSBURG_REV0P9-GFNOCPU04302A
P3V3_AUX                 U4               AF17     EMMITSBURG_REV0P9-GFNOCPU04302A
P3V3_AUX                 U4               AG17     EMMITSBURG_REV0P9-GFNOCPU04302A
P3V3_AUX                 U4               AJ17     EMMITSBURG_REV0P9-GFNOCPU04302A
P3V3_AUX                 U4               AK15     EMMITSBURG_REV0P9-GFNOCPU04302A
P3V3_AUX                 U4               AL17     EMMITSBURG_REV0P9-GFNOCPU04302A
P3V3_AUX                 U4               AN20     EMMITSBURG_REV0P9-GFNOCPU04302A
P3V3_AUX                 U4               P21      EMMITSBURG_REV0P9-GFNOCPU04302A
P3V3_AUX                 U4               T15      EMMITSBURG_REV0P9-GFNOCPU04302A
P3V3_AUX                 U4               V15      EMMITSBURG_REV0P9-GFNOCPU04302A
P3V3_AUX                 U10              16       PCA9546APWR-PCA9546APWR,SMLF,IA
P3V3_AUX                 U14              16       IDTQS3VH257QG_SMLF-IDTQS3VH257A
P3V3_AUX                 U15              16       IDTQS3VH257QG_SMLF-IDTQS3VH257A
P3V3_AUX                 U16              5        NC7SZ66M5X_SMLF-NC7SZ66M5X,NC7A
P3V3_AUX                 U17              14       74CBTLV3126PW-74CBTLV3126PW,SMA
P3V3_AUX                 U18              14       74CBTLV3126PW-74CBTLV3126PW,SMA
P3V3_AUX                 U21              5        NC7SB3157_SMLF-NC7SB3157P6X,NCA
P3V3_AUX                 U22              5        NC7SB3157_SMLF-NC7SB3157P6X,NCA
P3V3_AUX                 U23              5        74LVC1G02GW_SMLF-74LVC1G02GW,IA
P3V3_AUX                 U24              24       PCA9548APW-PCA9548APW,SMLF,IC,A
P3V3_AUX                 U28              8        PCA9617ADP-PCA9617ADP,SMLF,IC,A
P3V3_AUX                 U29              8        PCA9617ADP-PCA9617ADP,SMLF,IC,A
P3V3_AUX                 U30              8        PCA9617ADP-PCA9617ADP,SMLF,IC,A
P3V3_AUX                 U31              8        PCA9617ADP-PCA9617ADP,SMLF,IC,A
P3V3_AUX                 U36              16       PCA9546APWR-PCA9546APWR,SMLF,IA
P3V3_AUX                 U40              3        TPS259520DSGR-TPS259520DSGR,SMA
P3V3_AUX                 U40              4        TPS259520DSGR-TPS259520DSGR,SMA
P3V3_AUX                 U50              5        SN74LVC1G08DBVR_SMLF-SN74LVC1GA
P3V3_AUX                 U51              24       PCA9555PW_SMLF-PCA9555PW,IC,TMA
P3V3_AUX                 U52              3        APX80929SAG7-APX809-29SAG-7,SMA
P3V3_AUX                 U53              5        SN74LVC1G08DBVR_SMLF-SN74LVC1GA
P3V3_AUX                 U56              3        TPS259520DSGR-TPS259520DSGR,SMA
P3V3_AUX                 U56              4        TPS259520DSGR-TPS259520DSGR,SMA
P3V3_AUX                 U58              5        SN74LVC2G07DCKR_SMLF-SN74LVC2GA
P3V3_AUX                 U59              5        SN74LVC2G07DCKR_SMLF-SN74LVC2GA
P3V3_AUX                 U62              2        BAS70057F-BAS70-05-7-F,SMLF,ICA
P3V3_AUX                 U63              8        TMP75AIDR-TMP75AIDR,SMLF,IC,ALA
P3V3_AUX                 U64              8        M24128BWDW6TP-M24128-BWDW6TP,SA
P3V3_AUX                 U65              8        TMP75AIDR-TMP75AIDR,SMLF,IC,ALA
P3V3_AUX                 U66              5        74HC1G126GW-74HC1G126GW,SMLF,IA
P3V3_AUX                 U67              14       74CBTLV3126PW-74CBTLV3126PW,SMA
P3V3_AUX                 U68              14       74CBTLV3126PW-74CBTLV3126PW,SMA
P3V3_AUX                 U75              5        SN74LVC1G17DCKR-SN74LVC1G17DCKA
P3V3_AUX                 U77              14       74CBTLV3126PW-74CBTLV3126PW,SMB
P3V3_AUX                 U79              5        SLG55221120010VTR-SLG55221-120A
P3V3_AUX                 U82              5        74LVC1G126GW_SMLF-74LVC1G126GWA
P3V3_AUX                 U83              14       GTL2014PW-GTL2014PW,SMLF,IC,ALA
P3V3_AUX                 U84              14       GTL2014PW-GTL2014PW,SMLF,IC,ALA
P3V3_AUX                 U85              5        NC7SB3157_SMLF-NC7SB3157P6X,NCA
P3V3_AUX                 U86              14       74CBTLV3126PW-74CBTLV3126PW,SMA
P3V3_AUX                 U90              6        PI6CV304LE-PI6CV304LE,SMLF,IC,A
P3V3_AUX                 U94              6        ADM1086AKSZREEL7-ADM1086AKSZ-RA
P3V3_AUX                 U95              5        SN74LVC1G07DCKR-SN74LVC1G07DCKA
P3V3_AUX                 U96              10       TS3A24157RSER-TS3A24157RSER,SMA
P3V3_AUX                 U97              10       TS3A24157RSER-TS3A24157RSER,SMA
P3V3_AUX                 U98              7        PCA9306DCTR-PCA9306DCTR,SMLF,IA
P3V3_AUX                 U104             5        74LVC1G07GV-74LVC1G07GV,SMLF,IA
P3V3_AUX                 U105             8        ADS1015IDGSR-ADS1015IDGSR,SMLFA
P3V3_AUX                 U117             6        TPS3897PDRYR-TPS3897PDRYR,SMLFA
P3V3_AUX                 U121             8        MAX11607EUAT-MAX11607EUA+T,SMLA
P3V3_AUX                 U122             C3       10M04SAU324I7G-10M04SAU324I7G,A
P3V3_AUX                 U122             D11      10M04SAU324I7G-10M04SAU324I7G,A
P3V3_AUX                 U122             E7       10M04SAU324I7G-10M04SAU324I7G,A
P3V3_AUX                 U122             E8       10M04SAU324I7G-10M04SAU324I7G,A
P3V3_AUX                 U122             E9       10M04SAU324I7G-10M04SAU324I7G,A
P3V3_AUX                 U122             E11      10M04SAU324I7G-10M04SAU324I7G,A
P3V3_AUX                 U122             E12      10M04SAU324I7G-10M04SAU324I7G,A
P3V3_AUX                 U122             F9       10M04SAU324I7G-10M04SAU324I7G,A
P3V3_AUX                 U122             F13      10M04SAU324I7G-10M04SAU324I7G,A
P3V3_AUX                 U122             G5       10M04SAU324I7G-10M04SAU324I7G,A
P3V3_AUX                 U122             G13      10M04SAU324I7G-10M04SAU324I7G,A
P3V3_AUX                 U122             G14      10M04SAU324I7G-10M04SAU324I7G,A
P3V3_AUX                 U122             H5       10M04SAU324I7G-10M04SAU324I7G,A
P3V3_AUX                 U122             H10      10M04SAU324I7G-10M04SAU324I7G,A
P3V3_AUX                 U122             H13      10M04SAU324I7G-10M04SAU324I7G,A
P3V3_AUX                 U122             J5       10M04SAU324I7G-10M04SAU324I7G,A
P3V3_AUX                 U122             J9       10M04SAU324I7G-10M04SAU324I7G,A
P3V3_AUX                 U122             J13      10M04SAU324I7G-10M04SAU324I7G,A
P3V3_AUX                 U122             J14      10M04SAU324I7G-10M04SAU324I7G,A
P3V3_AUX                 U122             K5       10M04SAU324I7G-10M04SAU324I7G,A
P3V3_AUX                 U122             K10      10M04SAU324I7G-10M04SAU324I7G,A
P3V3_AUX                 U122             K14      10M04SAU324I7G-10M04SAU324I7G,A
P3V3_AUX                 U122             L5       10M04SAU324I7G-10M04SAU324I7G,A
P3V3_AUX                 U122             L6       10M04SAU324I7G-10M04SAU324I7G,A
P3V3_AUX                 U122             L9       10M04SAU324I7G-10M04SAU324I7G,A
P3V3_AUX                 U122             L13      10M04SAU324I7G-10M04SAU324I7G,A
P3V3_AUX                 U122             L14      10M04SAU324I7G-10M04SAU324I7G,A
P3V3_AUX                 U122             M5       10M04SAU324I7G-10M04SAU324I7G,A
P3V3_AUX                 U122             M13      10M04SAU324I7G-10M04SAU324I7G,A
P3V3_AUX                 U122             N6       10M04SAU324I7G-10M04SAU324I7G,A
P3V3_AUX                 U123             3        TPS259520DSGR-TPS259520DSGR,SMA
P3V3_AUX                 U123             4        TPS259520DSGR-TPS259520DSGR,SMA
P3V3_AUX                 U124             3        TPS259520DSGR-TPS259520DSGR,SMA
P3V3_AUX                 U124             4        TPS259520DSGR-TPS259520DSGR,SMA
P3V3_AUX                 U125             3        TPS259520DSGR-TPS259520DSGR,SMA
P3V3_AUX                 U125             4        TPS259520DSGR-TPS259520DSGR,SMA
P3V3_AUX                 U130             24       PCA9555PW_SMLF-PCA9555PW,IC,TMA
P3V3_AUX                 U131             24       PCA9555PW_SMLF-PCA9555PW,IC,TMA
P3V3_AUX                 U132             5        SN74LVC2G17DCKR-SN74LVC2G17DCKA
P3V3_AUX                 U133             5        SN74LVC2G17DCKR-SN74LVC2G17DCKA
P3V3_AUX                 U134             5        SN74LVC2G07DCKR_SMLF-SN74LVC2GA
P3V3_AUX                 U135             5        SN74LVC2G07DCKR_SMLF-SN74LVC2GA
P3V3_AUX                 U136             5        SN74LVC2G07DCKR_SMLF-SN74LVC2GA
P3V3_AUX                 U137             5        SN74LVC2G07DCKR_SMLF-SN74LVC2GA
P3V3_AUX                 U141             16       PCA9546APWR-PCA9546APWR,SMLF,IA
P3V3_AUX_CLK_GEN_VDDA100M_CK440 C172             1        Q_CAP_C0603-10UF,6.3V,20%,X6S,A
P3V3_AUX_CLK_GEN_VDDA100M_CK440 C173             1        Q_CAP_0402-0.1UF,25V,10%,X7R,CA
P3V3_AUX_CLK_GEN_VDDA100M_CK440 R519             2        Q_RES_0603LF-1,1%,1/10W,CHIP,CA
P3V3_AUX_CLK_GEN_VDDA100M_CK440 U13              B17      9SQ440NQQI8-9SQ440NQQI8,SMLF,IA
P3V3_AUX_CLK_GEN_VDDA25M_CK440 C114             1        Q_CAP_0402-0.1UF,25V,10%,X7R,CA
P3V3_AUX_CLK_GEN_VDDA25M_CK440 C1313            1        Q_CAP_C0603-10UF,6.3V,20%,X6S,A
P3V3_AUX_CLK_GEN_VDDA25M_CK440 R442             2        Q_RES_0603LF-1,1%,1/10W,CHIP,CA
P3V3_AUX_CLK_GEN_VDDA25M_CK440 U13              B1       9SQ440NQQI8-9SQ440NQQI8,SMLF,IA
P3V3_AUX_CLK_GEN_VDDMXCK_CK440 C115             1        Q_CAP_0402-0.1UF,25V,10%,X7R,CA
P3V3_AUX_CLK_GEN_VDDMXCK_CK440 C116             1        Q_CAP_0402-0.1UF,25V,10%,X7R,CA
P3V3_AUX_CLK_GEN_VDDMXCK_CK440 C117             1        Q_CAP_0402-0.1UF,25V,10%,X7R,CA
P3V3_AUX_CLK_GEN_VDDMXCK_CK440 C119             1        Q_CAP_0402-0.1UF,25V,10%,X7R,CA
P3V3_AUX_CLK_GEN_VDDMXCK_CK440 C1310            1        Q_CAP_C0603-10UF,6.3V,20%,X6S,A
P3V3_AUX_CLK_GEN_VDDMXCK_CK440 C1312            1        Q_CAP_C0402-1UF,25V,10%,X6S,CHA
P3V3_AUX_CLK_GEN_VDDMXCK_CK440 L14              2        Q_INDUCTOR_SMLF-FCM2012KF-601TA
P3V3_AUX_CLK_GEN_VDDMXCK_CK440 R447             1        Q_RES_0603LF-1,1%,1/10W,CHIP,CA
P3V3_AUX_CLK_GEN_VDDMXCK_CK440 U13              B29      9SQ440NQQI8-9SQ440NQQI8,SMLF,IA
P3V3_AUX_CLK_GEN_VDDMXCK_CK440 U13              B32      9SQ440NQQI8-9SQ440NQQI8,SMLF,IA
P3V3_AUX_CLK_GEN_VDDMXCK_CK440 U13              B35      9SQ440NQQI8-9SQ440NQQI8,SMLF,IA
P3V3_AUX_CLK_GEN_VDDMXCK_CK440 U13              B40      9SQ440NQQI8-9SQ440NQQI8,SMLF,IA
P3V3_AUX_CLK_GEN_VDDPT_CK440 C120             1        Q_CAP_0402-0.1UF,25V,10%,X7R,CA
P3V3_AUX_CLK_GEN_VDDPT_CK440 C1314            1        Q_CAP_C0603-10UF,6.3V,20%,X6S,A
P3V3_AUX_CLK_GEN_VDDPT_CK440 R447             2        Q_RES_0603LF-1,1%,1/10W,CHIP,CA
P3V3_AUX_CLK_GEN_VDDPT_CK440 U13              B6       9SQ440NQQI8-9SQ440NQQI8,SMLF,IA
P3V3_AUX_CLK_GEN_VDDXTAL_CK440 C111             1        Q_CAP_0402-0.1UF,25V,10%,X7R,CA
P3V3_AUX_CLK_GEN_VDDXTAL_CK440 C112             1        Q_CAP_0402-0.1UF,25V,10%,X7R,CA
P3V3_AUX_CLK_GEN_VDDXTAL_CK440 C1309            1        Q_CAP_C0603-10UF,6.3V,20%,X6S,A
P3V3_AUX_CLK_GEN_VDDXTAL_CK440 C1311            1        Q_CAP_C0402-1UF,25V,10%,X6S,CHA
P3V3_AUX_CLK_GEN_VDDXTAL_CK440 L13              2        Q_INDUCTOR_SMLF-FCM2012KF-601TA
P3V3_AUX_CLK_GEN_VDDXTAL_CK440 R442             1        Q_RES_0603LF-1,1%,1/10W,CHIP,CA
P3V3_AUX_CLK_GEN_VDDXTAL_CK440 U13              A12      9SQ440NQQI8-9SQ440NQQI8,SMLF,IA
P3V3_AUX_CLK_GEN_VDD_CK440 C108             1        Q_CAP_C0603-10UF,6.3V,20%,X6S,A
P3V3_AUX_CLK_GEN_VDD_CK440 C109             1        Q_CAP_C0402-1UF,25V,10%,X6S,CHA
P3V3_AUX_CLK_GEN_VDD_CK440 C110             1        Q_CAP_0402-0.1UF,25V,10%,X7R,CA
P3V3_AUX_CLK_GEN_VDD_CK440 C171             1        Q_CAP_0402-0.1UF,25V,10%,X7R,CA
P3V3_AUX_CLK_GEN_VDD_CK440 L1               2        Q_INDUCTOR_SMLF-FCM2012KF-601TA
P3V3_AUX_CLK_GEN_VDD_CK440 R519             1        Q_RES_0603LF-1,1%,1/10W,CHIP,CA
P3V3_AUX_CLK_GEN_VDD_CK440 U13              B21      9SQ440NQQI8-9SQ440NQQI8,SMLF,IA
P3V3_AUX_CLK_GEN_VDD_CK440 U13              B23      9SQ440NQQI8-9SQ440NQQI8,SMLF,IA
P3V3_AUX_DPLD_ADC_VREF   R507             2        Q_RES_0402LF-0,5%,1/16W,EMPTY,A
P3V3_AUX_DPLD_ADC_VREF   R508             1        Q_RES_0402LF-0,5%,1/16W,EMPTY,A
P3V3_AUX_DPLD_ADC_VREF   U122             F3       10M04SAU324I7G-10M04SAU324I7G,A
P3V3_AUX_FB              PC569            1        Q_CAP_0402-10PF,50V,1%,NPO,TMPA
P3V3_AUX_FB              PR830            1        Q_RES_0402LF-31.6K,1%,1/16W,CHA
P3V3_AUX_FB              PR831            1        Q_RES_0402LF-100K,1%,1/16W,CHIA
P3V3_AUX_FB              PU9              30       NCP3284MNTXG-NCP3284MNTXG,SMLFA
P3V3_AUX_ILIM            PR834            1        Q_RES_0402LF-21.5K,1%,1/16W,CHA
P3V3_AUX_ILIM            PU9              1        NCP3284MNTXG-NCP3284MNTXG,SMLFA
P3V3_AUX_MODE            PR832            1        Q_RES_0402LF-7.5K,1%,1/16W,CHIA
P3V3_AUX_MODE            PU9              36       NCP3284MNTXG-NCP3284MNTXG,SMLFA
P3V3_AUX_SENSE           C1344            1        Q_CAP_0402-0.1UF,25V,10%,X7R,CA
P3V3_AUX_SENSE           R1786            2        Q_RES_0402LF-0,1%,1/16W,CHIP,TA
P3V3_AUX_SENSE           R1787            1        Q_RES_0402LF-1K,0.1%,1/16W,CHIA
P3V3_AUX_SENSE           U105             4        ADS1015IDGSR-ADS1015IDGSR,SMLFA
P3V3_AUX_SENSE           U121             1        MAX11607EUAT-MAX11607EUA+T,SMLA
P3V3_AUX_SS              PR833            1        Q_RES_0402LF-1.5K,1%,1/16W,EMPA
P3V3_AUX_SS              PU9              29       NCP3284MNTXG-NCP3284MNTXG,SMLFA
P3V3_AUX_VCC             PC591            1        Q_CAP_C0603-2.2UF,16V,10%,X6S,A
P3V3_AUX_VCC             PR389            2        Q_RES_0402LF-1,1%,1/16W,CHIP,CA
P3V3_AUX_VCC             PU9              4        NCP3284MNTXG-NCP3284MNTXG,SMLFA
P3V3_AUX_VOS             PR836            1        Q_RES_0402LF-1K,1%,1/16W,CHIP,A
P3V3_AUX_VOS             PU9              28       NCP3284MNTXG-NCP3284MNTXG,SMLFA
P3V3_DB2000_FB_VDD       L4               2        Q_INDUCTOR_SMLF-BLM18SG331TN1DA
P3V3_DB2000_FB_VDD       R571             1        Q_RES_0603LF-2.2,1%,1/10W,CHIPA
P3V3_DB2000_FB_VDD       R572             1        Q_RES_0603LF-2.2,1%,1/10W,CHIPA
P3V3_DB2000_VDD          C204             1        Q_CAP_0402-0.1UF,25V,10%,X7R,CA
P3V3_DB2000_VDD          C205             1        Q_CAP_0402-0.1UF,25V,10%,X7R,CA
P3V3_DB2000_VDD          C206             1        Q_CAP_0402-0.1UF,25V,10%,X7R,CA
P3V3_DB2000_VDD          C207             1        Q_CAP_0402-0.1UF,25V,10%,X7R,CA
P3V3_DB2000_VDD          C1409            1        Q_CAP_C0603-10UF,6.3V,20%,X6S,A
P3V3_DB2000_VDD          L3               2        Q_INDUCTOR_SMLF-BLM18SG331TN1DA
P3V3_DB2000_VDD          U38              B2       9QXL2001BNHGI8-9QXL2001BNHGI8,A
P3V3_DB2000_VDD          U38              B11      9QXL2001BNHGI8-9QXL2001BNHGI8,A
P3V3_DB2000_VDD          U38              L2       9QXL2001BNHGI8-9QXL2001BNHGI8,A
P3V3_DB2000_VDD          U38              L11      9QXL2001BNHGI8-9QXL2001BNHGI8,A
P3V3_DB2000_VDDA         C209             1        Q_CAP_C0603-10UF,6.3V,20%,X6S,A
P3V3_DB2000_VDDA         C211             1        Q_CAP_0402-0.1UF,25V,10%,X7R,CA
P3V3_DB2000_VDDA         R572             2        Q_RES_0603LF-2.2,1%,1/10W,CHIPA
P3V3_DB2000_VDDA         U38              B6       9QXL2001BNHGI8-9QXL2001BNHGI8,A
P3V3_DB2000_VDDR         C208             1        Q_CAP_C0603-10UF,6.3V,20%,X6S,A
P3V3_DB2000_VDDR         C210             1        Q_CAP_0402-0.1UF,25V,10%,X7R,CA
P3V3_DB2000_VDDR         R571             2        Q_RES_0603LF-2.2,1%,1/10W,CHIPA
P3V3_DB2000_VDDR         U38              H2       9QXL2001BNHGI8-9QXL2001BNHGI8,A
P3V3_E1S_0               C184             1        Q_CAP_C0805-10UF,25V,10%,X6S,CA
P3V3_E1S_0               C1282            1        Q_CAP_0402-0.1UF,25V,10%,X7R,CA
P3V3_E1S_0               C1283            1        Q_CAP_0402-0.1UF,25V,10%,X7R,CA
P3V3_E1S_0               J90              B11      CONN56_ME2005602311011-CONN56_A
P3V3_E1S_0               R1673            1        Q_RES_0402LF-10K,1%,1/16W,EMPTA
P3V3_E1S_0               U40              5        TPS259520DSGR-TPS259520DSGR,SMA
P3V3_E1S_0_DVDT          C179             1        Q_CAP_C0402-100NF,50V,10%,X7R,A
P3V3_E1S_0_DVDT          U40              1        TPS259520DSGR-TPS259520DSGR,SMA
P3V3_E1S_0_FLT_N         R1104            2        Q_RES_0402LF-10K,1%,1/16W,CHIPA
P3V3_E1S_0_FLT_N         U40              6        TPS259520DSGR-TPS259520DSGR,SMA
P3V3_E1S_0_ILM           R1103            1        Q_RES_0402LF-1.33K,1%,1/16W,CHA
P3V3_E1S_0_ILM           U40              7        TPS259520DSGR-TPS259520DSGR,SMA
P3V3_E1S_1               C1284            1        Q_CAP_0402-0.1UF,25V,10%,X7R,CA
P3V3_E1S_1               C1285            1        Q_CAP_0402-0.1UF,25V,10%,X7R,CA
P3V3_E1S_1               C1487            1        Q_CAP_C0805-10UF,25V,10%,X6S,CA
P3V3_E1S_1               J91              B11      CONN56_ME2005602311011-CONN56_A
P3V3_E1S_1               R2005            1        Q_RES_0402LF-10K,1%,1/16W,EMPTA
P3V3_E1S_1               U124             5        TPS259520DSGR-TPS259520DSGR,SMA
P3V3_E1S_1_DVDT          C1484            1        Q_CAP_C0402-100NF,50V,10%,X7R,A
P3V3_E1S_1_DVDT          U124             1        TPS259520DSGR-TPS259520DSGR,SMA
P3V3_E1S_1_FLT_N         R2022            2        Q_RES_0402LF-10K,1%,1/16W,CHIPA
P3V3_E1S_1_FLT_N         U124             6        TPS259520DSGR-TPS259520DSGR,SMA
P3V3_E1S_1_ILM           R2020            1        Q_RES_0402LF-1.33K,1%,1/16W,CHA
P3V3_E1S_1_ILM           U124             7        TPS259520DSGR-TPS259520DSGR,SMA
P3V3_E1S_2               C1483            1        Q_CAP_C0805-10UF,25V,10%,X6S,CA
P3V3_E1S_2               C1499            1        Q_CAP_0402-0.1UF,25V,10%,X7R,CA
P3V3_E1S_2               C1501            1        Q_CAP_0402-0.1UF,25V,10%,X7R,CA
P3V3_E1S_2               J92              B11      CONN56_ME2005602311011-CONN56_A
P3V3_E1S_2               R2006            1        Q_RES_0402LF-10K,1%,1/16W,EMPTA
P3V3_E1S_2               U123             5        TPS259520DSGR-TPS259520DSGR,SMA
P3V3_E1S_2_DVDT          C1480            1        Q_CAP_C0402-100NF,50V,10%,X7R,A
P3V3_E1S_2_DVDT          U123             1        TPS259520DSGR-TPS259520DSGR,SMA
P3V3_E1S_2_FLT_N         R2017            2        Q_RES_0402LF-10K,1%,1/16W,CHIPA
P3V3_E1S_2_FLT_N         U123             6        TPS259520DSGR-TPS259520DSGR,SMA
P3V3_E1S_2_ILM           R2016            1        Q_RES_0402LF-1.33K,1%,1/16W,CHA
P3V3_E1S_2_ILM           U123             7        TPS259520DSGR-TPS259520DSGR,SMA
P3V3_E1S_3               C1488            1        Q_CAP_C0805-10UF,25V,10%,X6S,CA
P3V3_E1S_3               C1500            1        Q_CAP_0402-0.1UF,25V,10%,X7R,CA
P3V3_E1S_3               C1502            1        Q_CAP_0402-0.1UF,25V,10%,X7R,CA
P3V3_E1S_3               J93              B11      CONN56_ME2005602311011-CONN56_A
P3V3_E1S_3               R2007            1        Q_RES_0402LF-10K,1%,1/16W,EMPTA
P3V3_E1S_3               U125             5        TPS259520DSGR-TPS259520DSGR,SMA
P3V3_E1S_3_DVDT          C575             1        Q_CAP_C0402-100NF,50V,10%,X7R,A
P3V3_E1S_3_DVDT          U125             1        TPS259520DSGR-TPS259520DSGR,SMA
P3V3_E1S_3_FLT_N         R2023            2        Q_RES_0402LF-10K,1%,1/16W,CHIPA
P3V3_E1S_3_FLT_N         U125             6        TPS259520DSGR-TPS259520DSGR,SMA
P3V3_E1S_3_ILM           R2021            1        Q_RES_0402LF-1.33K,1%,1/16W,CHA
P3V3_E1S_3_ILM           U125             7        TPS259520DSGR-TPS259520DSGR,SMA
P3V3_OCP_DVDT_1          C582             1        Q_CAP_C0402-100NF,50V,10%,X7R,A
P3V3_OCP_DVDT_1          U56              1        TPS259520DSGR-TPS259520DSGR,SMA
P3V3_OCP_ILM1            R1142            1        Q_RES_0402LF-1K,5%,1/16W,CHIP,A
P3V3_OCP_ILM1            U56              7        TPS259520DSGR-TPS259520DSGR,SMA
P3V3_OCP_SFF             C587             1        Q_CAP_C0805-10UF,25V,10%,X6S,CA
P3V3_OCP_SFF             C1237            1        Q_CAP_0402-0.1UF,25V,10%,X7R,CA
P3V3_OCP_SFF             C1238            1        Q_CAP_0402-0.1UF,25V,10%,X7R,CA
P3V3_OCP_SFF             C1239            1        Q_CAP_0402-0.1UF,25V,10%,X7R,CA
P3V3_OCP_SFF             C1240            1        Q_CAP_0402-0.1UF,25V,10%,X7R,CA
P3V3_OCP_SFF             J37              B11      SCONN168_623403212-SCONN168_6-A
P3V3_OCP_SFF             R409             1        Q_RES_0402LF-4.7K,1%,1/16W,EMPA
P3V3_OCP_SFF             R414             1        Q_RES_0402LF-4.7K,1%,1/16W,EMPA
P3V3_OCP_SFF             R420             2        Q_RES_0402LF-1K,1%,1/16W,EMPTYA
P3V3_OCP_SFF             R421             2        Q_RES_0402LF-4.7K,5%,1/16W,CHIA
P3V3_OCP_SFF             R454             1        Q_RES_0402LF-10K,1%,1/16W,EMPTA
P3V3_OCP_SFF             R1132            1        Q_RES_0402LF-1K,5%,1/16W,EMPTYA
P3V3_OCP_SFF             R1592            1        Q_RES_0402LF-10K,1%,1/16W,CHIPA
P3V3_OCP_SFF             R1824            1        Q_RES_0402LF-10K,1%,1/16W,CHIPA
P3V3_OCP_SFF             U56              5        TPS259520DSGR-TPS259520DSGR,SMA
P3V3_RTC_AUX             C611             1        Q_CAP_C0402-1UF,25V,10%,X6S,CHA
P3V3_RTC_AUX             R989             2        Q_RES_0402LF-10K,1%,1/16W,CHIPA
P3V3_RTC_AUX             R1202            1        Q_RES_0402LF-20K,1%,1/16W,CHIPA
P3V3_RTC_AUX             R1340            1        Q_RES_0402LF-20K,5%,1/16W,CHIPA
P3V3_RTC_AUX             U4               AH15     EMMITSBURG_REV0P9-GFNOCPU04302A
P3V3_RTC_AUX             U62              3        BAS70057F-BAS70-05-7-F,SMLF,ICA
P3V3_RTC_AUX_SENSE       C1346            1        Q_CAP_0402-0.1UF,25V,10%,X7R,CA
P3V3_RTC_AUX_SENSE       R1790            2        Q_RES_0402LF-1K,1%,1/16W,EMPTYA
P3V3_RTC_AUX_SENSE       R1791            1        Q_RES_0402LF-200K,1%,1/16W,CHIA
P3V3_RTC_AUX_SENSE       U105             6        ADS1015IDGSR-ADS1015IDGSR,SMLFA
P3V3_RTC_AUX_SENSE       U121             3        MAX11607EUAT-MAX11607EUA+T,SMLA
P3V3_SENSE               C1345            1        Q_CAP_0402-0.1UF,25V,10%,X7R,CA
P3V3_SENSE               R1788            2        Q_RES_0402LF-0,1%,1/16W,CHIP,TA
P3V3_SENSE               R1789            1        Q_RES_0402LF-1K,0.1%,1/16W,CHIA
P3V3_SENSE               U105             5        ADS1015IDGSR-ADS1015IDGSR,SMLFA
P3V3_SENSE               U121             2        MAX11607EUAT-MAX11607EUA+T,SMLA
P3V_BAT                  BT1              1        CONN2_AAABAT029P15-CONN2_AAA-BA
P3V_BAT                  R1203            1        Q_RES_0402LF-1K,1%,1/16W,CHIP,A
P3V_BAT                  R1790            1        Q_RES_0402LF-1K,1%,1/16W,EMPTYA
P3V_BAT_R                J41              B41      SCONN168_623403212-SCONN168_6-A
P3V_BAT_R                R1203            2        Q_RES_0402LF-1K,1%,1/16W,CHIP,A
P3V_BAT_R                U62              1        BAS70057F-BAS70-05-7-F,SMLF,ICA
P5E_CPU0_PE0_RX_DN<0>    J90              A17      CONN56_ME2005602311011-CONN56_A
P5E_CPU0_PE0_RX_DN<0>    U2               BA9      SOCKET4677_AZIFS054P001C01-SOCA
P5E_CPU0_PE0_RX_DN<1>    J90              A20      CONN56_ME2005602311011-CONN56_A
P5E_CPU0_PE0_RX_DN<1>    U2               AV10     SOCKET4677_AZIFS054P001C01-SOCA
P5E_CPU0_PE0_RX_DN<2>    J90              A23      CONN56_ME2005602311011-CONN56_A
P5E_CPU0_PE0_RX_DN<2>    U2               AU9      SOCKET4677_AZIFS054P001C01-SOCA
P5E_CPU0_PE0_RX_DN<3>    J90              A26      CONN56_ME2005602311011-CONN56_A
P5E_CPU0_PE0_RX_DN<3>    U2               AP10     SOCKET4677_AZIFS054P001C01-SOCA
P5E_CPU0_PE0_RX_DN<4>    J91              A17      CONN56_ME2005602311011-CONN56_A
P5E_CPU0_PE0_RX_DN<4>    U2               AM10     SOCKET4677_AZIFS054P001C01-SOCA
P5E_CPU0_PE0_RX_DN<5>    J91              A20      CONN56_ME2005602311011-CONN56_A
P5E_CPU0_PE0_RX_DN<5>    U2               AK10     SOCKET4677_AZIFS054P001C01-SOCA
P5E_CPU0_PE0_RX_DN<6>    J91              A23      CONN56_ME2005602311011-CONN56_A
P5E_CPU0_PE0_RX_DN<6>    U2               AJ9      SOCKET4677_AZIFS054P001C01-SOCA
P5E_CPU0_PE0_RX_DN<7>    J91              A26      CONN56_ME2005602311011-CONN56_A
P5E_CPU0_PE0_RX_DN<7>    U2               AF10     SOCKET4677_AZIFS054P001C01-SOCA
P5E_CPU0_PE0_RX_DN<8>    J92              A17      CONN56_ME2005602311011-CONN56_A
P5E_CPU0_PE0_RX_DN<8>    U2               AE9      SOCKET4677_AZIFS054P001C01-SOCA
P5E_CPU0_PE0_RX_DN<9>    J92              A20      CONN56_ME2005602311011-CONN56_A
P5E_CPU0_PE0_RX_DN<9>    U2               AB10     SOCKET4677_AZIFS054P001C01-SOCA
P5E_CPU0_PE0_RX_DN<10>   J92              A23      CONN56_ME2005602311011-CONN56_A
P5E_CPU0_PE0_RX_DN<10>   U2               AA9      SOCKET4677_AZIFS054P001C01-SOCA
P5E_CPU0_PE0_RX_DN<11>   J92              A26      CONN56_ME2005602311011-CONN56_A
P5E_CPU0_PE0_RX_DN<11>   U2               V10      SOCKET4677_AZIFS054P001C01-SOCA
P5E_CPU0_PE0_RX_DN<12>   J93              A17      CONN56_ME2005602311011-CONN56_A
P5E_CPU0_PE0_RX_DN<12>   U2               T10      SOCKET4677_AZIFS054P001C01-SOCA
P5E_CPU0_PE0_RX_DN<13>   J93              A20      CONN56_ME2005602311011-CONN56_A
P5E_CPU0_PE0_RX_DN<13>   U2               P10      SOCKET4677_AZIFS054P001C01-SOCA
P5E_CPU0_PE0_RX_DN<14>   J93              A23      CONN56_ME2005602311011-CONN56_A
P5E_CPU0_PE0_RX_DN<14>   U2               M10      SOCKET4677_AZIFS054P001C01-SOCA
P5E_CPU0_PE0_RX_DN<15>   J93              A26      CONN56_ME2005602311011-CONN56_A
P5E_CPU0_PE0_RX_DN<15>   U2               K10      SOCKET4677_AZIFS054P001C01-SOCA
P5E_CPU0_PE0_RX_DP<0>    J90              A18      CONN56_ME2005602311011-CONN56_A
P5E_CPU0_PE0_RX_DP<0>    U2               AY10     SOCKET4677_AZIFS054P001C01-SOCA
P5E_CPU0_PE0_RX_DP<1>    J90              A21      CONN56_ME2005602311011-CONN56_A
P5E_CPU0_PE0_RX_DP<1>    U2               AW11     SOCKET4677_AZIFS054P001C01-SOCA
P5E_CPU0_PE0_RX_DP<2>    J90              A24      CONN56_ME2005602311011-CONN56_A
P5E_CPU0_PE0_RX_DP<2>    U2               AT10     SOCKET4677_AZIFS054P001C01-SOCA
P5E_CPU0_PE0_RX_DP<3>    J90              A27      CONN56_ME2005602311011-CONN56_A
P5E_CPU0_PE0_RX_DP<3>    U2               AR11     SOCKET4677_AZIFS054P001C01-SOCA
P5E_CPU0_PE0_RX_DP<4>    J91              A18      CONN56_ME2005602311011-CONN56_A
P5E_CPU0_PE0_RX_DP<4>    U2               AN9      SOCKET4677_AZIFS054P001C01-SOCA
P5E_CPU0_PE0_RX_DP<5>    J91              A21      CONN56_ME2005602311011-CONN56_A
P5E_CPU0_PE0_RX_DP<5>    U2               AL11     SOCKET4677_AZIFS054P001C01-SOCA
P5E_CPU0_PE0_RX_DP<6>    J91              A24      CONN56_ME2005602311011-CONN56_A
P5E_CPU0_PE0_RX_DP<6>    U2               AH10     SOCKET4677_AZIFS054P001C01-SOCA
P5E_CPU0_PE0_RX_DP<7>    J91              A27      CONN56_ME2005602311011-CONN56_A
P5E_CPU0_PE0_RX_DP<7>    U2               AG11     SOCKET4677_AZIFS054P001C01-SOCA
P5E_CPU0_PE0_RX_DP<8>    J92              A18      CONN56_ME2005602311011-CONN56_A
P5E_CPU0_PE0_RX_DP<8>    U2               AD10     SOCKET4677_AZIFS054P001C01-SOCA
P5E_CPU0_PE0_RX_DP<9>    J92              A21      CONN56_ME2005602311011-CONN56_A
P5E_CPU0_PE0_RX_DP<9>    U2               AC11     SOCKET4677_AZIFS054P001C01-SOCA
P5E_CPU0_PE0_RX_DP<10>   J92              A24      CONN56_ME2005602311011-CONN56_A
P5E_CPU0_PE0_RX_DP<10>   U2               Y10      SOCKET4677_AZIFS054P001C01-SOCA
P5E_CPU0_PE0_RX_DP<11>   J92              A27      CONN56_ME2005602311011-CONN56_A
P5E_CPU0_PE0_RX_DP<11>   U2               W11      SOCKET4677_AZIFS054P001C01-SOCA
P5E_CPU0_PE0_RX_DP<12>   J93              A18      CONN56_ME2005602311011-CONN56_A
P5E_CPU0_PE0_RX_DP<12>   U2               U9       SOCKET4677_AZIFS054P001C01-SOCA
P5E_CPU0_PE0_RX_DP<13>   J93              A21      CONN56_ME2005602311011-CONN56_A
P5E_CPU0_PE0_RX_DP<13>   U2               R11      SOCKET4677_AZIFS054P001C01-SOCA
P5E_CPU0_PE0_RX_DP<14>   J93              A24      CONN56_ME2005602311011-CONN56_A
P5E_CPU0_PE0_RX_DP<14>   U2               N9       SOCKET4677_AZIFS054P001C01-SOCA
P5E_CPU0_PE0_RX_DP<15>   J93              A27      CONN56_ME2005602311011-CONN56_A
P5E_CPU0_PE0_RX_DP<15>   U2               L11      SOCKET4677_AZIFS054P001C01-SOCA
P5E_CPU0_PE0_TX_C_DN<0>  C932             1        Q_CAP_DIFFBUS_C0201-DIFF BUS_0A
P5E_CPU0_PE0_TX_C_DN<0>  J90              B17      CONN56_ME2005602311011-CONN56_A
P5E_CPU0_PE0_TX_C_DN<1>  C930             1        Q_CAP_DIFFBUS_C0201-DIFF BUS_0A
P5E_CPU0_PE0_TX_C_DN<1>  J90              B20      CONN56_ME2005602311011-CONN56_A
P5E_CPU0_PE0_TX_C_DN<2>  C928             1        Q_CAP_DIFFBUS_C0201-DIFF BUS_0A
P5E_CPU0_PE0_TX_C_DN<2>  J90              B23      CONN56_ME2005602311011-CONN56_A
P5E_CPU0_PE0_TX_C_DN<3>  C926             1        Q_CAP_DIFFBUS_C0201-DIFF BUS_0A
P5E_CPU0_PE0_TX_C_DN<3>  J90              B26      CONN56_ME2005602311011-CONN56_A
P5E_CPU0_PE0_TX_C_DN<4>  C924             1        Q_CAP_DIFFBUS_C0201-DIFF BUS_0A
P5E_CPU0_PE0_TX_C_DN<4>  J91              B17      CONN56_ME2005602311011-CONN56_A
P5E_CPU0_PE0_TX_C_DN<5>  C922             1        Q_CAP_DIFFBUS_C0201-DIFF BUS_0A
P5E_CPU0_PE0_TX_C_DN<5>  J91              B20      CONN56_ME2005602311011-CONN56_A
P5E_CPU0_PE0_TX_C_DN<6>  C920             1        Q_CAP_DIFFBUS_C0201-DIFF BUS_0A
P5E_CPU0_PE0_TX_C_DN<6>  J91              B23      CONN56_ME2005602311011-CONN56_A
P5E_CPU0_PE0_TX_C_DN<7>  C918             1        Q_CAP_DIFFBUS_C0201-DIFF BUS_0A
P5E_CPU0_PE0_TX_C_DN<7>  J91              B26      CONN56_ME2005602311011-CONN56_A
P5E_CPU0_PE0_TX_C_DN<8>  C916             1        Q_CAP_DIFFBUS_C0201-DIFF BUS_0A
P5E_CPU0_PE0_TX_C_DN<8>  J92              B17      CONN56_ME2005602311011-CONN56_A
P5E_CPU0_PE0_TX_C_DN<9>  C914             1        Q_CAP_DIFFBUS_C0201-DIFF BUS_0A
P5E_CPU0_PE0_TX_C_DN<9>  J92              B20      CONN56_ME2005602311011-CONN56_A
P5E_CPU0_PE0_TX_C_DN<10> C912             1        Q_CAP_DIFFBUS_C0201-DIFF BUS_0A
P5E_CPU0_PE0_TX_C_DN<10> J92              B23      CONN56_ME2005602311011-CONN56_A
P5E_CPU0_PE0_TX_C_DN<11> C910             1        Q_CAP_DIFFBUS_C0201-DIFF BUS_0A
P5E_CPU0_PE0_TX_C_DN<11> J92              B26      CONN56_ME2005602311011-CONN56_A
P5E_CPU0_PE0_TX_C_DN<12> C908             1        Q_CAP_DIFFBUS_C0201-DIFF BUS_0A
P5E_CPU0_PE0_TX_C_DN<12> J93              B17      CONN56_ME2005602311011-CONN56_A
P5E_CPU0_PE0_TX_C_DN<13> C906             1        Q_CAP_DIFFBUS_C0201-DIFF BUS_0A
P5E_CPU0_PE0_TX_C_DN<13> J93              B20      CONN56_ME2005602311011-CONN56_A
P5E_CPU0_PE0_TX_C_DN<14> C904             1        Q_CAP_DIFFBUS_C0201-DIFF BUS_0A
P5E_CPU0_PE0_TX_C_DN<14> J93              B23      CONN56_ME2005602311011-CONN56_A
P5E_CPU0_PE0_TX_C_DN<15> C902             1        Q_CAP_DIFFBUS_C0201-DIFF BUS_0A
P5E_CPU0_PE0_TX_C_DN<15> J93              B26      CONN56_ME2005602311011-CONN56_A
P5E_CPU0_PE0_TX_C_DP<0>  C933             1        Q_CAP_DIFFBUS_C0201-DIFF BUS_0A
P5E_CPU0_PE0_TX_C_DP<0>  J90              B18      CONN56_ME2005602311011-CONN56_A
P5E_CPU0_PE0_TX_C_DP<1>  C931             1        Q_CAP_DIFFBUS_C0201-DIFF BUS_0A
P5E_CPU0_PE0_TX_C_DP<1>  J90              B21      CONN56_ME2005602311011-CONN56_A
P5E_CPU0_PE0_TX_C_DP<2>  C929             1        Q_CAP_DIFFBUS_C0201-DIFF BUS_0A
P5E_CPU0_PE0_TX_C_DP<2>  J90              B24      CONN56_ME2005602311011-CONN56_A
P5E_CPU0_PE0_TX_C_DP<3>  C927             1        Q_CAP_DIFFBUS_C0201-DIFF BUS_0A
P5E_CPU0_PE0_TX_C_DP<3>  J90              B27      CONN56_ME2005602311011-CONN56_A
P5E_CPU0_PE0_TX_C_DP<4>  C925             1        Q_CAP_DIFFBUS_C0201-DIFF BUS_0A
P5E_CPU0_PE0_TX_C_DP<4>  J91              B18      CONN56_ME2005602311011-CONN56_A
P5E_CPU0_PE0_TX_C_DP<5>  C923             1        Q_CAP_DIFFBUS_C0201-DIFF BUS_0A
P5E_CPU0_PE0_TX_C_DP<5>  J91              B21      CONN56_ME2005602311011-CONN56_A
P5E_CPU0_PE0_TX_C_DP<6>  C921             1        Q_CAP_DIFFBUS_C0201-DIFF BUS_0A
P5E_CPU0_PE0_TX_C_DP<6>  J91              B24      CONN56_ME2005602311011-CONN56_A
P5E_CPU0_PE0_TX_C_DP<7>  C919             1        Q_CAP_DIFFBUS_C0201-DIFF BUS_0A
P5E_CPU0_PE0_TX_C_DP<7>  J91              B27      CONN56_ME2005602311011-CONN56_A
P5E_CPU0_PE0_TX_C_DP<8>  C917             1        Q_CAP_DIFFBUS_C0201-DIFF BUS_0A
P5E_CPU0_PE0_TX_C_DP<8>  J92              B18      CONN56_ME2005602311011-CONN56_A
P5E_CPU0_PE0_TX_C_DP<9>  C915             1        Q_CAP_DIFFBUS_C0201-DIFF BUS_0A
P5E_CPU0_PE0_TX_C_DP<9>  J92              B21      CONN56_ME2005602311011-CONN56_A
P5E_CPU0_PE0_TX_C_DP<10> C913             1        Q_CAP_DIFFBUS_C0201-DIFF BUS_0A
P5E_CPU0_PE0_TX_C_DP<10> J92              B24      CONN56_ME2005602311011-CONN56_A
P5E_CPU0_PE0_TX_C_DP<11> C911             1        Q_CAP_DIFFBUS_C0201-DIFF BUS_0A
P5E_CPU0_PE0_TX_C_DP<11> J92              B27      CONN56_ME2005602311011-CONN56_A
P5E_CPU0_PE0_TX_C_DP<12> C909             1        Q_CAP_DIFFBUS_C0201-DIFF BUS_0A
P5E_CPU0_PE0_TX_C_DP<12> J93              B18      CONN56_ME2005602311011-CONN56_A
P5E_CPU0_PE0_TX_C_DP<13> C907             1        Q_CAP_DIFFBUS_C0201-DIFF BUS_0A
P5E_CPU0_PE0_TX_C_DP<13> J93              B21      CONN56_ME2005602311011-CONN56_A
P5E_CPU0_PE0_TX_C_DP<14> C905             1        Q_CAP_DIFFBUS_C0201-DIFF BUS_0A
P5E_CPU0_PE0_TX_C_DP<14> J93              B24      CONN56_ME2005602311011-CONN56_A
P5E_CPU0_PE0_TX_C_DP<15> C903             1        Q_CAP_DIFFBUS_C0201-DIFF BUS_0A
P5E_CPU0_PE0_TX_C_DP<15> J93              B27      CONN56_ME2005602311011-CONN56_A
P5E_CPU0_PE0_TX_DN<0>    C932             2        Q_CAP_DIFFBUS_C0201-DIFF BUS_0A
P5E_CPU0_PE0_TX_DN<0>    U2               BB14     SOCKET4677_AZIFS054P001C01-SOCA
P5E_CPU0_PE0_TX_DN<1>    C930             2        Q_CAP_DIFFBUS_C0201-DIFF BUS_0A
P5E_CPU0_PE0_TX_DN<1>    U2               BA13     SOCKET4677_AZIFS054P001C01-SOCA
P5E_CPU0_PE0_TX_DN<2>    C928             2        Q_CAP_DIFFBUS_C0201-DIFF BUS_0A
P5E_CPU0_PE0_TX_DN<2>    U2               AV14     SOCKET4677_AZIFS054P001C01-SOCA
P5E_CPU0_PE0_TX_DN<3>    C926             2        Q_CAP_DIFFBUS_C0201-DIFF BUS_0A
P5E_CPU0_PE0_TX_DN<3>    U2               AU13     SOCKET4677_AZIFS054P001C01-SOCA
P5E_CPU0_PE0_TX_DN<4>    C924             2        Q_CAP_DIFFBUS_C0201-DIFF BUS_0A
P5E_CPU0_PE0_TX_DN<4>    U2               AP14     SOCKET4677_AZIFS054P001C01-SOCA
P5E_CPU0_PE0_TX_DN<5>    C922             2        Q_CAP_DIFFBUS_C0201-DIFF BUS_0A
P5E_CPU0_PE0_TX_DN<5>    U2               AN13     SOCKET4677_AZIFS054P001C01-SOCA
P5E_CPU0_PE0_TX_DN<6>    C920             2        Q_CAP_DIFFBUS_C0201-DIFF BUS_0A
P5E_CPU0_PE0_TX_DN<6>    U2               AK14     SOCKET4677_AZIFS054P001C01-SOCA
P5E_CPU0_PE0_TX_DN<7>    C918             2        Q_CAP_DIFFBUS_C0201-DIFF BUS_0A
P5E_CPU0_PE0_TX_DN<7>    U2               AJ13     SOCKET4677_AZIFS054P001C01-SOCA
P5E_CPU0_PE0_TX_DN<8>    C916             2        Q_CAP_DIFFBUS_C0201-DIFF BUS_0A
P5E_CPU0_PE0_TX_DN<8>    U2               AF14     SOCKET4677_AZIFS054P001C01-SOCA
P5E_CPU0_PE0_TX_DN<9>    C914             2        Q_CAP_DIFFBUS_C0201-DIFF BUS_0A
P5E_CPU0_PE0_TX_DN<9>    U2               AE13     SOCKET4677_AZIFS054P001C01-SOCA
P5E_CPU0_PE0_TX_DN<10>   C912             2        Q_CAP_DIFFBUS_C0201-DIFF BUS_0A
P5E_CPU0_PE0_TX_DN<10>   U2               AB14     SOCKET4677_AZIFS054P001C01-SOCA
P5E_CPU0_PE0_TX_DN<11>   C910             2        Q_CAP_DIFFBUS_C0201-DIFF BUS_0A
P5E_CPU0_PE0_TX_DN<11>   U2               AA13     SOCKET4677_AZIFS054P001C01-SOCA
P5E_CPU0_PE0_TX_DN<12>   C908             2        Q_CAP_DIFFBUS_C0201-DIFF BUS_0A
P5E_CPU0_PE0_TX_DN<12>   U2               V14      SOCKET4677_AZIFS054P001C01-SOCA
P5E_CPU0_PE0_TX_DN<13>   C906             2        Q_CAP_DIFFBUS_C0201-DIFF BUS_0A
P5E_CPU0_PE0_TX_DN<13>   U2               U13      SOCKET4677_AZIFS054P001C01-SOCA
P5E_CPU0_PE0_TX_DN<14>   C904             2        Q_CAP_DIFFBUS_C0201-DIFF BUS_0A
P5E_CPU0_PE0_TX_DN<14>   U2               P14      SOCKET4677_AZIFS054P001C01-SOCA
P5E_CPU0_PE0_TX_DN<15>   C902             2        Q_CAP_DIFFBUS_C0201-DIFF BUS_0A
P5E_CPU0_PE0_TX_DN<15>   U2               N13      SOCKET4677_AZIFS054P001C01-SOCA
P5E_CPU0_PE0_TX_DP<0>    C933             2        Q_CAP_DIFFBUS_C0201-DIFF BUS_0A
P5E_CPU0_PE0_TX_DP<0>    U2               BC15     SOCKET4677_AZIFS054P001C01-SOCA
P5E_CPU0_PE0_TX_DP<1>    C931             2        Q_CAP_DIFFBUS_C0201-DIFF BUS_0A
P5E_CPU0_PE0_TX_DP<1>    U2               AY14     SOCKET4677_AZIFS054P001C01-SOCA
P5E_CPU0_PE0_TX_DP<2>    C929             2        Q_CAP_DIFFBUS_C0201-DIFF BUS_0A
P5E_CPU0_PE0_TX_DP<2>    U2               AW15     SOCKET4677_AZIFS054P001C01-SOCA
P5E_CPU0_PE0_TX_DP<3>    C927             2        Q_CAP_DIFFBUS_C0201-DIFF BUS_0A
P5E_CPU0_PE0_TX_DP<3>    U2               AT14     SOCKET4677_AZIFS054P001C01-SOCA
P5E_CPU0_PE0_TX_DP<4>    C925             2        Q_CAP_DIFFBUS_C0201-DIFF BUS_0A
P5E_CPU0_PE0_TX_DP<4>    U2               AR15     SOCKET4677_AZIFS054P001C01-SOCA
P5E_CPU0_PE0_TX_DP<5>    C923             2        Q_CAP_DIFFBUS_C0201-DIFF BUS_0A
P5E_CPU0_PE0_TX_DP<5>    U2               AM14     SOCKET4677_AZIFS054P001C01-SOCA
P5E_CPU0_PE0_TX_DP<6>    C921             2        Q_CAP_DIFFBUS_C0201-DIFF BUS_0A
P5E_CPU0_PE0_TX_DP<6>    U2               AL15     SOCKET4677_AZIFS054P001C01-SOCA
P5E_CPU0_PE0_TX_DP<7>    C919             2        Q_CAP_DIFFBUS_C0201-DIFF BUS_0A
P5E_CPU0_PE0_TX_DP<7>    U2               AH14     SOCKET4677_AZIFS054P001C01-SOCA
P5E_CPU0_PE0_TX_DP<8>    C917             2        Q_CAP_DIFFBUS_C0201-DIFF BUS_0A
P5E_CPU0_PE0_TX_DP<8>    U2               AG15     SOCKET4677_AZIFS054P001C01-SOCA
P5E_CPU0_PE0_TX_DP<9>    C915             2        Q_CAP_DIFFBUS_C0201-DIFF BUS_0A
P5E_CPU0_PE0_TX_DP<9>    U2               AD14     SOCKET4677_AZIFS054P001C01-SOCA
P5E_CPU0_PE0_TX_DP<10>   C913             2        Q_CAP_DIFFBUS_C0201-DIFF BUS_0A
P5E_CPU0_PE0_TX_DP<10>   U2               AC15     SOCKET4677_AZIFS054P001C01-SOCA
P5E_CPU0_PE0_TX_DP<11>   C911             2        Q_CAP_DIFFBUS_C0201-DIFF BUS_0A
P5E_CPU0_PE0_TX_DP<11>   U2               Y14      SOCKET4677_AZIFS054P001C01-SOCA
P5E_CPU0_PE0_TX_DP<12>   C909             2        Q_CAP_DIFFBUS_C0201-DIFF BUS_0A
P5E_CPU0_PE0_TX_DP<12>   U2               W15      SOCKET4677_AZIFS054P001C01-SOCA
P5E_CPU0_PE0_TX_DP<13>   C907             2        Q_CAP_DIFFBUS_C0201-DIFF BUS_0A
P5E_CPU0_PE0_TX_DP<13>   U2               T14      SOCKET4677_AZIFS054P001C01-SOCA
P5E_CPU0_PE0_TX_DP<14>   C905             2        Q_CAP_DIFFBUS_C0201-DIFF BUS_0A
P5E_CPU0_PE0_TX_DP<14>   U2               R15      SOCKET4677_AZIFS054P001C01-SOCA
P5E_CPU0_PE0_TX_DP<15>   C903             2        Q_CAP_DIFFBUS_C0201-DIFF BUS_0A
P5E_CPU0_PE0_TX_DP<15>   U2               M14      SOCKET4677_AZIFS054P001C01-SOCA
P5E_CPU0_PE1_RX_DN<0>    J37              A18      SCONN168_623403212-SCONN168_6-A
P5E_CPU0_PE1_RX_DN<0>    U2               CN9      SOCKET4677_AZIFS054P001C01-SOCA
P5E_CPU0_PE1_RX_DN<1>    J37              A21      SCONN168_623403212-SCONN168_6-A
P5E_CPU0_PE1_RX_DN<1>    U2               CM10     SOCKET4677_AZIFS054P001C01-SOCA
P5E_CPU0_PE1_RX_DN<2>    J37              A24      SCONN168_623403212-SCONN168_6-A
P5E_CPU0_PE1_RX_DN<2>    U2               CJ9      SOCKET4677_AZIFS054P001C01-SOCA
P5E_CPU0_PE1_RX_DN<3>    J37              A27      SCONN168_623403212-SCONN168_6-A
P5E_CPU0_PE1_RX_DN<3>    U2               CH10     SOCKET4677_AZIFS054P001C01-SOCA
P5E_CPU0_PE1_RX_DN<4>    J37              A31      SCONN168_623403212-SCONN168_6-A
P5E_CPU0_PE1_RX_DN<4>    U2               CE9      SOCKET4677_AZIFS054P001C01-SOCA
P5E_CPU0_PE1_RX_DN<5>    J37              A34      SCONN168_623403212-SCONN168_6-A
P5E_CPU0_PE1_RX_DN<5>    U2               CD10     SOCKET4677_AZIFS054P001C01-SOCA
P5E_CPU0_PE1_RX_DN<6>    J37              A37      SCONN168_623403212-SCONN168_6-A
P5E_CPU0_PE1_RX_DN<6>    U2               CA9      SOCKET4677_AZIFS054P001C01-SOCA
P5E_CPU0_PE1_RX_DN<7>    J37              A40      SCONN168_623403212-SCONN168_6-A
P5E_CPU0_PE1_RX_DN<7>    U2               BY10     SOCKET4677_AZIFS054P001C01-SOCA
P5E_CPU0_PE1_RX_DN<8>    J37              A45      SCONN168_623403212-SCONN168_6-A
P5E_CPU0_PE1_RX_DN<8>    U2               BU9      SOCKET4677_AZIFS054P001C01-SOCA
P5E_CPU0_PE1_RX_DN<9>    J37              A48      SCONN168_623403212-SCONN168_6-A
P5E_CPU0_PE1_RX_DN<9>    U2               BT10     SOCKET4677_AZIFS054P001C01-SOCA
P5E_CPU0_PE1_RX_DN<10>   J37              A51      SCONN168_623403212-SCONN168_6-A
P5E_CPU0_PE1_RX_DN<10>   U2               BN9      SOCKET4677_AZIFS054P001C01-SOCA
P5E_CPU0_PE1_RX_DN<11>   J37              A54      SCONN168_623403212-SCONN168_6-A
P5E_CPU0_PE1_RX_DN<11>   U2               BM10     SOCKET4677_AZIFS054P001C01-SOCA
P5E_CPU0_PE1_RX_DN<12>   J37              A57      SCONN168_623403212-SCONN168_6-A
P5E_CPU0_PE1_RX_DN<12>   U2               BJ9      SOCKET4677_AZIFS054P001C01-SOCA
P5E_CPU0_PE1_RX_DN<13>   J37              A60      SCONN168_623403212-SCONN168_6-A
P5E_CPU0_PE1_RX_DN<13>   U2               BH10     SOCKET4677_AZIFS054P001C01-SOCA
P5E_CPU0_PE1_RX_DN<14>   J37              A63      SCONN168_623403212-SCONN168_6-A
P5E_CPU0_PE1_RX_DN<14>   U2               BE9      SOCKET4677_AZIFS054P001C01-SOCA
P5E_CPU0_PE1_RX_DN<15>   J37              A66      SCONN168_623403212-SCONN168_6-A
P5E_CPU0_PE1_RX_DN<15>   U2               BD10     SOCKET4677_AZIFS054P001C01-SOCA
P5E_CPU0_PE1_RX_DP<0>    J37              A17      SCONN168_623403212-SCONN168_6-A
P5E_CPU0_PE1_RX_DP<0>    U2               CP10     SOCKET4677_AZIFS054P001C01-SOCA
P5E_CPU0_PE1_RX_DP<1>    J37              A20      SCONN168_623403212-SCONN168_6-A
P5E_CPU0_PE1_RX_DP<1>    U2               CL11     SOCKET4677_AZIFS054P001C01-SOCA
P5E_CPU0_PE1_RX_DP<2>    J37              A23      SCONN168_623403212-SCONN168_6-A
P5E_CPU0_PE1_RX_DP<2>    U2               CK10     SOCKET4677_AZIFS054P001C01-SOCA
P5E_CPU0_PE1_RX_DP<3>    J37              A26      SCONN168_623403212-SCONN168_6-A
P5E_CPU0_PE1_RX_DP<3>    U2               CG11     SOCKET4677_AZIFS054P001C01-SOCA
P5E_CPU0_PE1_RX_DP<4>    J37              A30      SCONN168_623403212-SCONN168_6-A
P5E_CPU0_PE1_RX_DP<4>    U2               CF10     SOCKET4677_AZIFS054P001C01-SOCA
P5E_CPU0_PE1_RX_DP<5>    J37              A33      SCONN168_623403212-SCONN168_6-A
P5E_CPU0_PE1_RX_DP<5>    U2               CC11     SOCKET4677_AZIFS054P001C01-SOCA
P5E_CPU0_PE1_RX_DP<6>    J37              A36      SCONN168_623403212-SCONN168_6-A
P5E_CPU0_PE1_RX_DP<6>    U2               CB10     SOCKET4677_AZIFS054P001C01-SOCA
P5E_CPU0_PE1_RX_DP<7>    J37              A39      SCONN168_623403212-SCONN168_6-A
P5E_CPU0_PE1_RX_DP<7>    U2               BW11     SOCKET4677_AZIFS054P001C01-SOCA
P5E_CPU0_PE1_RX_DP<8>    J37              A44      SCONN168_623403212-SCONN168_6-A
P5E_CPU0_PE1_RX_DP<8>    U2               BV10     SOCKET4677_AZIFS054P001C01-SOCA
P5E_CPU0_PE1_RX_DP<9>    J37              A47      SCONN168_623403212-SCONN168_6-A
P5E_CPU0_PE1_RX_DP<9>    U2               BR11     SOCKET4677_AZIFS054P001C01-SOCA
P5E_CPU0_PE1_RX_DP<10>   J37              A50      SCONN168_623403212-SCONN168_6-A
P5E_CPU0_PE1_RX_DP<10>   U2               BP10     SOCKET4677_AZIFS054P001C01-SOCA
P5E_CPU0_PE1_RX_DP<11>   J37              A53      SCONN168_623403212-SCONN168_6-A
P5E_CPU0_PE1_RX_DP<11>   U2               BL11     SOCKET4677_AZIFS054P001C01-SOCA
P5E_CPU0_PE1_RX_DP<12>   J37              A56      SCONN168_623403212-SCONN168_6-A
P5E_CPU0_PE1_RX_DP<12>   U2               BK10     SOCKET4677_AZIFS054P001C01-SOCA
P5E_CPU0_PE1_RX_DP<13>   J37              A59      SCONN168_623403212-SCONN168_6-A
P5E_CPU0_PE1_RX_DP<13>   U2               BG11     SOCKET4677_AZIFS054P001C01-SOCA
P5E_CPU0_PE1_RX_DP<14>   J37              A62      SCONN168_623403212-SCONN168_6-A
P5E_CPU0_PE1_RX_DP<14>   U2               BF10     SOCKET4677_AZIFS054P001C01-SOCA
P5E_CPU0_PE1_RX_DP<15>   J37              A65      SCONN168_623403212-SCONN168_6-A
P5E_CPU0_PE1_RX_DP<15>   U2               BC11     SOCKET4677_AZIFS054P001C01-SOCA
P5E_CPU0_PE1_TX_C_DN<0>  C964             1        Q_CAP_DIFFBUS_C0201-DIFF BUS_0A
P5E_CPU0_PE1_TX_C_DN<0>  J37              B18      SCONN168_623403212-SCONN168_6-A
P5E_CPU0_PE1_TX_C_DN<1>  C962             1        Q_CAP_DIFFBUS_C0201-DIFF BUS_0A
P5E_CPU0_PE1_TX_C_DN<1>  J37              B21      SCONN168_623403212-SCONN168_6-A
P5E_CPU0_PE1_TX_C_DN<2>  C960             1        Q_CAP_DIFFBUS_C0201-DIFF BUS_0A
P5E_CPU0_PE1_TX_C_DN<2>  J37              B24      SCONN168_623403212-SCONN168_6-A
P5E_CPU0_PE1_TX_C_DN<3>  C958             1        Q_CAP_DIFFBUS_C0201-DIFF BUS_0A
P5E_CPU0_PE1_TX_C_DN<3>  J37              B27      SCONN168_623403212-SCONN168_6-A
P5E_CPU0_PE1_TX_C_DN<4>  C956             1        Q_CAP_DIFFBUS_C0201-DIFF BUS_0A
P5E_CPU0_PE1_TX_C_DN<4>  J37              B31      SCONN168_623403212-SCONN168_6-A
P5E_CPU0_PE1_TX_C_DN<5>  C954             1        Q_CAP_DIFFBUS_C0201-DIFF BUS_0A
P5E_CPU0_PE1_TX_C_DN<5>  J37              B34      SCONN168_623403212-SCONN168_6-A
P5E_CPU0_PE1_TX_C_DN<6>  C952             1        Q_CAP_DIFFBUS_C0201-DIFF BUS_0A
P5E_CPU0_PE1_TX_C_DN<6>  J37              B37      SCONN168_623403212-SCONN168_6-A
P5E_CPU0_PE1_TX_C_DN<7>  C950             1        Q_CAP_DIFFBUS_C0201-DIFF BUS_0A
P5E_CPU0_PE1_TX_C_DN<7>  J37              B40      SCONN168_623403212-SCONN168_6-A
P5E_CPU0_PE1_TX_C_DN<8>  C948             1        Q_CAP_DIFFBUS_C0201-DIFF BUS_0A
P5E_CPU0_PE1_TX_C_DN<8>  J37              B45      SCONN168_623403212-SCONN168_6-A
P5E_CPU0_PE1_TX_C_DN<9>  C946             1        Q_CAP_DIFFBUS_C0201-DIFF BUS_0A
P5E_CPU0_PE1_TX_C_DN<9>  J37              B48      SCONN168_623403212-SCONN168_6-A
P5E_CPU0_PE1_TX_C_DN<10> C944             1        Q_CAP_DIFFBUS_C0201-DIFF BUS_0A
P5E_CPU0_PE1_TX_C_DN<10> J37              B51      SCONN168_623403212-SCONN168_6-A
P5E_CPU0_PE1_TX_C_DN<11> C942             1        Q_CAP_DIFFBUS_C0201-DIFF BUS_0A
P5E_CPU0_PE1_TX_C_DN<11> J37              B54      SCONN168_623403212-SCONN168_6-A
P5E_CPU0_PE1_TX_C_DN<12> C940             1        Q_CAP_DIFFBUS_C0201-DIFF BUS_0A
P5E_CPU0_PE1_TX_C_DN<12> J37              B57      SCONN168_623403212-SCONN168_6-A
P5E_CPU0_PE1_TX_C_DN<13> C938             1        Q_CAP_DIFFBUS_C0201-DIFF BUS_0A
P5E_CPU0_PE1_TX_C_DN<13> J37              B60      SCONN168_623403212-SCONN168_6-A
P5E_CPU0_PE1_TX_C_DN<14> C936             1        Q_CAP_DIFFBUS_C0201-DIFF BUS_0A
P5E_CPU0_PE1_TX_C_DN<14> J37              B63      SCONN168_623403212-SCONN168_6-A
P5E_CPU0_PE1_TX_C_DN<15> C934             1        Q_CAP_DIFFBUS_C0201-DIFF BUS_0A
P5E_CPU0_PE1_TX_C_DN<15> J37              B66      SCONN168_623403212-SCONN168_6-A
P5E_CPU0_PE1_TX_C_DP<0>  C965             1        Q_CAP_DIFFBUS_C0201-DIFF BUS_0A
P5E_CPU0_PE1_TX_C_DP<0>  J37              B17      SCONN168_623403212-SCONN168_6-A
P5E_CPU0_PE1_TX_C_DP<1>  C963             1        Q_CAP_DIFFBUS_C0201-DIFF BUS_0A
P5E_CPU0_PE1_TX_C_DP<1>  J37              B20      SCONN168_623403212-SCONN168_6-A
P5E_CPU0_PE1_TX_C_DP<2>  C961             1        Q_CAP_DIFFBUS_C0201-DIFF BUS_0A
P5E_CPU0_PE1_TX_C_DP<2>  J37              B23      SCONN168_623403212-SCONN168_6-A
P5E_CPU0_PE1_TX_C_DP<3>  C959             1        Q_CAP_DIFFBUS_C0201-DIFF BUS_0A
P5E_CPU0_PE1_TX_C_DP<3>  J37              B26      SCONN168_623403212-SCONN168_6-A
P5E_CPU0_PE1_TX_C_DP<4>  C957             1        Q_CAP_DIFFBUS_C0201-DIFF BUS_0A
P5E_CPU0_PE1_TX_C_DP<4>  J37              B30      SCONN168_623403212-SCONN168_6-A
P5E_CPU0_PE1_TX_C_DP<5>  C955             1        Q_CAP_DIFFBUS_C0201-DIFF BUS_0A
P5E_CPU0_PE1_TX_C_DP<5>  J37              B33      SCONN168_623403212-SCONN168_6-A
P5E_CPU0_PE1_TX_C_DP<6>  C953             1        Q_CAP_DIFFBUS_C0201-DIFF BUS_0A
P5E_CPU0_PE1_TX_C_DP<6>  J37              B36      SCONN168_623403212-SCONN168_6-A
P5E_CPU0_PE1_TX_C_DP<7>  C951             1        Q_CAP_DIFFBUS_C0201-DIFF BUS_0A
P5E_CPU0_PE1_TX_C_DP<7>  J37              B39      SCONN168_623403212-SCONN168_6-A
P5E_CPU0_PE1_TX_C_DP<8>  C949             1        Q_CAP_DIFFBUS_C0201-DIFF BUS_0A
P5E_CPU0_PE1_TX_C_DP<8>  J37              B44      SCONN168_623403212-SCONN168_6-A
P5E_CPU0_PE1_TX_C_DP<9>  C947             1        Q_CAP_DIFFBUS_C0201-DIFF BUS_0A
P5E_CPU0_PE1_TX_C_DP<9>  J37              B47      SCONN168_623403212-SCONN168_6-A
P5E_CPU0_PE1_TX_C_DP<10> C945             1        Q_CAP_DIFFBUS_C0201-DIFF BUS_0A
P5E_CPU0_PE1_TX_C_DP<10> J37              B50      SCONN168_623403212-SCONN168_6-A
P5E_CPU0_PE1_TX_C_DP<11> C943             1        Q_CAP_DIFFBUS_C0201-DIFF BUS_0A
P5E_CPU0_PE1_TX_C_DP<11> J37              B53      SCONN168_623403212-SCONN168_6-A
P5E_CPU0_PE1_TX_C_DP<12> C941             1        Q_CAP_DIFFBUS_C0201-DIFF BUS_0A
P5E_CPU0_PE1_TX_C_DP<12> J37              B56      SCONN168_623403212-SCONN168_6-A
P5E_CPU0_PE1_TX_C_DP<13> C939             1        Q_CAP_DIFFBUS_C0201-DIFF BUS_0A
P5E_CPU0_PE1_TX_C_DP<13> J37              B59      SCONN168_623403212-SCONN168_6-A
P5E_CPU0_PE1_TX_C_DP<14> C937             1        Q_CAP_DIFFBUS_C0201-DIFF BUS_0A
P5E_CPU0_PE1_TX_C_DP<14> J37              B62      SCONN168_623403212-SCONN168_6-A
P5E_CPU0_PE1_TX_C_DP<15> C935             1        Q_CAP_DIFFBUS_C0201-DIFF BUS_0A
P5E_CPU0_PE1_TX_C_DP<15> J37              B65      SCONN168_623403212-SCONN168_6-A
P5E_CPU0_PE1_TX_DN<0>    C964             2        Q_CAP_DIFFBUS_C0201-DIFF BUS_0A
P5E_CPU0_PE1_TX_DN<0>    U2               CP14     SOCKET4677_AZIFS054P001C01-SOCA
P5E_CPU0_PE1_TX_DN<1>    C962             2        Q_CAP_DIFFBUS_C0201-DIFF BUS_0A
P5E_CPU0_PE1_TX_DN<1>    U2               CN13     SOCKET4677_AZIFS054P001C01-SOCA
P5E_CPU0_PE1_TX_DN<2>    C960             2        Q_CAP_DIFFBUS_C0201-DIFF BUS_0A
P5E_CPU0_PE1_TX_DN<2>    U2               CK14     SOCKET4677_AZIFS054P001C01-SOCA
P5E_CPU0_PE1_TX_DN<3>    C958             2        Q_CAP_DIFFBUS_C0201-DIFF BUS_0A
P5E_CPU0_PE1_TX_DN<3>    U2               CJ13     SOCKET4677_AZIFS054P001C01-SOCA
P5E_CPU0_PE1_TX_DN<4>    C956             2        Q_CAP_DIFFBUS_C0201-DIFF BUS_0A
P5E_CPU0_PE1_TX_DN<4>    U2               CF14     SOCKET4677_AZIFS054P001C01-SOCA
P5E_CPU0_PE1_TX_DN<5>    C954             2        Q_CAP_DIFFBUS_C0201-DIFF BUS_0A
P5E_CPU0_PE1_TX_DN<5>    U2               CE13     SOCKET4677_AZIFS054P001C01-SOCA
P5E_CPU0_PE1_TX_DN<6>    C952             2        Q_CAP_DIFFBUS_C0201-DIFF BUS_0A
P5E_CPU0_PE1_TX_DN<6>    U2               CB14     SOCKET4677_AZIFS054P001C01-SOCA
P5E_CPU0_PE1_TX_DN<7>    C950             2        Q_CAP_DIFFBUS_C0201-DIFF BUS_0A
P5E_CPU0_PE1_TX_DN<7>    U2               CA13     SOCKET4677_AZIFS054P001C01-SOCA
P5E_CPU0_PE1_TX_DN<8>    C948             2        Q_CAP_DIFFBUS_C0201-DIFF BUS_0A
P5E_CPU0_PE1_TX_DN<8>    U2               BV14     SOCKET4677_AZIFS054P001C01-SOCA
P5E_CPU0_PE1_TX_DN<9>    C946             2        Q_CAP_DIFFBUS_C0201-DIFF BUS_0A
P5E_CPU0_PE1_TX_DN<9>    U2               BU13     SOCKET4677_AZIFS054P001C01-SOCA
P5E_CPU0_PE1_TX_DN<10>   C944             2        Q_CAP_DIFFBUS_C0201-DIFF BUS_0A
P5E_CPU0_PE1_TX_DN<10>   U2               BP14     SOCKET4677_AZIFS054P001C01-SOCA
P5E_CPU0_PE1_TX_DN<11>   C942             2        Q_CAP_DIFFBUS_C0201-DIFF BUS_0A
P5E_CPU0_PE1_TX_DN<11>   U2               BN13     SOCKET4677_AZIFS054P001C01-SOCA
P5E_CPU0_PE1_TX_DN<12>   C940             2        Q_CAP_DIFFBUS_C0201-DIFF BUS_0A
P5E_CPU0_PE1_TX_DN<12>   U2               BK14     SOCKET4677_AZIFS054P001C01-SOCA
P5E_CPU0_PE1_TX_DN<13>   C938             2        Q_CAP_DIFFBUS_C0201-DIFF BUS_0A
P5E_CPU0_PE1_TX_DN<13>   U2               BJ13     SOCKET4677_AZIFS054P001C01-SOCA
P5E_CPU0_PE1_TX_DN<14>   C936             2        Q_CAP_DIFFBUS_C0201-DIFF BUS_0A
P5E_CPU0_PE1_TX_DN<14>   U2               BF14     SOCKET4677_AZIFS054P001C01-SOCA
P5E_CPU0_PE1_TX_DN<15>   C934             2        Q_CAP_DIFFBUS_C0201-DIFF BUS_0A
P5E_CPU0_PE1_TX_DN<15>   U2               BE13     SOCKET4677_AZIFS054P001C01-SOCA
P5E_CPU0_PE1_TX_DP<0>    C965             2        Q_CAP_DIFFBUS_C0201-DIFF BUS_0A
P5E_CPU0_PE1_TX_DP<0>    U2               CR15     SOCKET4677_AZIFS054P001C01-SOCA
P5E_CPU0_PE1_TX_DP<1>    C963             2        Q_CAP_DIFFBUS_C0201-DIFF BUS_0A
P5E_CPU0_PE1_TX_DP<1>    U2               CM14     SOCKET4677_AZIFS054P001C01-SOCA
P5E_CPU0_PE1_TX_DP<2>    C961             2        Q_CAP_DIFFBUS_C0201-DIFF BUS_0A
P5E_CPU0_PE1_TX_DP<2>    U2               CL15     SOCKET4677_AZIFS054P001C01-SOCA
P5E_CPU0_PE1_TX_DP<3>    C959             2        Q_CAP_DIFFBUS_C0201-DIFF BUS_0A
P5E_CPU0_PE1_TX_DP<3>    U2               CH14     SOCKET4677_AZIFS054P001C01-SOCA
P5E_CPU0_PE1_TX_DP<4>    C957             2        Q_CAP_DIFFBUS_C0201-DIFF BUS_0A
P5E_CPU0_PE1_TX_DP<4>    U2               CG15     SOCKET4677_AZIFS054P001C01-SOCA
P5E_CPU0_PE1_TX_DP<5>    C955             2        Q_CAP_DIFFBUS_C0201-DIFF BUS_0A
P5E_CPU0_PE1_TX_DP<5>    U2               CD14     SOCKET4677_AZIFS054P001C01-SOCA
P5E_CPU0_PE1_TX_DP<6>    C953             2        Q_CAP_DIFFBUS_C0201-DIFF BUS_0A
P5E_CPU0_PE1_TX_DP<6>    U2               CC15     SOCKET4677_AZIFS054P001C01-SOCA
P5E_CPU0_PE1_TX_DP<7>    C951             2        Q_CAP_DIFFBUS_C0201-DIFF BUS_0A
P5E_CPU0_PE1_TX_DP<7>    U2               BY14     SOCKET4677_AZIFS054P001C01-SOCA
P5E_CPU0_PE1_TX_DP<8>    C949             2        Q_CAP_DIFFBUS_C0201-DIFF BUS_0A
P5E_CPU0_PE1_TX_DP<8>    U2               BW15     SOCKET4677_AZIFS054P001C01-SOCA
P5E_CPU0_PE1_TX_DP<9>    C947             2        Q_CAP_DIFFBUS_C0201-DIFF BUS_0A
P5E_CPU0_PE1_TX_DP<9>    U2               BT14     SOCKET4677_AZIFS054P001C01-SOCA
P5E_CPU0_PE1_TX_DP<10>   C945             2        Q_CAP_DIFFBUS_C0201-DIFF BUS_0A
P5E_CPU0_PE1_TX_DP<10>   U2               BR15     SOCKET4677_AZIFS054P001C01-SOCA
P5E_CPU0_PE1_TX_DP<11>   C943             2        Q_CAP_DIFFBUS_C0201-DIFF BUS_0A
P5E_CPU0_PE1_TX_DP<11>   U2               BM14     SOCKET4677_AZIFS054P001C01-SOCA
P5E_CPU0_PE1_TX_DP<12>   C941             2        Q_CAP_DIFFBUS_C0201-DIFF BUS_0A
P5E_CPU0_PE1_TX_DP<12>   U2               BL15     SOCKET4677_AZIFS054P001C01-SOCA
P5E_CPU0_PE1_TX_DP<13>   C939             2        Q_CAP_DIFFBUS_C0201-DIFF BUS_0A
P5E_CPU0_PE1_TX_DP<13>   U2               BH14     SOCKET4677_AZIFS054P001C01-SOCA
P5E_CPU0_PE1_TX_DP<14>   C937             2        Q_CAP_DIFFBUS_C0201-DIFF BUS_0A
P5E_CPU0_PE1_TX_DP<14>   U2               BG15     SOCKET4677_AZIFS054P001C01-SOCA
P5E_CPU0_PE1_TX_DP<15>   C935             2        Q_CAP_DIFFBUS_C0201-DIFF BUS_0A
P5E_CPU0_PE1_TX_DP<15>   U2               BD14     SOCKET4677_AZIFS054P001C01-SOCA
P5E_CPU0_PE2_RX_DN<0>    J55              B66      SCONN140_G64V3431BHR-SCONN140_A
P5E_CPU0_PE2_RX_DN<0>    U2               CU9      SOCKET4677_AZIFS054P001C01-SOCA
P5E_CPU0_PE2_RX_DN<1>    J55              B63      SCONN140_G64V3431BHR-SCONN140_A
P5E_CPU0_PE2_RX_DN<1>    U2               CY10     SOCKET4677_AZIFS054P001C01-SOCA
P5E_CPU0_PE2_RX_DN<2>    J55              B60      SCONN140_G64V3431BHR-SCONN140_A
P5E_CPU0_PE2_RX_DN<2>    U2               DA9      SOCKET4677_AZIFS054P001C01-SOCA
P5E_CPU0_PE2_RX_DN<3>    J55              B57      SCONN140_G64V3431BHR-SCONN140_A
P5E_CPU0_PE2_RX_DN<3>    U2               DD10     SOCKET4677_AZIFS054P001C01-SOCA
P5E_CPU0_PE2_RX_DN<4>    J55              B54      SCONN140_G64V3431BHR-SCONN140_A
P5E_CPU0_PE2_RX_DN<4>    U2               DE9      SOCKET4677_AZIFS054P001C01-SOCA
P5E_CPU0_PE2_RX_DN<5>    J55              B51      SCONN140_G64V3431BHR-SCONN140_A
P5E_CPU0_PE2_RX_DN<5>    U2               DH10     SOCKET4677_AZIFS054P001C01-SOCA
P5E_CPU0_PE2_RX_DN<6>    J55              B48      SCONN140_G64V3431BHR-SCONN140_A
P5E_CPU0_PE2_RX_DN<6>    U2               DJ9      SOCKET4677_AZIFS054P001C01-SOCA
P5E_CPU0_PE2_RX_DN<7>    J55              B45      SCONN140_G64V3431BHR-SCONN140_A
P5E_CPU0_PE2_RX_DN<7>    U2               DM10     SOCKET4677_AZIFS054P001C01-SOCA
P5E_CPU0_PE2_RX_DN<8>    J55              B40      SCONN140_G64V3431BHR-SCONN140_A
P5E_CPU0_PE2_RX_DN<8>    U2               DN9      SOCKET4677_AZIFS054P001C01-SOCA
P5E_CPU0_PE2_RX_DN<9>    J55              B37      SCONN140_G64V3431BHR-SCONN140_A
P5E_CPU0_PE2_RX_DN<9>    U2               DT10     SOCKET4677_AZIFS054P001C01-SOCA
P5E_CPU0_PE2_RX_DN<10>   J55              B34      SCONN140_G64V3431BHR-SCONN140_A
P5E_CPU0_PE2_RX_DN<10>   U2               DU9      SOCKET4677_AZIFS054P001C01-SOCA
P5E_CPU0_PE2_RX_DN<11>   J55              B31      SCONN140_G64V3431BHR-SCONN140_A
P5E_CPU0_PE2_RX_DN<11>   U2               DY10     SOCKET4677_AZIFS054P001C01-SOCA
P5E_CPU0_PE2_RX_DN<12>   J55              B27      SCONN140_G64V3431BHR-SCONN140_A
P5E_CPU0_PE2_RX_DN<12>   U2               EA9      SOCKET4677_AZIFS054P001C01-SOCA
P5E_CPU0_PE2_RX_DN<13>   J55              B24      SCONN140_G64V3431BHR-SCONN140_A
P5E_CPU0_PE2_RX_DN<13>   U2               ED10     SOCKET4677_AZIFS054P001C01-SOCA
P5E_CPU0_PE2_RX_DN<14>   J55              B21      SCONN140_G64V3431BHR-SCONN140_A
P5E_CPU0_PE2_RX_DN<14>   U2               EE9      SOCKET4677_AZIFS054P001C01-SOCA
P5E_CPU0_PE2_RX_DN<15>   J55              B18      SCONN140_G64V3431BHR-SCONN140_A
P5E_CPU0_PE2_RX_DN<15>   U2               EH10     SOCKET4677_AZIFS054P001C01-SOCA
P5E_CPU0_PE2_RX_DP<0>    J55              B65      SCONN140_G64V3431BHR-SCONN140_A
P5E_CPU0_PE2_RX_DP<0>    U2               CV10     SOCKET4677_AZIFS054P001C01-SOCA
P5E_CPU0_PE2_RX_DP<1>    J55              B62      SCONN140_G64V3431BHR-SCONN140_A
P5E_CPU0_PE2_RX_DP<1>    U2               CW11     SOCKET4677_AZIFS054P001C01-SOCA
P5E_CPU0_PE2_RX_DP<2>    J55              B59      SCONN140_G64V3431BHR-SCONN140_A
P5E_CPU0_PE2_RX_DP<2>    U2               DB10     SOCKET4677_AZIFS054P001C01-SOCA
P5E_CPU0_PE2_RX_DP<3>    J55              B56      SCONN140_G64V3431BHR-SCONN140_A
P5E_CPU0_PE2_RX_DP<3>    U2               DC11     SOCKET4677_AZIFS054P001C01-SOCA
P5E_CPU0_PE2_RX_DP<4>    J55              B53      SCONN140_G64V3431BHR-SCONN140_A
P5E_CPU0_PE2_RX_DP<4>    U2               DF10     SOCKET4677_AZIFS054P001C01-SOCA
P5E_CPU0_PE2_RX_DP<5>    J55              B50      SCONN140_G64V3431BHR-SCONN140_A
P5E_CPU0_PE2_RX_DP<5>    U2               DG11     SOCKET4677_AZIFS054P001C01-SOCA
P5E_CPU0_PE2_RX_DP<6>    J55              B47      SCONN140_G64V3431BHR-SCONN140_A
P5E_CPU0_PE2_RX_DP<6>    U2               DK10     SOCKET4677_AZIFS054P001C01-SOCA
P5E_CPU0_PE2_RX_DP<7>    J55              B44      SCONN140_G64V3431BHR-SCONN140_A
P5E_CPU0_PE2_RX_DP<7>    U2               DL11     SOCKET4677_AZIFS054P001C01-SOCA
P5E_CPU0_PE2_RX_DP<8>    J55              B39      SCONN140_G64V3431BHR-SCONN140_A
P5E_CPU0_PE2_RX_DP<8>    U2               DP10     SOCKET4677_AZIFS054P001C01-SOCA
P5E_CPU0_PE2_RX_DP<9>    J55              B36      SCONN140_G64V3431BHR-SCONN140_A
P5E_CPU0_PE2_RX_DP<9>    U2               DR11     SOCKET4677_AZIFS054P001C01-SOCA
P5E_CPU0_PE2_RX_DP<10>   J55              B33      SCONN140_G64V3431BHR-SCONN140_A
P5E_CPU0_PE2_RX_DP<10>   U2               DV10     SOCKET4677_AZIFS054P001C01-SOCA
P5E_CPU0_PE2_RX_DP<11>   J55              B30      SCONN140_G64V3431BHR-SCONN140_A
P5E_CPU0_PE2_RX_DP<11>   U2               DW11     SOCKET4677_AZIFS054P001C01-SOCA
P5E_CPU0_PE2_RX_DP<12>   J55              B26      SCONN140_G64V3431BHR-SCONN140_A
P5E_CPU0_PE2_RX_DP<12>   U2               EB10     SOCKET4677_AZIFS054P001C01-SOCA
P5E_CPU0_PE2_RX_DP<13>   J55              B23      SCONN140_G64V3431BHR-SCONN140_A
P5E_CPU0_PE2_RX_DP<13>   U2               EC11     SOCKET4677_AZIFS054P001C01-SOCA
P5E_CPU0_PE2_RX_DP<14>   J55              B20      SCONN140_G64V3431BHR-SCONN140_A
P5E_CPU0_PE2_RX_DP<14>   U2               EF10     SOCKET4677_AZIFS054P001C01-SOCA
P5E_CPU0_PE2_RX_DP<15>   J55              B17      SCONN140_G64V3431BHR-SCONN140_A
P5E_CPU0_PE2_RX_DP<15>   U2               EG11     SOCKET4677_AZIFS054P001C01-SOCA
P5E_CPU0_PE2_TX_C_DN<0>  C868             1        Q_CAP_DIFFBUS_C0201-DIFF BUS_0A
P5E_CPU0_PE2_TX_C_DN<0>  J55              A66      SCONN140_G64V3431BHR-SCONN140_A
P5E_CPU0_PE2_TX_C_DN<1>  C866             1        Q_CAP_DIFFBUS_C0201-DIFF BUS_0A
P5E_CPU0_PE2_TX_C_DN<1>  J55              A63      SCONN140_G64V3431BHR-SCONN140_A
P5E_CPU0_PE2_TX_C_DN<2>  C864             1        Q_CAP_DIFFBUS_C0201-DIFF BUS_0A
P5E_CPU0_PE2_TX_C_DN<2>  J55              A60      SCONN140_G64V3431BHR-SCONN140_A
P5E_CPU0_PE2_TX_C_DN<3>  C862             1        Q_CAP_DIFFBUS_C0201-DIFF BUS_0A
P5E_CPU0_PE2_TX_C_DN<3>  J55              A57      SCONN140_G64V3431BHR-SCONN140_A
P5E_CPU0_PE2_TX_C_DN<4>  C860             1        Q_CAP_DIFFBUS_C0201-DIFF BUS_0A
P5E_CPU0_PE2_TX_C_DN<4>  J55              A54      SCONN140_G64V3431BHR-SCONN140_A
P5E_CPU0_PE2_TX_C_DN<5>  C858             1        Q_CAP_DIFFBUS_C0201-DIFF BUS_0A
P5E_CPU0_PE2_TX_C_DN<5>  J55              A51      SCONN140_G64V3431BHR-SCONN140_A
P5E_CPU0_PE2_TX_C_DN<6>  C856             1        Q_CAP_DIFFBUS_C0201-DIFF BUS_0A
P5E_CPU0_PE2_TX_C_DN<6>  J55              A48      SCONN140_G64V3431BHR-SCONN140_A
P5E_CPU0_PE2_TX_C_DN<7>  C854             1        Q_CAP_DIFFBUS_C0201-DIFF BUS_0A
P5E_CPU0_PE2_TX_C_DN<7>  J55              A45      SCONN140_G64V3431BHR-SCONN140_A
P5E_CPU0_PE2_TX_C_DN<8>  C852             1        Q_CAP_DIFFBUS_C0201-DIFF BUS_0A
P5E_CPU0_PE2_TX_C_DN<8>  J55              A40      SCONN140_G64V3431BHR-SCONN140_A
P5E_CPU0_PE2_TX_C_DN<9>  C850             1        Q_CAP_DIFFBUS_C0201-DIFF BUS_0A
P5E_CPU0_PE2_TX_C_DN<9>  J55              A37      SCONN140_G64V3431BHR-SCONN140_A
P5E_CPU0_PE2_TX_C_DN<10> C848             1        Q_CAP_DIFFBUS_C0201-DIFF BUS_0A
P5E_CPU0_PE2_TX_C_DN<10> J55              A34      SCONN140_G64V3431BHR-SCONN140_A
P5E_CPU0_PE2_TX_C_DN<11> C846             1        Q_CAP_DIFFBUS_C0201-DIFF BUS_0A
P5E_CPU0_PE2_TX_C_DN<11> J55              A31      SCONN140_G64V3431BHR-SCONN140_A
P5E_CPU0_PE2_TX_C_DN<12> C844             1        Q_CAP_DIFFBUS_C0201-DIFF BUS_0A
P5E_CPU0_PE2_TX_C_DN<12> J55              A27      SCONN140_G64V3431BHR-SCONN140_A
P5E_CPU0_PE2_TX_C_DN<13> C842             1        Q_CAP_DIFFBUS_C0201-DIFF BUS_0A
P5E_CPU0_PE2_TX_C_DN<13> J55              A24      SCONN140_G64V3431BHR-SCONN140_A
P5E_CPU0_PE2_TX_C_DN<14> C840             1        Q_CAP_DIFFBUS_C0201-DIFF BUS_0A
P5E_CPU0_PE2_TX_C_DN<14> J55              A21      SCONN140_G64V3431BHR-SCONN140_A
P5E_CPU0_PE2_TX_C_DN<15> C838             1        Q_CAP_DIFFBUS_C0201-DIFF BUS_0A
P5E_CPU0_PE2_TX_C_DN<15> J55              A18      SCONN140_G64V3431BHR-SCONN140_A
P5E_CPU0_PE2_TX_C_DP<0>  C869             1        Q_CAP_DIFFBUS_C0201-DIFF BUS_0A
P5E_CPU0_PE2_TX_C_DP<0>  J55              A65      SCONN140_G64V3431BHR-SCONN140_A
P5E_CPU0_PE2_TX_C_DP<1>  C867             1        Q_CAP_DIFFBUS_C0201-DIFF BUS_0A
P5E_CPU0_PE2_TX_C_DP<1>  J55              A62      SCONN140_G64V3431BHR-SCONN140_A
P5E_CPU0_PE2_TX_C_DP<2>  C865             1        Q_CAP_DIFFBUS_C0201-DIFF BUS_0A
P5E_CPU0_PE2_TX_C_DP<2>  J55              A59      SCONN140_G64V3431BHR-SCONN140_A
P5E_CPU0_PE2_TX_C_DP<3>  C863             1        Q_CAP_DIFFBUS_C0201-DIFF BUS_0A
P5E_CPU0_PE2_TX_C_DP<3>  J55              A56      SCONN140_G64V3431BHR-SCONN140_A
P5E_CPU0_PE2_TX_C_DP<4>  C861             1        Q_CAP_DIFFBUS_C0201-DIFF BUS_0A
P5E_CPU0_PE2_TX_C_DP<4>  J55              A53      SCONN140_G64V3431BHR-SCONN140_A
P5E_CPU0_PE2_TX_C_DP<5>  C859             1        Q_CAP_DIFFBUS_C0201-DIFF BUS_0A
P5E_CPU0_PE2_TX_C_DP<5>  J55              A50      SCONN140_G64V3431BHR-SCONN140_A
P5E_CPU0_PE2_TX_C_DP<6>  C857             1        Q_CAP_DIFFBUS_C0201-DIFF BUS_0A
P5E_CPU0_PE2_TX_C_DP<6>  J55              A47      SCONN140_G64V3431BHR-SCONN140_A
P5E_CPU0_PE2_TX_C_DP<7>  C855             1        Q_CAP_DIFFBUS_C0201-DIFF BUS_0A
P5E_CPU0_PE2_TX_C_DP<7>  J55              A44      SCONN140_G64V3431BHR-SCONN140_A
P5E_CPU0_PE2_TX_C_DP<8>  C853             1        Q_CAP_DIFFBUS_C0201-DIFF BUS_0A
P5E_CPU0_PE2_TX_C_DP<8>  J55              A39      SCONN140_G64V3431BHR-SCONN140_A
P5E_CPU0_PE2_TX_C_DP<9>  C851             1        Q_CAP_DIFFBUS_C0201-DIFF BUS_0A
P5E_CPU0_PE2_TX_C_DP<9>  J55              A36      SCONN140_G64V3431BHR-SCONN140_A
P5E_CPU0_PE2_TX_C_DP<10> C849             1        Q_CAP_DIFFBUS_C0201-DIFF BUS_0A
P5E_CPU0_PE2_TX_C_DP<10> J55              A33      SCONN140_G64V3431BHR-SCONN140_A
P5E_CPU0_PE2_TX_C_DP<11> C847             1        Q_CAP_DIFFBUS_C0201-DIFF BUS_0A
P5E_CPU0_PE2_TX_C_DP<11> J55              A30      SCONN140_G64V3431BHR-SCONN140_A
P5E_CPU0_PE2_TX_C_DP<12> C845             1        Q_CAP_DIFFBUS_C0201-DIFF BUS_0A
P5E_CPU0_PE2_TX_C_DP<12> J55              A26      SCONN140_G64V3431BHR-SCONN140_A
P5E_CPU0_PE2_TX_C_DP<13> C843             1        Q_CAP_DIFFBUS_C0201-DIFF BUS_0A
P5E_CPU0_PE2_TX_C_DP<13> J55              A23      SCONN140_G64V3431BHR-SCONN140_A
P5E_CPU0_PE2_TX_C_DP<14> C841             1        Q_CAP_DIFFBUS_C0201-DIFF BUS_0A
P5E_CPU0_PE2_TX_C_DP<14> J55              A20      SCONN140_G64V3431BHR-SCONN140_A
P5E_CPU0_PE2_TX_C_DP<15> C839             1        Q_CAP_DIFFBUS_C0201-DIFF BUS_0A
P5E_CPU0_PE2_TX_C_DP<15> J55              A17      SCONN140_G64V3431BHR-SCONN140_A
P5E_CPU0_PE2_TX_DN<0>    C868             2        Q_CAP_DIFFBUS_C0201-DIFF BUS_0A
P5E_CPU0_PE2_TX_DN<0>    U2               CT14     SOCKET4677_AZIFS054P001C01-SOCA
P5E_CPU0_PE2_TX_DN<1>    C866             2        Q_CAP_DIFFBUS_C0201-DIFF BUS_0A
P5E_CPU0_PE2_TX_DN<1>    U2               CW15     SOCKET4677_AZIFS054P001C01-SOCA
P5E_CPU0_PE2_TX_DN<2>    C864             2        Q_CAP_DIFFBUS_C0201-DIFF BUS_0A
P5E_CPU0_PE2_TX_DN<2>    U2               CY14     SOCKET4677_AZIFS054P001C01-SOCA
P5E_CPU0_PE2_TX_DN<3>    C862             2        Q_CAP_DIFFBUS_C0201-DIFF BUS_0A
P5E_CPU0_PE2_TX_DN<3>    U2               DC15     SOCKET4677_AZIFS054P001C01-SOCA
P5E_CPU0_PE2_TX_DN<4>    C860             2        Q_CAP_DIFFBUS_C0201-DIFF BUS_0A
P5E_CPU0_PE2_TX_DN<4>    U2               DD14     SOCKET4677_AZIFS054P001C01-SOCA
P5E_CPU0_PE2_TX_DN<5>    C858             2        Q_CAP_DIFFBUS_C0201-DIFF BUS_0A
P5E_CPU0_PE2_TX_DN<5>    U2               DG15     SOCKET4677_AZIFS054P001C01-SOCA
P5E_CPU0_PE2_TX_DN<6>    C856             2        Q_CAP_DIFFBUS_C0201-DIFF BUS_0A
P5E_CPU0_PE2_TX_DN<6>    U2               DH14     SOCKET4677_AZIFS054P001C01-SOCA
P5E_CPU0_PE2_TX_DN<7>    C854             2        Q_CAP_DIFFBUS_C0201-DIFF BUS_0A
P5E_CPU0_PE2_TX_DN<7>    U2               DL15     SOCKET4677_AZIFS054P001C01-SOCA
P5E_CPU0_PE2_TX_DN<8>    C852             2        Q_CAP_DIFFBUS_C0201-DIFF BUS_0A
P5E_CPU0_PE2_TX_DN<8>    U2               DM14     SOCKET4677_AZIFS054P001C01-SOCA
P5E_CPU0_PE2_TX_DN<9>    C850             2        Q_CAP_DIFFBUS_C0201-DIFF BUS_0A
P5E_CPU0_PE2_TX_DN<9>    U2               DR15     SOCKET4677_AZIFS054P001C01-SOCA
P5E_CPU0_PE2_TX_DN<10>   C848             2        Q_CAP_DIFFBUS_C0201-DIFF BUS_0A
P5E_CPU0_PE2_TX_DN<10>   U2               DT14     SOCKET4677_AZIFS054P001C01-SOCA
P5E_CPU0_PE2_TX_DN<11>   C846             2        Q_CAP_DIFFBUS_C0201-DIFF BUS_0A
P5E_CPU0_PE2_TX_DN<11>   U2               DW15     SOCKET4677_AZIFS054P001C01-SOCA
P5E_CPU0_PE2_TX_DN<12>   C844             2        Q_CAP_DIFFBUS_C0201-DIFF BUS_0A
P5E_CPU0_PE2_TX_DN<12>   U2               DY14     SOCKET4677_AZIFS054P001C01-SOCA
P5E_CPU0_PE2_TX_DN<13>   C842             2        Q_CAP_DIFFBUS_C0201-DIFF BUS_0A
P5E_CPU0_PE2_TX_DN<13>   U2               EC15     SOCKET4677_AZIFS054P001C01-SOCA
P5E_CPU0_PE2_TX_DN<14>   C840             2        Q_CAP_DIFFBUS_C0201-DIFF BUS_0A
P5E_CPU0_PE2_TX_DN<14>   U2               ED14     SOCKET4677_AZIFS054P001C01-SOCA
P5E_CPU0_PE2_TX_DN<15>   C838             2        Q_CAP_DIFFBUS_C0201-DIFF BUS_0A
P5E_CPU0_PE2_TX_DN<15>   U2               EG15     SOCKET4677_AZIFS054P001C01-SOCA
P5E_CPU0_PE2_TX_DP<0>    C869             2        Q_CAP_DIFFBUS_C0201-DIFF BUS_0A
P5E_CPU0_PE2_TX_DP<0>    U2               CU13     SOCKET4677_AZIFS054P001C01-SOCA
P5E_CPU0_PE2_TX_DP<1>    C867             2        Q_CAP_DIFFBUS_C0201-DIFF BUS_0A
P5E_CPU0_PE2_TX_DP<1>    U2               CV14     SOCKET4677_AZIFS054P001C01-SOCA
P5E_CPU0_PE2_TX_DP<2>    C865             2        Q_CAP_DIFFBUS_C0201-DIFF BUS_0A
P5E_CPU0_PE2_TX_DP<2>    U2               DA13     SOCKET4677_AZIFS054P001C01-SOCA
P5E_CPU0_PE2_TX_DP<3>    C863             2        Q_CAP_DIFFBUS_C0201-DIFF BUS_0A
P5E_CPU0_PE2_TX_DP<3>    U2               DB14     SOCKET4677_AZIFS054P001C01-SOCA
P5E_CPU0_PE2_TX_DP<4>    C861             2        Q_CAP_DIFFBUS_C0201-DIFF BUS_0A
P5E_CPU0_PE2_TX_DP<4>    U2               DE13     SOCKET4677_AZIFS054P001C01-SOCA
P5E_CPU0_PE2_TX_DP<5>    C859             2        Q_CAP_DIFFBUS_C0201-DIFF BUS_0A
P5E_CPU0_PE2_TX_DP<5>    U2               DF14     SOCKET4677_AZIFS054P001C01-SOCA
P5E_CPU0_PE2_TX_DP<6>    C857             2        Q_CAP_DIFFBUS_C0201-DIFF BUS_0A
P5E_CPU0_PE2_TX_DP<6>    U2               DJ13     SOCKET4677_AZIFS054P001C01-SOCA
P5E_CPU0_PE2_TX_DP<7>    C855             2        Q_CAP_DIFFBUS_C0201-DIFF BUS_0A
P5E_CPU0_PE2_TX_DP<7>    U2               DK14     SOCKET4677_AZIFS054P001C01-SOCA
P5E_CPU0_PE2_TX_DP<8>    C853             2        Q_CAP_DIFFBUS_C0201-DIFF BUS_0A
P5E_CPU0_PE2_TX_DP<8>    U2               DN13     SOCKET4677_AZIFS054P001C01-SOCA
P5E_CPU0_PE2_TX_DP<9>    C851             2        Q_CAP_DIFFBUS_C0201-DIFF BUS_0A
P5E_CPU0_PE2_TX_DP<9>    U2               DP14     SOCKET4677_AZIFS054P001C01-SOCA
P5E_CPU0_PE2_TX_DP<10>   C849             2        Q_CAP_DIFFBUS_C0201-DIFF BUS_0A
P5E_CPU0_PE2_TX_DP<10>   U2               DU13     SOCKET4677_AZIFS054P001C01-SOCA
P5E_CPU0_PE2_TX_DP<11>   C847             2        Q_CAP_DIFFBUS_C0201-DIFF BUS_0A
P5E_CPU0_PE2_TX_DP<11>   U2               DV14     SOCKET4677_AZIFS054P001C01-SOCA
P5E_CPU0_PE2_TX_DP<12>   C845             2        Q_CAP_DIFFBUS_C0201-DIFF BUS_0A
P5E_CPU0_PE2_TX_DP<12>   U2               EA13     SOCKET4677_AZIFS054P001C01-SOCA
P5E_CPU0_PE2_TX_DP<13>   C843             2        Q_CAP_DIFFBUS_C0201-DIFF BUS_0A
P5E_CPU0_PE2_TX_DP<13>   U2               EB14     SOCKET4677_AZIFS054P001C01-SOCA
P5E_CPU0_PE2_TX_DP<14>   C841             2        Q_CAP_DIFFBUS_C0201-DIFF BUS_0A
P5E_CPU0_PE2_TX_DP<14>   U2               EE13     SOCKET4677_AZIFS054P001C01-SOCA
P5E_CPU0_PE2_TX_DP<15>   C839             2        Q_CAP_DIFFBUS_C0201-DIFF BUS_0A
P5E_CPU0_PE2_TX_DP<15>   U2               EF14     SOCKET4677_AZIFS054P001C01-SOCA
P5E_CPU0_PE3_RX_DN<0>    J62              A17      SCONN84_123318136-SCONN84_1-23A
P5E_CPU0_PE3_RX_DN<0>    U2               EH89     SOCKET4677_AZIFS054P001C01-SOCA
P5E_CPU0_PE3_RX_DN<1>    J62              A20      SCONN84_123318136-SCONN84_1-23A
P5E_CPU0_PE3_RX_DN<1>    U2               ED91     SOCKET4677_AZIFS054P001C01-SOCA
P5E_CPU0_PE3_RX_DN<2>    J62              A23      SCONN84_123318136-SCONN84_1-23A
P5E_CPU0_PE3_RX_DN<2>    U2               EC90     SOCKET4677_AZIFS054P001C01-SOCA
P5E_CPU0_PE3_RX_DN<3>    J62              A26      SCONN84_123318136-SCONN84_1-23A
P5E_CPU0_PE3_RX_DN<3>    U2               DY91     SOCKET4677_AZIFS054P001C01-SOCA
P5E_CPU0_PE3_RX_DN<4>    J62              A30      SCONN84_123318136-SCONN84_1-23A
P5E_CPU0_PE3_RX_DN<4>    U2               DV89     SOCKET4677_AZIFS054P001C01-SOCA
P5E_CPU0_PE3_RX_DN<5>    J62              A33      SCONN84_123318136-SCONN84_1-23A
P5E_CPU0_PE3_RX_DN<5>    U2               DU90     SOCKET4677_AZIFS054P001C01-SOCA
P5E_CPU0_PE3_RX_DN<6>    J62              A36      SCONN84_123318136-SCONN84_1-23A
P5E_CPU0_PE3_RX_DN<6>    U2               DP89     SOCKET4677_AZIFS054P001C01-SOCA
P5E_CPU0_PE3_RX_DN<7>    J62              A39      SCONN84_123318136-SCONN84_1-23A
P5E_CPU0_PE3_RX_DN<7>    U2               DN90     SOCKET4677_AZIFS054P001C01-SOCA
P5E_CPU0_PE3_RX_DN<8>    J87              A17      SCONN84_123318136-SCONN84_1-23A
P5E_CPU0_PE3_RX_DN<8>    U2               DL90     SOCKET4677_AZIFS054P001C01-SOCA
P5E_CPU0_PE3_RX_DN<9>    J87              A20      SCONN84_123318136-SCONN84_1-23A
P5E_CPU0_PE3_RX_DN<9>    U2               DH91     SOCKET4677_AZIFS054P001C01-SOCA
P5E_CPU0_PE3_RX_DN<10>   J87              A23      SCONN84_123318136-SCONN84_1-23A
P5E_CPU0_PE3_RX_DN<10>   U2               DG90     SOCKET4677_AZIFS054P001C01-SOCA
P5E_CPU0_PE3_RX_DN<11>   J87              A26      SCONN84_123318136-SCONN84_1-23A
P5E_CPU0_PE3_RX_DN<11>   U2               DD91     SOCKET4677_AZIFS054P001C01-SOCA
P5E_CPU0_PE3_RX_DN<12>   J87              A30      SCONN84_123318136-SCONN84_1-23A
P5E_CPU0_PE3_RX_DN<12>   U2               DB89     SOCKET4677_AZIFS054P001C01-SOCA
P5E_CPU0_PE3_RX_DN<13>   J87              A33      SCONN84_123318136-SCONN84_1-23A
P5E_CPU0_PE3_RX_DN<13>   U2               DA90     SOCKET4677_AZIFS054P001C01-SOCA
P5E_CPU0_PE3_RX_DN<14>   J87              A36      SCONN84_123318136-SCONN84_1-23A
P5E_CPU0_PE3_RX_DN<14>   U2               CV89     SOCKET4677_AZIFS054P001C01-SOCA
P5E_CPU0_PE3_RX_DN<15>   J87              A39      SCONN84_123318136-SCONN84_1-23A
P5E_CPU0_PE3_RX_DN<15>   U2               CU90     SOCKET4677_AZIFS054P001C01-SOCA
P5E_CPU0_PE3_RX_DP<0>    J62              A18      SCONN84_123318136-SCONN84_1-23A
P5E_CPU0_PE3_RX_DP<0>    U2               EJ90     SOCKET4677_AZIFS054P001C01-SOCA
P5E_CPU0_PE3_RX_DP<1>    J62              A21      SCONN84_123318136-SCONN84_1-23A
P5E_CPU0_PE3_RX_DP<1>    U2               EE90     SOCKET4677_AZIFS054P001C01-SOCA
P5E_CPU0_PE3_RX_DP<2>    J62              A24      SCONN84_123318136-SCONN84_1-23A
P5E_CPU0_PE3_RX_DP<2>    U2               EB89     SOCKET4677_AZIFS054P001C01-SOCA
P5E_CPU0_PE3_RX_DP<3>    J62              A27      SCONN84_123318136-SCONN84_1-23A
P5E_CPU0_PE3_RX_DP<3>    U2               EA90     SOCKET4677_AZIFS054P001C01-SOCA
P5E_CPU0_PE3_RX_DP<4>    J62              A31      SCONN84_123318136-SCONN84_1-23A
P5E_CPU0_PE3_RX_DP<4>    U2               DW90     SOCKET4677_AZIFS054P001C01-SOCA
P5E_CPU0_PE3_RX_DP<5>    J62              A34      SCONN84_123318136-SCONN84_1-23A
P5E_CPU0_PE3_RX_DP<5>    U2               DT91     SOCKET4677_AZIFS054P001C01-SOCA
P5E_CPU0_PE3_RX_DP<6>    J62              A37      SCONN84_123318136-SCONN84_1-23A
P5E_CPU0_PE3_RX_DP<6>    U2               DR90     SOCKET4677_AZIFS054P001C01-SOCA
P5E_CPU0_PE3_RX_DP<7>    J62              A40      SCONN84_123318136-SCONN84_1-23A
P5E_CPU0_PE3_RX_DP<7>    U2               DM91     SOCKET4677_AZIFS054P001C01-SOCA
P5E_CPU0_PE3_RX_DP<8>    J87              A18      SCONN84_123318136-SCONN84_1-23A
P5E_CPU0_PE3_RX_DP<8>    U2               DK89     SOCKET4677_AZIFS054P001C01-SOCA
P5E_CPU0_PE3_RX_DP<9>    J87              A21      SCONN84_123318136-SCONN84_1-23A
P5E_CPU0_PE3_RX_DP<9>    U2               DJ90     SOCKET4677_AZIFS054P001C01-SOCA
P5E_CPU0_PE3_RX_DP<10>   J87              A24      SCONN84_123318136-SCONN84_1-23A
P5E_CPU0_PE3_RX_DP<10>   U2               DF89     SOCKET4677_AZIFS054P001C01-SOCA
P5E_CPU0_PE3_RX_DP<11>   J87              A27      SCONN84_123318136-SCONN84_1-23A
P5E_CPU0_PE3_RX_DP<11>   U2               DE90     SOCKET4677_AZIFS054P001C01-SOCA
P5E_CPU0_PE3_RX_DP<12>   J87              A31      SCONN84_123318136-SCONN84_1-23A
P5E_CPU0_PE3_RX_DP<12>   U2               DC90     SOCKET4677_AZIFS054P001C01-SOCA
P5E_CPU0_PE3_RX_DP<13>   J87              A34      SCONN84_123318136-SCONN84_1-23A
P5E_CPU0_PE3_RX_DP<13>   U2               CY91     SOCKET4677_AZIFS054P001C01-SOCA
P5E_CPU0_PE3_RX_DP<14>   J87              A37      SCONN84_123318136-SCONN84_1-23A
P5E_CPU0_PE3_RX_DP<14>   U2               CW90     SOCKET4677_AZIFS054P001C01-SOCA
P5E_CPU0_PE3_RX_DP<15>   J87              A40      SCONN84_123318136-SCONN84_1-23A
P5E_CPU0_PE3_RX_DP<15>   U2               CT91     SOCKET4677_AZIFS054P001C01-SOCA
P5E_CPU0_PE3_TX_C_DN<0>  C900             1        Q_CAP_DIFFBUS_C0201-DIFF BUS_0A
P5E_CPU0_PE3_TX_C_DN<0>  J62              B17      SCONN84_123318136-SCONN84_1-23A
P5E_CPU0_PE3_TX_C_DN<1>  C898             1        Q_CAP_DIFFBUS_C0201-DIFF BUS_0A
P5E_CPU0_PE3_TX_C_DN<1>  J62              B20      SCONN84_123318136-SCONN84_1-23A
P5E_CPU0_PE3_TX_C_DN<2>  C896             1        Q_CAP_DIFFBUS_C0201-DIFF BUS_0A
P5E_CPU0_PE3_TX_C_DN<2>  J62              B23      SCONN84_123318136-SCONN84_1-23A
P5E_CPU0_PE3_TX_C_DN<3>  C894             1        Q_CAP_DIFFBUS_C0201-DIFF BUS_0A
P5E_CPU0_PE3_TX_C_DN<3>  J62              B26      SCONN84_123318136-SCONN84_1-23A
P5E_CPU0_PE3_TX_C_DN<4>  C892             1        Q_CAP_DIFFBUS_C0201-DIFF BUS_0A
P5E_CPU0_PE3_TX_C_DN<4>  J62              B30      SCONN84_123318136-SCONN84_1-23A
P5E_CPU0_PE3_TX_C_DN<5>  C890             1        Q_CAP_DIFFBUS_C0201-DIFF BUS_0A
P5E_CPU0_PE3_TX_C_DN<5>  J62              B33      SCONN84_123318136-SCONN84_1-23A
P5E_CPU0_PE3_TX_C_DN<6>  C888             1        Q_CAP_DIFFBUS_C0201-DIFF BUS_0A
P5E_CPU0_PE3_TX_C_DN<6>  J62              B36      SCONN84_123318136-SCONN84_1-23A
P5E_CPU0_PE3_TX_C_DN<7>  C886             1        Q_CAP_DIFFBUS_C0201-DIFF BUS_0A
P5E_CPU0_PE3_TX_C_DN<7>  J62              B39      SCONN84_123318136-SCONN84_1-23A
P5E_CPU0_PE3_TX_C_DN<8>  C884             1        Q_CAP_DIFFBUS_C0201-DIFF BUS_0A
P5E_CPU0_PE3_TX_C_DN<8>  J87              B17      SCONN84_123318136-SCONN84_1-23A
P5E_CPU0_PE3_TX_C_DN<9>  C882             1        Q_CAP_DIFFBUS_C0201-DIFF BUS_0A
P5E_CPU0_PE3_TX_C_DN<9>  J87              B20      SCONN84_123318136-SCONN84_1-23A
P5E_CPU0_PE3_TX_C_DN<10> C880             1        Q_CAP_DIFFBUS_C0201-DIFF BUS_0A
P5E_CPU0_PE3_TX_C_DN<10> J87              B23      SCONN84_123318136-SCONN84_1-23A
P5E_CPU0_PE3_TX_C_DN<11> C878             1        Q_CAP_DIFFBUS_C0201-DIFF BUS_0A
P5E_CPU0_PE3_TX_C_DN<11> J87              B26      SCONN84_123318136-SCONN84_1-23A
P5E_CPU0_PE3_TX_C_DN<12> C876             1        Q_CAP_DIFFBUS_C0201-DIFF BUS_0A
P5E_CPU0_PE3_TX_C_DN<12> J87              B30      SCONN84_123318136-SCONN84_1-23A
P5E_CPU0_PE3_TX_C_DN<13> C874             1        Q_CAP_DIFFBUS_C0201-DIFF BUS_0A
P5E_CPU0_PE3_TX_C_DN<13> J87              B33      SCONN84_123318136-SCONN84_1-23A
P5E_CPU0_PE3_TX_C_DN<14> C872             1        Q_CAP_DIFFBUS_C0201-DIFF BUS_0A
P5E_CPU0_PE3_TX_C_DN<14> J87              B36      SCONN84_123318136-SCONN84_1-23A
P5E_CPU0_PE3_TX_C_DN<15> C870             1        Q_CAP_DIFFBUS_C0201-DIFF BUS_0A
P5E_CPU0_PE3_TX_C_DN<15> J87              B39      SCONN84_123318136-SCONN84_1-23A
P5E_CPU0_PE3_TX_C_DP<0>  C901             1        Q_CAP_DIFFBUS_C0201-DIFF BUS_0A
P5E_CPU0_PE3_TX_C_DP<0>  J62              B18      SCONN84_123318136-SCONN84_1-23A
P5E_CPU0_PE3_TX_C_DP<1>  C899             1        Q_CAP_DIFFBUS_C0201-DIFF BUS_0A
P5E_CPU0_PE3_TX_C_DP<1>  J62              B21      SCONN84_123318136-SCONN84_1-23A
P5E_CPU0_PE3_TX_C_DP<2>  C897             1        Q_CAP_DIFFBUS_C0201-DIFF BUS_0A
P5E_CPU0_PE3_TX_C_DP<2>  J62              B24      SCONN84_123318136-SCONN84_1-23A
P5E_CPU0_PE3_TX_C_DP<3>  C895             1        Q_CAP_DIFFBUS_C0201-DIFF BUS_0A
P5E_CPU0_PE3_TX_C_DP<3>  J62              B27      SCONN84_123318136-SCONN84_1-23A
P5E_CPU0_PE3_TX_C_DP<4>  C893             1        Q_CAP_DIFFBUS_C0201-DIFF BUS_0A
P5E_CPU0_PE3_TX_C_DP<4>  J62              B31      SCONN84_123318136-SCONN84_1-23A
P5E_CPU0_PE3_TX_C_DP<5>  C891             1        Q_CAP_DIFFBUS_C0201-DIFF BUS_0A
P5E_CPU0_PE3_TX_C_DP<5>  J62              B34      SCONN84_123318136-SCONN84_1-23A
P5E_CPU0_PE3_TX_C_DP<6>  C889             1        Q_CAP_DIFFBUS_C0201-DIFF BUS_0A
P5E_CPU0_PE3_TX_C_DP<6>  J62              B37      SCONN84_123318136-SCONN84_1-23A
P5E_CPU0_PE3_TX_C_DP<7>  C887             1        Q_CAP_DIFFBUS_C0201-DIFF BUS_0A
P5E_CPU0_PE3_TX_C_DP<7>  J62              B40      SCONN84_123318136-SCONN84_1-23A
P5E_CPU0_PE3_TX_C_DP<8>  C885             1        Q_CAP_DIFFBUS_C0201-DIFF BUS_0A
P5E_CPU0_PE3_TX_C_DP<8>  J87              B18      SCONN84_123318136-SCONN84_1-23A
P5E_CPU0_PE3_TX_C_DP<9>  C883             1        Q_CAP_DIFFBUS_C0201-DIFF BUS_0A
P5E_CPU0_PE3_TX_C_DP<9>  J87              B21      SCONN84_123318136-SCONN84_1-23A
P5E_CPU0_PE3_TX_C_DP<10> C881             1        Q_CAP_DIFFBUS_C0201-DIFF BUS_0A
P5E_CPU0_PE3_TX_C_DP<10> J87              B24      SCONN84_123318136-SCONN84_1-23A
P5E_CPU0_PE3_TX_C_DP<11> C879             1        Q_CAP_DIFFBUS_C0201-DIFF BUS_0A
P5E_CPU0_PE3_TX_C_DP<11> J87              B27      SCONN84_123318136-SCONN84_1-23A
P5E_CPU0_PE3_TX_C_DP<12> C877             1        Q_CAP_DIFFBUS_C0201-DIFF BUS_0A
P5E_CPU0_PE3_TX_C_DP<12> J87              B31      SCONN84_123318136-SCONN84_1-23A
P5E_CPU0_PE3_TX_C_DP<13> C875             1        Q_CAP_DIFFBUS_C0201-DIFF BUS_0A
P5E_CPU0_PE3_TX_C_DP<13> J87              B34      SCONN84_123318136-SCONN84_1-23A
P5E_CPU0_PE3_TX_C_DP<14> C873             1        Q_CAP_DIFFBUS_C0201-DIFF BUS_0A
P5E_CPU0_PE3_TX_C_DP<14> J87              B37      SCONN84_123318136-SCONN84_1-23A
P5E_CPU0_PE3_TX_C_DP<15> C871             1        Q_CAP_DIFFBUS_C0201-DIFF BUS_0A
P5E_CPU0_PE3_TX_C_DP<15> J87              B40      SCONN84_123318136-SCONN84_1-23A
P5E_CPU0_PE3_TX_DN<0>    C900             2        Q_CAP_DIFFBUS_C0201-DIFF BUS_0A
P5E_CPU0_PE3_TX_DN<0>    U2               EE86     SOCKET4677_AZIFS054P001C01-SOCA
P5E_CPU0_PE3_TX_DN<1>    C898             2        Q_CAP_DIFFBUS_C0201-DIFF BUS_0A
P5E_CPU0_PE3_TX_DN<1>    U2               EB85     SOCKET4677_AZIFS054P001C01-SOCA
P5E_CPU0_PE3_TX_DN<2>    C896             2        Q_CAP_DIFFBUS_C0201-DIFF BUS_0A
P5E_CPU0_PE3_TX_DN<2>    U2               DY87     SOCKET4677_AZIFS054P001C01-SOCA
P5E_CPU0_PE3_TX_DN<3>    C894             2        Q_CAP_DIFFBUS_C0201-DIFF BUS_0A
P5E_CPU0_PE3_TX_DN<3>    U2               DV85     SOCKET4677_AZIFS054P001C01-SOCA
P5E_CPU0_PE3_TX_DN<4>    C892             2        Q_CAP_DIFFBUS_C0201-DIFF BUS_0A
P5E_CPU0_PE3_TX_DN<4>    U2               DT87     SOCKET4677_AZIFS054P001C01-SOCA
P5E_CPU0_PE3_TX_DN<5>    C890             2        Q_CAP_DIFFBUS_C0201-DIFF BUS_0A
P5E_CPU0_PE3_TX_DN<5>    U2               DP85     SOCKET4677_AZIFS054P001C01-SOCA
P5E_CPU0_PE3_TX_DN<6>    C888             2        Q_CAP_DIFFBUS_C0201-DIFF BUS_0A
P5E_CPU0_PE3_TX_DN<6>    U2               DM87     SOCKET4677_AZIFS054P001C01-SOCA
P5E_CPU0_PE3_TX_DN<7>    C886             2        Q_CAP_DIFFBUS_C0201-DIFF BUS_0A
P5E_CPU0_PE3_TX_DN<7>    U2               DK85     SOCKET4677_AZIFS054P001C01-SOCA
P5E_CPU0_PE3_TX_DN<8>    C884             2        Q_CAP_DIFFBUS_C0201-DIFF BUS_0A
P5E_CPU0_PE3_TX_DN<8>    U2               DH87     SOCKET4677_AZIFS054P001C01-SOCA
P5E_CPU0_PE3_TX_DN<9>    C882             2        Q_CAP_DIFFBUS_C0201-DIFF BUS_0A
P5E_CPU0_PE3_TX_DN<9>    U2               DF85     SOCKET4677_AZIFS054P001C01-SOCA
P5E_CPU0_PE3_TX_DN<10>   C880             2        Q_CAP_DIFFBUS_C0201-DIFF BUS_0A
P5E_CPU0_PE3_TX_DN<10>   U2               DD87     SOCKET4677_AZIFS054P001C01-SOCA
P5E_CPU0_PE3_TX_DN<11>   C878             2        Q_CAP_DIFFBUS_C0201-DIFF BUS_0A
P5E_CPU0_PE3_TX_DN<11>   U2               DB85     SOCKET4677_AZIFS054P001C01-SOCA
P5E_CPU0_PE3_TX_DN<12>   C876             2        Q_CAP_DIFFBUS_C0201-DIFF BUS_0A
P5E_CPU0_PE3_TX_DN<12>   U2               CY87     SOCKET4677_AZIFS054P001C01-SOCA
P5E_CPU0_PE3_TX_DN<13>   C874             2        Q_CAP_DIFFBUS_C0201-DIFF BUS_0A
P5E_CPU0_PE3_TX_DN<13>   U2               CV85     SOCKET4677_AZIFS054P001C01-SOCA
P5E_CPU0_PE3_TX_DN<14>   C872             2        Q_CAP_DIFFBUS_C0201-DIFF BUS_0A
P5E_CPU0_PE3_TX_DN<14>   U2               CT87     SOCKET4677_AZIFS054P001C01-SOCA
P5E_CPU0_PE3_TX_DN<15>   C870             2        Q_CAP_DIFFBUS_C0201-DIFF BUS_0A
P5E_CPU0_PE3_TX_DN<15>   U2               CP85     SOCKET4677_AZIFS054P001C01-SOCA
P5E_CPU0_PE3_TX_DP<0>    C901             2        Q_CAP_DIFFBUS_C0201-DIFF BUS_0A
P5E_CPU0_PE3_TX_DP<0>    U2               ED87     SOCKET4677_AZIFS054P001C01-SOCA
P5E_CPU0_PE3_TX_DP<1>    C899             2        Q_CAP_DIFFBUS_C0201-DIFF BUS_0A
P5E_CPU0_PE3_TX_DP<1>    U2               EC86     SOCKET4677_AZIFS054P001C01-SOCA
P5E_CPU0_PE3_TX_DP<2>    C897             2        Q_CAP_DIFFBUS_C0201-DIFF BUS_0A
P5E_CPU0_PE3_TX_DP<2>    U2               EA86     SOCKET4677_AZIFS054P001C01-SOCA
P5E_CPU0_PE3_TX_DP<3>    C895             2        Q_CAP_DIFFBUS_C0201-DIFF BUS_0A
P5E_CPU0_PE3_TX_DP<3>    U2               DW86     SOCKET4677_AZIFS054P001C01-SOCA
P5E_CPU0_PE3_TX_DP<4>    C893             2        Q_CAP_DIFFBUS_C0201-DIFF BUS_0A
P5E_CPU0_PE3_TX_DP<4>    U2               DU86     SOCKET4677_AZIFS054P001C01-SOCA
P5E_CPU0_PE3_TX_DP<5>    C891             2        Q_CAP_DIFFBUS_C0201-DIFF BUS_0A
P5E_CPU0_PE3_TX_DP<5>    U2               DR86     SOCKET4677_AZIFS054P001C01-SOCA
P5E_CPU0_PE3_TX_DP<6>    C889             2        Q_CAP_DIFFBUS_C0201-DIFF BUS_0A
P5E_CPU0_PE3_TX_DP<6>    U2               DN86     SOCKET4677_AZIFS054P001C01-SOCA
P5E_CPU0_PE3_TX_DP<7>    C887             2        Q_CAP_DIFFBUS_C0201-DIFF BUS_0A
P5E_CPU0_PE3_TX_DP<7>    U2               DL86     SOCKET4677_AZIFS054P001C01-SOCA
P5E_CPU0_PE3_TX_DP<8>    C885             2        Q_CAP_DIFFBUS_C0201-DIFF BUS_0A
P5E_CPU0_PE3_TX_DP<8>    U2               DJ86     SOCKET4677_AZIFS054P001C01-SOCA
P5E_CPU0_PE3_TX_DP<9>    C883             2        Q_CAP_DIFFBUS_C0201-DIFF BUS_0A
P5E_CPU0_PE3_TX_DP<9>    U2               DG86     SOCKET4677_AZIFS054P001C01-SOCA
P5E_CPU0_PE3_TX_DP<10>   C881             2        Q_CAP_DIFFBUS_C0201-DIFF BUS_0A
P5E_CPU0_PE3_TX_DP<10>   U2               DE86     SOCKET4677_AZIFS054P001C01-SOCA
P5E_CPU0_PE3_TX_DP<11>   C879             2        Q_CAP_DIFFBUS_C0201-DIFF BUS_0A
P5E_CPU0_PE3_TX_DP<11>   U2               DC86     SOCKET4677_AZIFS054P001C01-SOCA
P5E_CPU0_PE3_TX_DP<12>   C877             2        Q_CAP_DIFFBUS_C0201-DIFF BUS_0A
P5E_CPU0_PE3_TX_DP<12>   U2               DA86     SOCKET4677_AZIFS054P001C01-SOCA
P5E_CPU0_PE3_TX_DP<13>   C875             2        Q_CAP_DIFFBUS_C0201-DIFF BUS_0A
P5E_CPU0_PE3_TX_DP<13>   U2               CW86     SOCKET4677_AZIFS054P001C01-SOCA
P5E_CPU0_PE3_TX_DP<14>   C873             2        Q_CAP_DIFFBUS_C0201-DIFF BUS_0A
P5E_CPU0_PE3_TX_DP<14>   U2               CU86     SOCKET4677_AZIFS054P001C01-SOCA
P5E_CPU0_PE3_TX_DP<15>   C871             2        Q_CAP_DIFFBUS_C0201-DIFF BUS_0A
P5E_CPU0_PE3_TX_DP<15>   U2               CR86     SOCKET4677_AZIFS054P001C01-SOCA
P5E_CPU0_PE4_RX_DN<0>    J33              A39      SCONN84_123318136-SCONN84_1-23A
P5E_CPU0_PE4_RX_DN<0>    U2               BB89     SOCKET4677_AZIFS054P001C01-SOCA
P5E_CPU0_PE4_RX_DN<1>    J33              A37      SCONN84_123318136-SCONN84_1-23A
P5E_CPU0_PE4_RX_DN<1>    U2               AY91     SOCKET4677_AZIFS054P001C01-SOCA
P5E_CPU0_PE4_RX_DN<2>    J33              A33      SCONN84_123318136-SCONN84_1-23A
P5E_CPU0_PE4_RX_DN<2>    U2               AV89     SOCKET4677_AZIFS054P001C01-SOCA
P5E_CPU0_PE4_RX_DN<3>    J33              A30      SCONN84_123318136-SCONN84_1-23A
P5E_CPU0_PE4_RX_DN<3>    U2               AT91     SOCKET4677_AZIFS054P001C01-SOCA
P5E_CPU0_PE4_RX_DN<4>    J33              A26      SCONN84_123318136-SCONN84_1-23A
P5E_CPU0_PE4_RX_DN<4>    U2               AP89     SOCKET4677_AZIFS054P001C01-SOCA
P5E_CPU0_PE4_RX_DN<5>    J33              A24      SCONN84_123318136-SCONN84_1-23A
P5E_CPU0_PE4_RX_DN<5>    U2               AM91     SOCKET4677_AZIFS054P001C01-SOCA
P5E_CPU0_PE4_RX_DN<6>    J33              A20      SCONN84_123318136-SCONN84_1-23A
P5E_CPU0_PE4_RX_DN<6>    U2               AK89     SOCKET4677_AZIFS054P001C01-SOCA
P5E_CPU0_PE4_RX_DN<7>    J33              A17      SCONN84_123318136-SCONN84_1-23A
P5E_CPU0_PE4_RX_DN<7>    U2               AH91     SOCKET4677_AZIFS054P001C01-SOCA
P5E_CPU0_PE4_RX_DN<8>    J34              A39      SCONN84_123318136-SCONN84_1-23A
P5E_CPU0_PE4_RX_DN<8>    U2               AF89     SOCKET4677_AZIFS054P001C01-SOCA
P5E_CPU0_PE4_RX_DN<9>    J34              A36      SCONN84_123318136-SCONN84_1-23A
P5E_CPU0_PE4_RX_DN<9>    U2               AD91     SOCKET4677_AZIFS054P001C01-SOCA
P5E_CPU0_PE4_RX_DN<10>   J34              A33      SCONN84_123318136-SCONN84_1-23A
P5E_CPU0_PE4_RX_DN<10>   U2               AB89     SOCKET4677_AZIFS054P001C01-SOCA
P5E_CPU0_PE4_RX_DN<11>   J34              A30      SCONN84_123318136-SCONN84_1-23A
P5E_CPU0_PE4_RX_DN<11>   U2               Y91      SOCKET4677_AZIFS054P001C01-SOCA
P5E_CPU0_PE4_RX_DN<12>   J34              A26      SCONN84_123318136-SCONN84_1-23A
P5E_CPU0_PE4_RX_DN<12>   U2               V89      SOCKET4677_AZIFS054P001C01-SOCA
P5E_CPU0_PE4_RX_DN<13>   J34              A23      SCONN84_123318136-SCONN84_1-23A
P5E_CPU0_PE4_RX_DN<13>   U2               T91      SOCKET4677_AZIFS054P001C01-SOCA
P5E_CPU0_PE4_RX_DN<14>   J34              A20      SCONN84_123318136-SCONN84_1-23A
P5E_CPU0_PE4_RX_DN<14>   U2               P89      SOCKET4677_AZIFS054P001C01-SOCA
P5E_CPU0_PE4_RX_DN<15>   J34              A17      SCONN84_123318136-SCONN84_1-23A
P5E_CPU0_PE4_RX_DN<15>   U2               J90      SOCKET4677_AZIFS054P001C01-SOCA
P5E_CPU0_PE4_RX_DP<0>    J33              A40      SCONN84_123318136-SCONN84_1-23A
P5E_CPU0_PE4_RX_DP<0>    U2               BA90     SOCKET4677_AZIFS054P001C01-SOCA
P5E_CPU0_PE4_RX_DP<1>    J33              A36      SCONN84_123318136-SCONN84_1-23A
P5E_CPU0_PE4_RX_DP<1>    U2               AW90     SOCKET4677_AZIFS054P001C01-SOCA
P5E_CPU0_PE4_RX_DP<2>    J33              A34      SCONN84_123318136-SCONN84_1-23A
P5E_CPU0_PE4_RX_DP<2>    U2               AU90     SOCKET4677_AZIFS054P001C01-SOCA
P5E_CPU0_PE4_RX_DP<3>    J33              A31      SCONN84_123318136-SCONN84_1-23A
P5E_CPU0_PE4_RX_DP<3>    U2               AR90     SOCKET4677_AZIFS054P001C01-SOCA
P5E_CPU0_PE4_RX_DP<4>    J33              A27      SCONN84_123318136-SCONN84_1-23A
P5E_CPU0_PE4_RX_DP<4>    U2               AN90     SOCKET4677_AZIFS054P001C01-SOCA
P5E_CPU0_PE4_RX_DP<5>    J33              A23      SCONN84_123318136-SCONN84_1-23A
P5E_CPU0_PE4_RX_DP<5>    U2               AL90     SOCKET4677_AZIFS054P001C01-SOCA
P5E_CPU0_PE4_RX_DP<6>    J33              A21      SCONN84_123318136-SCONN84_1-23A
P5E_CPU0_PE4_RX_DP<6>    U2               AJ90     SOCKET4677_AZIFS054P001C01-SOCA
P5E_CPU0_PE4_RX_DP<7>    J33              A18      SCONN84_123318136-SCONN84_1-23A
P5E_CPU0_PE4_RX_DP<7>    U2               AG90     SOCKET4677_AZIFS054P001C01-SOCA
P5E_CPU0_PE4_RX_DP<8>    J34              A40      SCONN84_123318136-SCONN84_1-23A
P5E_CPU0_PE4_RX_DP<8>    U2               AE90     SOCKET4677_AZIFS054P001C01-SOCA
P5E_CPU0_PE4_RX_DP<9>    J34              A37      SCONN84_123318136-SCONN84_1-23A
P5E_CPU0_PE4_RX_DP<9>    U2               AC90     SOCKET4677_AZIFS054P001C01-SOCA
P5E_CPU0_PE4_RX_DP<10>   J34              A34      SCONN84_123318136-SCONN84_1-23A
P5E_CPU0_PE4_RX_DP<10>   U2               AA90     SOCKET4677_AZIFS054P001C01-SOCA
P5E_CPU0_PE4_RX_DP<11>   J34              A31      SCONN84_123318136-SCONN84_1-23A
P5E_CPU0_PE4_RX_DP<11>   U2               W90      SOCKET4677_AZIFS054P001C01-SOCA
P5E_CPU0_PE4_RX_DP<12>   J34              A27      SCONN84_123318136-SCONN84_1-23A
P5E_CPU0_PE4_RX_DP<12>   U2               U90      SOCKET4677_AZIFS054P001C01-SOCA
P5E_CPU0_PE4_RX_DP<13>   J34              A24      SCONN84_123318136-SCONN84_1-23A
P5E_CPU0_PE4_RX_DP<13>   U2               R90      SOCKET4677_AZIFS054P001C01-SOCA
P5E_CPU0_PE4_RX_DP<14>   J34              A21      SCONN84_123318136-SCONN84_1-23A
P5E_CPU0_PE4_RX_DP<14>   U2               N90      SOCKET4677_AZIFS054P001C01-SOCA
P5E_CPU0_PE4_RX_DP<15>   J34              A18      SCONN84_123318136-SCONN84_1-23A
P5E_CPU0_PE4_RX_DP<15>   U2               K89      SOCKET4677_AZIFS054P001C01-SOCA
P5E_CPU0_PE4_TX_C_DN<0>  C1578            1        Q_CAP_DIFFBUS_C0201-DIFF BUS_0A
P5E_CPU0_PE4_TX_C_DN<0>  J33              B40      SCONN84_123318136-SCONN84_1-23A
P5E_CPU0_PE4_TX_C_DN<1>  C1576            1        Q_CAP_DIFFBUS_C0201-DIFF BUS_0A
P5E_CPU0_PE4_TX_C_DN<1>  J33              B37      SCONN84_123318136-SCONN84_1-23A
P5E_CPU0_PE4_TX_C_DN<2>  C1574            1        Q_CAP_DIFFBUS_C0201-DIFF BUS_0A
P5E_CPU0_PE4_TX_C_DN<2>  J33              B34      SCONN84_123318136-SCONN84_1-23A
P5E_CPU0_PE4_TX_C_DN<3>  C1572            1        Q_CAP_DIFFBUS_C0201-DIFF BUS_0A
P5E_CPU0_PE4_TX_C_DN<3>  J33              B31      SCONN84_123318136-SCONN84_1-23A
P5E_CPU0_PE4_TX_C_DN<4>  C1570            1        Q_CAP_DIFFBUS_C0201-DIFF BUS_0A
P5E_CPU0_PE4_TX_C_DN<4>  J33              B27      SCONN84_123318136-SCONN84_1-23A
P5E_CPU0_PE4_TX_C_DN<5>  C1568            1        Q_CAP_DIFFBUS_C0201-DIFF BUS_0A
P5E_CPU0_PE4_TX_C_DN<5>  J33              B24      SCONN84_123318136-SCONN84_1-23A
P5E_CPU0_PE4_TX_C_DN<6>  C1566            1        Q_CAP_DIFFBUS_C0201-DIFF BUS_0A
P5E_CPU0_PE4_TX_C_DN<6>  J33              B21      SCONN84_123318136-SCONN84_1-23A
P5E_CPU0_PE4_TX_C_DN<7>  C1564            1        Q_CAP_DIFFBUS_C0201-DIFF BUS_0A
P5E_CPU0_PE4_TX_C_DN<7>  J33              B18      SCONN84_123318136-SCONN84_1-23A
P5E_CPU0_PE4_TX_C_DN<8>  C1562            1        Q_CAP_DIFFBUS_C0201-DIFF BUS_0A
P5E_CPU0_PE4_TX_C_DN<8>  J34              B40      SCONN84_123318136-SCONN84_1-23A
P5E_CPU0_PE4_TX_C_DN<9>  C1560            1        Q_CAP_DIFFBUS_C0201-DIFF BUS_0A
P5E_CPU0_PE4_TX_C_DN<9>  J34              B37      SCONN84_123318136-SCONN84_1-23A
P5E_CPU0_PE4_TX_C_DN<10> C1558            1        Q_CAP_DIFFBUS_C0201-DIFF BUS_0A
P5E_CPU0_PE4_TX_C_DN<10> J34              B34      SCONN84_123318136-SCONN84_1-23A
P5E_CPU0_PE4_TX_C_DN<11> C1556            1        Q_CAP_DIFFBUS_C0201-DIFF BUS_0A
P5E_CPU0_PE4_TX_C_DN<11> J34              B31      SCONN84_123318136-SCONN84_1-23A
P5E_CPU0_PE4_TX_C_DN<12> C1554            1        Q_CAP_DIFFBUS_C0201-DIFF BUS_0A
P5E_CPU0_PE4_TX_C_DN<12> J34              B27      SCONN84_123318136-SCONN84_1-23A
P5E_CPU0_PE4_TX_C_DN<13> C1552            1        Q_CAP_DIFFBUS_C0201-DIFF BUS_0A
P5E_CPU0_PE4_TX_C_DN<13> J34              B24      SCONN84_123318136-SCONN84_1-23A
P5E_CPU0_PE4_TX_C_DN<14> C1550            1        Q_CAP_DIFFBUS_C0201-DIFF BUS_0A
P5E_CPU0_PE4_TX_C_DN<14> J34              B21      SCONN84_123318136-SCONN84_1-23A
P5E_CPU0_PE4_TX_C_DN<15> C1548            1        Q_CAP_DIFFBUS_C0201-DIFF BUS_0A
P5E_CPU0_PE4_TX_C_DN<15> J34              B18      SCONN84_123318136-SCONN84_1-23A
P5E_CPU0_PE4_TX_C_DP<0>  C1579            1        Q_CAP_DIFFBUS_C0201-DIFF BUS_0A
P5E_CPU0_PE4_TX_C_DP<0>  J33              B39      SCONN84_123318136-SCONN84_1-23A
P5E_CPU0_PE4_TX_C_DP<1>  C1577            1        Q_CAP_DIFFBUS_C0201-DIFF BUS_0A
P5E_CPU0_PE4_TX_C_DP<1>  J33              B36      SCONN84_123318136-SCONN84_1-23A
P5E_CPU0_PE4_TX_C_DP<2>  C1575            1        Q_CAP_DIFFBUS_C0201-DIFF BUS_0A
P5E_CPU0_PE4_TX_C_DP<2>  J33              B33      SCONN84_123318136-SCONN84_1-23A
P5E_CPU0_PE4_TX_C_DP<3>  C1573            1        Q_CAP_DIFFBUS_C0201-DIFF BUS_0A
P5E_CPU0_PE4_TX_C_DP<3>  J33              B30      SCONN84_123318136-SCONN84_1-23A
P5E_CPU0_PE4_TX_C_DP<4>  C1571            1        Q_CAP_DIFFBUS_C0201-DIFF BUS_0A
P5E_CPU0_PE4_TX_C_DP<4>  J33              B26      SCONN84_123318136-SCONN84_1-23A
P5E_CPU0_PE4_TX_C_DP<5>  C1569            1        Q_CAP_DIFFBUS_C0201-DIFF BUS_0A
P5E_CPU0_PE4_TX_C_DP<5>  J33              B23      SCONN84_123318136-SCONN84_1-23A
P5E_CPU0_PE4_TX_C_DP<6>  C1567            1        Q_CAP_DIFFBUS_C0201-DIFF BUS_0A
P5E_CPU0_PE4_TX_C_DP<6>  J33              B20      SCONN84_123318136-SCONN84_1-23A
P5E_CPU0_PE4_TX_C_DP<7>  C1565            1        Q_CAP_DIFFBUS_C0201-DIFF BUS_0A
P5E_CPU0_PE4_TX_C_DP<7>  J33              B17      SCONN84_123318136-SCONN84_1-23A
P5E_CPU0_PE4_TX_C_DP<8>  C1563            1        Q_CAP_DIFFBUS_C0201-DIFF BUS_0A
P5E_CPU0_PE4_TX_C_DP<8>  J34              B39      SCONN84_123318136-SCONN84_1-23A
P5E_CPU0_PE4_TX_C_DP<9>  C1561            1        Q_CAP_DIFFBUS_C0201-DIFF BUS_0A
P5E_CPU0_PE4_TX_C_DP<9>  J34              B36      SCONN84_123318136-SCONN84_1-23A
P5E_CPU0_PE4_TX_C_DP<10> C1559            1        Q_CAP_DIFFBUS_C0201-DIFF BUS_0A
P5E_CPU0_PE4_TX_C_DP<10> J34              B33      SCONN84_123318136-SCONN84_1-23A
P5E_CPU0_PE4_TX_C_DP<11> C1557            1        Q_CAP_DIFFBUS_C0201-DIFF BUS_0A
P5E_CPU0_PE4_TX_C_DP<11> J34              B30      SCONN84_123318136-SCONN84_1-23A
P5E_CPU0_PE4_TX_C_DP<12> C1555            1        Q_CAP_DIFFBUS_C0201-DIFF BUS_0A
P5E_CPU0_PE4_TX_C_DP<12> J34              B26      SCONN84_123318136-SCONN84_1-23A
P5E_CPU0_PE4_TX_C_DP<13> C1553            1        Q_CAP_DIFFBUS_C0201-DIFF BUS_0A
P5E_CPU0_PE4_TX_C_DP<13> J34              B23      SCONN84_123318136-SCONN84_1-23A
P5E_CPU0_PE4_TX_C_DP<14> C1551            1        Q_CAP_DIFFBUS_C0201-DIFF BUS_0A
P5E_CPU0_PE4_TX_C_DP<14> J34              B20      SCONN84_123318136-SCONN84_1-23A
P5E_CPU0_PE4_TX_C_DP<15> C1549            1        Q_CAP_DIFFBUS_C0201-DIFF BUS_0A
P5E_CPU0_PE4_TX_C_DP<15> J34              B17      SCONN84_123318136-SCONN84_1-23A
P5E_CPU0_PE4_TX_DN<0>    C1578            2        Q_CAP_DIFFBUS_C0201-DIFF BUS_0A
P5E_CPU0_PE4_TX_DN<0>    U2               BA86     SOCKET4677_AZIFS054P001C01-SOCA
P5E_CPU0_PE4_TX_DN<1>    C1576            2        Q_CAP_DIFFBUS_C0201-DIFF BUS_0A
P5E_CPU0_PE4_TX_DN<1>    U2               AW86     SOCKET4677_AZIFS054P001C01-SOCA
P5E_CPU0_PE4_TX_DN<2>    C1574            2        Q_CAP_DIFFBUS_C0201-DIFF BUS_0A
P5E_CPU0_PE4_TX_DN<2>    U2               AU86     SOCKET4677_AZIFS054P001C01-SOCA
P5E_CPU0_PE4_TX_DN<3>    C1572            2        Q_CAP_DIFFBUS_C0201-DIFF BUS_0A
P5E_CPU0_PE4_TX_DN<3>    U2               AR86     SOCKET4677_AZIFS054P001C01-SOCA
P5E_CPU0_PE4_TX_DN<4>    C1570            2        Q_CAP_DIFFBUS_C0201-DIFF BUS_0A
P5E_CPU0_PE4_TX_DN<4>    U2               AP85     SOCKET4677_AZIFS054P001C01-SOCA
P5E_CPU0_PE4_TX_DN<5>    C1568            2        Q_CAP_DIFFBUS_C0201-DIFF BUS_0A
P5E_CPU0_PE4_TX_DN<5>    U2               AL86     SOCKET4677_AZIFS054P001C01-SOCA
P5E_CPU0_PE4_TX_DN<6>    C1566            2        Q_CAP_DIFFBUS_C0201-DIFF BUS_0A
P5E_CPU0_PE4_TX_DN<6>    U2               AJ86     SOCKET4677_AZIFS054P001C01-SOCA
P5E_CPU0_PE4_TX_DN<7>    C1564            2        Q_CAP_DIFFBUS_C0201-DIFF BUS_0A
P5E_CPU0_PE4_TX_DN<7>    U2               AG86     SOCKET4677_AZIFS054P001C01-SOCA
P5E_CPU0_PE4_TX_DN<8>    C1562            2        Q_CAP_DIFFBUS_C0201-DIFF BUS_0A
P5E_CPU0_PE4_TX_DN<8>    U2               AE86     SOCKET4677_AZIFS054P001C01-SOCA
P5E_CPU0_PE4_TX_DN<9>    C1560            2        Q_CAP_DIFFBUS_C0201-DIFF BUS_0A
P5E_CPU0_PE4_TX_DN<9>    U2               AC86     SOCKET4677_AZIFS054P001C01-SOCA
P5E_CPU0_PE4_TX_DN<10>   C1558            2        Q_CAP_DIFFBUS_C0201-DIFF BUS_0A
P5E_CPU0_PE4_TX_DN<10>   U2               AA86     SOCKET4677_AZIFS054P001C01-SOCA
P5E_CPU0_PE4_TX_DN<11>   C1556            2        Q_CAP_DIFFBUS_C0201-DIFF BUS_0A
P5E_CPU0_PE4_TX_DN<11>   U2               W86      SOCKET4677_AZIFS054P001C01-SOCA
P5E_CPU0_PE4_TX_DN<12>   C1554            2        Q_CAP_DIFFBUS_C0201-DIFF BUS_0A
P5E_CPU0_PE4_TX_DN<12>   U2               U86      SOCKET4677_AZIFS054P001C01-SOCA
P5E_CPU0_PE4_TX_DN<13>   C1552            2        Q_CAP_DIFFBUS_C0201-DIFF BUS_0A
P5E_CPU0_PE4_TX_DN<13>   U2               R86      SOCKET4677_AZIFS054P001C01-SOCA
P5E_CPU0_PE4_TX_DN<14>   C1550            2        Q_CAP_DIFFBUS_C0201-DIFF BUS_0A
P5E_CPU0_PE4_TX_DN<14>   U2               P85      SOCKET4677_AZIFS054P001C01-SOCA
P5E_CPU0_PE4_TX_DN<15>   C1548            2        Q_CAP_DIFFBUS_C0201-DIFF BUS_0A
P5E_CPU0_PE4_TX_DN<15>   U2               L86      SOCKET4677_AZIFS054P001C01-SOCA
P5E_CPU0_PE4_TX_DP<0>    C1579            2        Q_CAP_DIFFBUS_C0201-DIFF BUS_0A
P5E_CPU0_PE4_TX_DP<0>    U2               BB85     SOCKET4677_AZIFS054P001C01-SOCA
P5E_CPU0_PE4_TX_DP<1>    C1577            2        Q_CAP_DIFFBUS_C0201-DIFF BUS_0A
P5E_CPU0_PE4_TX_DP<1>    U2               AY87     SOCKET4677_AZIFS054P001C01-SOCA
P5E_CPU0_PE4_TX_DP<2>    C1575            2        Q_CAP_DIFFBUS_C0201-DIFF BUS_0A
P5E_CPU0_PE4_TX_DP<2>    U2               AV85     SOCKET4677_AZIFS054P001C01-SOCA
P5E_CPU0_PE4_TX_DP<3>    C1573            2        Q_CAP_DIFFBUS_C0201-DIFF BUS_0A
P5E_CPU0_PE4_TX_DP<3>    U2               AT87     SOCKET4677_AZIFS054P001C01-SOCA
P5E_CPU0_PE4_TX_DP<4>    C1571            2        Q_CAP_DIFFBUS_C0201-DIFF BUS_0A
P5E_CPU0_PE4_TX_DP<4>    U2               AN86     SOCKET4677_AZIFS054P001C01-SOCA
P5E_CPU0_PE4_TX_DP<5>    C1569            2        Q_CAP_DIFFBUS_C0201-DIFF BUS_0A
P5E_CPU0_PE4_TX_DP<5>    U2               AM87     SOCKET4677_AZIFS054P001C01-SOCA
P5E_CPU0_PE4_TX_DP<6>    C1567            2        Q_CAP_DIFFBUS_C0201-DIFF BUS_0A
P5E_CPU0_PE4_TX_DP<6>    U2               AK85     SOCKET4677_AZIFS054P001C01-SOCA
P5E_CPU0_PE4_TX_DP<7>    C1565            2        Q_CAP_DIFFBUS_C0201-DIFF BUS_0A
P5E_CPU0_PE4_TX_DP<7>    U2               AH87     SOCKET4677_AZIFS054P001C01-SOCA
P5E_CPU0_PE4_TX_DP<8>    C1563            2        Q_CAP_DIFFBUS_C0201-DIFF BUS_0A
P5E_CPU0_PE4_TX_DP<8>    U2               AF85     SOCKET4677_AZIFS054P001C01-SOCA
P5E_CPU0_PE4_TX_DP<9>    C1561            2        Q_CAP_DIFFBUS_C0201-DIFF BUS_0A
P5E_CPU0_PE4_TX_DP<9>    U2               AD87     SOCKET4677_AZIFS054P001C01-SOCA
P5E_CPU0_PE4_TX_DP<10>   C1559            2        Q_CAP_DIFFBUS_C0201-DIFF BUS_0A
P5E_CPU0_PE4_TX_DP<10>   U2               AB85     SOCKET4677_AZIFS054P001C01-SOCA
P5E_CPU0_PE4_TX_DP<11>   C1557            2        Q_CAP_DIFFBUS_C0201-DIFF BUS_0A
P5E_CPU0_PE4_TX_DP<11>   U2               Y87      SOCKET4677_AZIFS054P001C01-SOCA
P5E_CPU0_PE4_TX_DP<12>   C1555            2        Q_CAP_DIFFBUS_C0201-DIFF BUS_0A
P5E_CPU0_PE4_TX_DP<12>   U2               V85      SOCKET4677_AZIFS054P001C01-SOCA
P5E_CPU0_PE4_TX_DP<13>   C1553            2        Q_CAP_DIFFBUS_C0201-DIFF BUS_0A
P5E_CPU0_PE4_TX_DP<13>   U2               T87      SOCKET4677_AZIFS054P001C01-SOCA
P5E_CPU0_PE4_TX_DP<14>   C1551            2        Q_CAP_DIFFBUS_C0201-DIFF BUS_0A
P5E_CPU0_PE4_TX_DP<14>   U2               N86      SOCKET4677_AZIFS054P001C01-SOCA
P5E_CPU0_PE4_TX_DP<15>   C1549            2        Q_CAP_DIFFBUS_C0201-DIFF BUS_0A
P5E_CPU0_PE4_TX_DP<15>   U2               M87      SOCKET4677_AZIFS054P001C01-SOCA
P5E_CPU1_PE0_RX_DN<0>    J89              A83      SCONN280_ME1028040102011-SCONNA
P5E_CPU1_PE0_RX_DN<0>    U1               BA9      SOCKET4677_AZIFS054P001C01-SOCA
P5E_CPU1_PE0_RX_DN<1>    J89              A80      SCONN280_ME1028040102011-SCONNA
P5E_CPU1_PE0_RX_DN<1>    U1               AV10     SOCKET4677_AZIFS054P001C01-SOCA
P5E_CPU1_PE0_RX_DN<2>    J89              A77      SCONN280_ME1028040102011-SCONNA
P5E_CPU1_PE0_RX_DN<2>    U1               AU9      SOCKET4677_AZIFS054P001C01-SOCA
P5E_CPU1_PE0_RX_DN<3>    J89              A74      SCONN280_ME1028040102011-SCONNA
P5E_CPU1_PE0_RX_DN<3>    U1               AP10     SOCKET4677_AZIFS054P001C01-SOCA
P5E_CPU1_PE0_RX_DN<4>    J89              A71      SCONN280_ME1028040102011-SCONNA
P5E_CPU1_PE0_RX_DN<4>    U1               AM10     SOCKET4677_AZIFS054P001C01-SOCA
P5E_CPU1_PE0_RX_DN<5>    J89              A68      SCONN280_ME1028040102011-SCONNA
P5E_CPU1_PE0_RX_DN<5>    U1               AK10     SOCKET4677_AZIFS054P001C01-SOCA
P5E_CPU1_PE0_RX_DN<6>    J89              A65      SCONN280_ME1028040102011-SCONNA
P5E_CPU1_PE0_RX_DN<6>    U1               AJ9      SOCKET4677_AZIFS054P001C01-SOCA
P5E_CPU1_PE0_RX_DN<7>    J89              A62      SCONN280_ME1028040102011-SCONNA
P5E_CPU1_PE0_RX_DN<7>    U1               AF10     SOCKET4677_AZIFS054P001C01-SOCA
P5E_CPU1_PE0_RX_DN<8>    J89              A59      SCONN280_ME1028040102011-SCONNA
P5E_CPU1_PE0_RX_DN<8>    U1               AE9      SOCKET4677_AZIFS054P001C01-SOCA
P5E_CPU1_PE0_RX_DN<9>    J89              A55      SCONN280_ME1028040102011-SCONNA
P5E_CPU1_PE0_RX_DN<9>    U1               AB10     SOCKET4677_AZIFS054P001C01-SOCA
P5E_CPU1_PE0_RX_DN<10>   J89              A52      SCONN280_ME1028040102011-SCONNA
P5E_CPU1_PE0_RX_DN<10>   U1               AA9      SOCKET4677_AZIFS054P001C01-SOCA
P5E_CPU1_PE0_RX_DN<11>   J89              A49      SCONN280_ME1028040102011-SCONNA
P5E_CPU1_PE0_RX_DN<11>   U1               V10      SOCKET4677_AZIFS054P001C01-SOCA
P5E_CPU1_PE0_RX_DN<12>   J89              A46      SCONN280_ME1028040102011-SCONNA
P5E_CPU1_PE0_RX_DN<12>   U1               T10      SOCKET4677_AZIFS054P001C01-SOCA
P5E_CPU1_PE0_RX_DN<13>   J89              A43      SCONN280_ME1028040102011-SCONNA
P5E_CPU1_PE0_RX_DN<13>   U1               P10      SOCKET4677_AZIFS054P001C01-SOCA
P5E_CPU1_PE0_RX_DN<14>   J89              A40      SCONN280_ME1028040102011-SCONNA
P5E_CPU1_PE0_RX_DN<14>   U1               M10      SOCKET4677_AZIFS054P001C01-SOCA
P5E_CPU1_PE0_RX_DN<15>   J89              A37      SCONN280_ME1028040102011-SCONNA
P5E_CPU1_PE0_RX_DN<15>   U1               K10      SOCKET4677_AZIFS054P001C01-SOCA
P5E_CPU1_PE0_RX_DP<0>    J89              A82      SCONN280_ME1028040102011-SCONNA
P5E_CPU1_PE0_RX_DP<0>    U1               AY10     SOCKET4677_AZIFS054P001C01-SOCA
P5E_CPU1_PE0_RX_DP<1>    J89              A79      SCONN280_ME1028040102011-SCONNA
P5E_CPU1_PE0_RX_DP<1>    U1               AW11     SOCKET4677_AZIFS054P001C01-SOCA
P5E_CPU1_PE0_RX_DP<2>    J89              A76      SCONN280_ME1028040102011-SCONNA
P5E_CPU1_PE0_RX_DP<2>    U1               AT10     SOCKET4677_AZIFS054P001C01-SOCA
P5E_CPU1_PE0_RX_DP<3>    J89              A73      SCONN280_ME1028040102011-SCONNA
P5E_CPU1_PE0_RX_DP<3>    U1               AR11     SOCKET4677_AZIFS054P001C01-SOCA
P5E_CPU1_PE0_RX_DP<4>    J89              A70      SCONN280_ME1028040102011-SCONNA
P5E_CPU1_PE0_RX_DP<4>    U1               AN9      SOCKET4677_AZIFS054P001C01-SOCA
P5E_CPU1_PE0_RX_DP<5>    J89              A67      SCONN280_ME1028040102011-SCONNA
P5E_CPU1_PE0_RX_DP<5>    U1               AL11     SOCKET4677_AZIFS054P001C01-SOCA
P5E_CPU1_PE0_RX_DP<6>    J89              A64      SCONN280_ME1028040102011-SCONNA
P5E_CPU1_PE0_RX_DP<6>    U1               AH10     SOCKET4677_AZIFS054P001C01-SOCA
P5E_CPU1_PE0_RX_DP<7>    J89              A61      SCONN280_ME1028040102011-SCONNA
P5E_CPU1_PE0_RX_DP<7>    U1               AG11     SOCKET4677_AZIFS054P001C01-SOCA
P5E_CPU1_PE0_RX_DP<8>    J89              A58      SCONN280_ME1028040102011-SCONNA
P5E_CPU1_PE0_RX_DP<8>    U1               AD10     SOCKET4677_AZIFS054P001C01-SOCA
P5E_CPU1_PE0_RX_DP<9>    J89              A54      SCONN280_ME1028040102011-SCONNA
P5E_CPU1_PE0_RX_DP<9>    U1               AC11     SOCKET4677_AZIFS054P001C01-SOCA
P5E_CPU1_PE0_RX_DP<10>   J89              A51      SCONN280_ME1028040102011-SCONNA
P5E_CPU1_PE0_RX_DP<10>   U1               Y10      SOCKET4677_AZIFS054P001C01-SOCA
P5E_CPU1_PE0_RX_DP<11>   J89              A48      SCONN280_ME1028040102011-SCONNA
P5E_CPU1_PE0_RX_DP<11>   U1               W11      SOCKET4677_AZIFS054P001C01-SOCA
P5E_CPU1_PE0_RX_DP<12>   J89              A45      SCONN280_ME1028040102011-SCONNA
P5E_CPU1_PE0_RX_DP<12>   U1               U9       SOCKET4677_AZIFS054P001C01-SOCA
P5E_CPU1_PE0_RX_DP<13>   J89              A42      SCONN280_ME1028040102011-SCONNA
P5E_CPU1_PE0_RX_DP<13>   U1               R11      SOCKET4677_AZIFS054P001C01-SOCA
P5E_CPU1_PE0_RX_DP<14>   J89              A39      SCONN280_ME1028040102011-SCONNA
P5E_CPU1_PE0_RX_DP<14>   U1               N9       SOCKET4677_AZIFS054P001C01-SOCA
P5E_CPU1_PE0_RX_DP<15>   J89              A36      SCONN280_ME1028040102011-SCONNA
P5E_CPU1_PE0_RX_DP<15>   U1               L11      SOCKET4677_AZIFS054P001C01-SOCA
P5E_CPU1_PE0_TX_C_DN<0>  C836             1        Q_CAP_DIFFBUS_C0201-DIFF BUS_0A
P5E_CPU1_PE0_TX_C_DN<0>  J89              B83      SCONN280_ME1028040102011-SCONNA
P5E_CPU1_PE0_TX_C_DN<1>  C834             1        Q_CAP_DIFFBUS_C0201-DIFF BUS_0A
P5E_CPU1_PE0_TX_C_DN<1>  J89              B80      SCONN280_ME1028040102011-SCONNA
P5E_CPU1_PE0_TX_C_DN<2>  C832             1        Q_CAP_DIFFBUS_C0201-DIFF BUS_0A
P5E_CPU1_PE0_TX_C_DN<2>  J89              B77      SCONN280_ME1028040102011-SCONNA
P5E_CPU1_PE0_TX_C_DN<3>  C830             1        Q_CAP_DIFFBUS_C0201-DIFF BUS_0A
P5E_CPU1_PE0_TX_C_DN<3>  J89              B74      SCONN280_ME1028040102011-SCONNA
P5E_CPU1_PE0_TX_C_DN<4>  C828             1        Q_CAP_DIFFBUS_C0201-DIFF BUS_0A
P5E_CPU1_PE0_TX_C_DN<4>  J89              B71      SCONN280_ME1028040102011-SCONNA
P5E_CPU1_PE0_TX_C_DN<5>  C826             1        Q_CAP_DIFFBUS_C0201-DIFF BUS_0A
P5E_CPU1_PE0_TX_C_DN<5>  J89              B68      SCONN280_ME1028040102011-SCONNA
P5E_CPU1_PE0_TX_C_DN<6>  C824             1        Q_CAP_DIFFBUS_C0201-DIFF BUS_0A
P5E_CPU1_PE0_TX_C_DN<6>  J89              B65      SCONN280_ME1028040102011-SCONNA
P5E_CPU1_PE0_TX_C_DN<7>  C822             1        Q_CAP_DIFFBUS_C0201-DIFF BUS_0A
P5E_CPU1_PE0_TX_C_DN<7>  J89              B62      SCONN280_ME1028040102011-SCONNA
P5E_CPU1_PE0_TX_C_DN<8>  C820             1        Q_CAP_DIFFBUS_C0201-DIFF BUS_0A
P5E_CPU1_PE0_TX_C_DN<8>  J89              B59      SCONN280_ME1028040102011-SCONNA
P5E_CPU1_PE0_TX_C_DN<9>  C818             1        Q_CAP_DIFFBUS_C0201-DIFF BUS_0A
P5E_CPU1_PE0_TX_C_DN<9>  J89              B55      SCONN280_ME1028040102011-SCONNA
P5E_CPU1_PE0_TX_C_DN<10> C816             1        Q_CAP_DIFFBUS_C0201-DIFF BUS_0A
P5E_CPU1_PE0_TX_C_DN<10> J89              B52      SCONN280_ME1028040102011-SCONNA
P5E_CPU1_PE0_TX_C_DN<11> C814             1        Q_CAP_DIFFBUS_C0201-DIFF BUS_0A
P5E_CPU1_PE0_TX_C_DN<11> J89              B49      SCONN280_ME1028040102011-SCONNA
P5E_CPU1_PE0_TX_C_DN<12> C812             1        Q_CAP_DIFFBUS_C0201-DIFF BUS_0A
P5E_CPU1_PE0_TX_C_DN<12> J89              B46      SCONN280_ME1028040102011-SCONNA
P5E_CPU1_PE0_TX_C_DN<13> C810             1        Q_CAP_DIFFBUS_C0201-DIFF BUS_0A
P5E_CPU1_PE0_TX_C_DN<13> J89              B43      SCONN280_ME1028040102011-SCONNA
P5E_CPU1_PE0_TX_C_DN<14> C808             1        Q_CAP_DIFFBUS_C0201-DIFF BUS_0A
P5E_CPU1_PE0_TX_C_DN<14> J89              B40      SCONN280_ME1028040102011-SCONNA
P5E_CPU1_PE0_TX_C_DN<15> C806             1        Q_CAP_DIFFBUS_C0201-DIFF BUS_0A
P5E_CPU1_PE0_TX_C_DN<15> J89              B37      SCONN280_ME1028040102011-SCONNA
P5E_CPU1_PE0_TX_C_DP<0>  C837             1        Q_CAP_DIFFBUS_C0201-DIFF BUS_0A
P5E_CPU1_PE0_TX_C_DP<0>  J89              B82      SCONN280_ME1028040102011-SCONNA
P5E_CPU1_PE0_TX_C_DP<1>  C835             1        Q_CAP_DIFFBUS_C0201-DIFF BUS_0A
P5E_CPU1_PE0_TX_C_DP<1>  J89              B79      SCONN280_ME1028040102011-SCONNA
P5E_CPU1_PE0_TX_C_DP<2>  C833             1        Q_CAP_DIFFBUS_C0201-DIFF BUS_0A
P5E_CPU1_PE0_TX_C_DP<2>  J89              B76      SCONN280_ME1028040102011-SCONNA
P5E_CPU1_PE0_TX_C_DP<3>  C831             1        Q_CAP_DIFFBUS_C0201-DIFF BUS_0A
P5E_CPU1_PE0_TX_C_DP<3>  J89              B73      SCONN280_ME1028040102011-SCONNA
P5E_CPU1_PE0_TX_C_DP<4>  C829             1        Q_CAP_DIFFBUS_C0201-DIFF BUS_0A
P5E_CPU1_PE0_TX_C_DP<4>  J89              B70      SCONN280_ME1028040102011-SCONNA
P5E_CPU1_PE0_TX_C_DP<5>  C827             1        Q_CAP_DIFFBUS_C0201-DIFF BUS_0A
P5E_CPU1_PE0_TX_C_DP<5>  J89              B67      SCONN280_ME1028040102011-SCONNA
P5E_CPU1_PE0_TX_C_DP<6>  C825             1        Q_CAP_DIFFBUS_C0201-DIFF BUS_0A
P5E_CPU1_PE0_TX_C_DP<6>  J89              B64      SCONN280_ME1028040102011-SCONNA
P5E_CPU1_PE0_TX_C_DP<7>  C823             1        Q_CAP_DIFFBUS_C0201-DIFF BUS_0A
P5E_CPU1_PE0_TX_C_DP<7>  J89              B61      SCONN280_ME1028040102011-SCONNA
P5E_CPU1_PE0_TX_C_DP<8>  C821             1        Q_CAP_DIFFBUS_C0201-DIFF BUS_0A
P5E_CPU1_PE0_TX_C_DP<8>  J89              B58      SCONN280_ME1028040102011-SCONNA
P5E_CPU1_PE0_TX_C_DP<9>  C819             1        Q_CAP_DIFFBUS_C0201-DIFF BUS_0A
P5E_CPU1_PE0_TX_C_DP<9>  J89              B54      SCONN280_ME1028040102011-SCONNA
P5E_CPU1_PE0_TX_C_DP<10> C817             1        Q_CAP_DIFFBUS_C0201-DIFF BUS_0A
P5E_CPU1_PE0_TX_C_DP<10> J89              B51      SCONN280_ME1028040102011-SCONNA
P5E_CPU1_PE0_TX_C_DP<11> C815             1        Q_CAP_DIFFBUS_C0201-DIFF BUS_0A
P5E_CPU1_PE0_TX_C_DP<11> J89              B48      SCONN280_ME1028040102011-SCONNA
P5E_CPU1_PE0_TX_C_DP<12> C813             1        Q_CAP_DIFFBUS_C0201-DIFF BUS_0A
P5E_CPU1_PE0_TX_C_DP<12> J89              B45      SCONN280_ME1028040102011-SCONNA
P5E_CPU1_PE0_TX_C_DP<13> C811             1        Q_CAP_DIFFBUS_C0201-DIFF BUS_0A
P5E_CPU1_PE0_TX_C_DP<13> J89              B42      SCONN280_ME1028040102011-SCONNA
P5E_CPU1_PE0_TX_C_DP<14> C809             1        Q_CAP_DIFFBUS_C0201-DIFF BUS_0A
P5E_CPU1_PE0_TX_C_DP<14> J89              B39      SCONN280_ME1028040102011-SCONNA
P5E_CPU1_PE0_TX_C_DP<15> C807             1        Q_CAP_DIFFBUS_C0201-DIFF BUS_0A
P5E_CPU1_PE0_TX_C_DP<15> J89              B36      SCONN280_ME1028040102011-SCONNA
P5E_CPU1_PE0_TX_DN<0>    C836             2        Q_CAP_DIFFBUS_C0201-DIFF BUS_0A
P5E_CPU1_PE0_TX_DN<0>    U1               BB14     SOCKET4677_AZIFS054P001C01-SOCA
P5E_CPU1_PE0_TX_DN<1>    C834             2        Q_CAP_DIFFBUS_C0201-DIFF BUS_0A
P5E_CPU1_PE0_TX_DN<1>    U1               BA13     SOCKET4677_AZIFS054P001C01-SOCA
P5E_CPU1_PE0_TX_DN<2>    C832             2        Q_CAP_DIFFBUS_C0201-DIFF BUS_0A
P5E_CPU1_PE0_TX_DN<2>    U1               AV14     SOCKET4677_AZIFS054P001C01-SOCA
P5E_CPU1_PE0_TX_DN<3>    C830             2        Q_CAP_DIFFBUS_C0201-DIFF BUS_0A
P5E_CPU1_PE0_TX_DN<3>    U1               AU13     SOCKET4677_AZIFS054P001C01-SOCA
P5E_CPU1_PE0_TX_DN<4>    C828             2        Q_CAP_DIFFBUS_C0201-DIFF BUS_0A
P5E_CPU1_PE0_TX_DN<4>    U1               AP14     SOCKET4677_AZIFS054P001C01-SOCA
P5E_CPU1_PE0_TX_DN<5>    C826             2        Q_CAP_DIFFBUS_C0201-DIFF BUS_0A
P5E_CPU1_PE0_TX_DN<5>    U1               AN13     SOCKET4677_AZIFS054P001C01-SOCA
P5E_CPU1_PE0_TX_DN<6>    C824             2        Q_CAP_DIFFBUS_C0201-DIFF BUS_0A
P5E_CPU1_PE0_TX_DN<6>    U1               AK14     SOCKET4677_AZIFS054P001C01-SOCA
P5E_CPU1_PE0_TX_DN<7>    C822             2        Q_CAP_DIFFBUS_C0201-DIFF BUS_0A
P5E_CPU1_PE0_TX_DN<7>    U1               AJ13     SOCKET4677_AZIFS054P001C01-SOCA
P5E_CPU1_PE0_TX_DN<8>    C820             2        Q_CAP_DIFFBUS_C0201-DIFF BUS_0A
P5E_CPU1_PE0_TX_DN<8>    U1               AF14     SOCKET4677_AZIFS054P001C01-SOCA
P5E_CPU1_PE0_TX_DN<9>    C818             2        Q_CAP_DIFFBUS_C0201-DIFF BUS_0A
P5E_CPU1_PE0_TX_DN<9>    U1               AE13     SOCKET4677_AZIFS054P001C01-SOCA
P5E_CPU1_PE0_TX_DN<10>   C816             2        Q_CAP_DIFFBUS_C0201-DIFF BUS_0A
P5E_CPU1_PE0_TX_DN<10>   U1               AB14     SOCKET4677_AZIFS054P001C01-SOCA
P5E_CPU1_PE0_TX_DN<11>   C814             2        Q_CAP_DIFFBUS_C0201-DIFF BUS_0A
P5E_CPU1_PE0_TX_DN<11>   U1               AA13     SOCKET4677_AZIFS054P001C01-SOCA
P5E_CPU1_PE0_TX_DN<12>   C812             2        Q_CAP_DIFFBUS_C0201-DIFF BUS_0A
P5E_CPU1_PE0_TX_DN<12>   U1               V14      SOCKET4677_AZIFS054P001C01-SOCA
P5E_CPU1_PE0_TX_DN<13>   C810             2        Q_CAP_DIFFBUS_C0201-DIFF BUS_0A
P5E_CPU1_PE0_TX_DN<13>   U1               U13      SOCKET4677_AZIFS054P001C01-SOCA
P5E_CPU1_PE0_TX_DN<14>   C808             2        Q_CAP_DIFFBUS_C0201-DIFF BUS_0A
P5E_CPU1_PE0_TX_DN<14>   U1               P14      SOCKET4677_AZIFS054P001C01-SOCA
P5E_CPU1_PE0_TX_DN<15>   C806             2        Q_CAP_DIFFBUS_C0201-DIFF BUS_0A
P5E_CPU1_PE0_TX_DN<15>   U1               N13      SOCKET4677_AZIFS054P001C01-SOCA
P5E_CPU1_PE0_TX_DP<0>    C837             2        Q_CAP_DIFFBUS_C0201-DIFF BUS_0A
P5E_CPU1_PE0_TX_DP<0>    U1               BC15     SOCKET4677_AZIFS054P001C01-SOCA
P5E_CPU1_PE0_TX_DP<1>    C835             2        Q_CAP_DIFFBUS_C0201-DIFF BUS_0A
P5E_CPU1_PE0_TX_DP<1>    U1               AY14     SOCKET4677_AZIFS054P001C01-SOCA
P5E_CPU1_PE0_TX_DP<2>    C833             2        Q_CAP_DIFFBUS_C0201-DIFF BUS_0A
P5E_CPU1_PE0_TX_DP<2>    U1               AW15     SOCKET4677_AZIFS054P001C01-SOCA
P5E_CPU1_PE0_TX_DP<3>    C831             2        Q_CAP_DIFFBUS_C0201-DIFF BUS_0A
P5E_CPU1_PE0_TX_DP<3>    U1               AT14     SOCKET4677_AZIFS054P001C01-SOCA
P5E_CPU1_PE0_TX_DP<4>    C829             2        Q_CAP_DIFFBUS_C0201-DIFF BUS_0A
P5E_CPU1_PE0_TX_DP<4>    U1               AR15     SOCKET4677_AZIFS054P001C01-SOCA
P5E_CPU1_PE0_TX_DP<5>    C827             2        Q_CAP_DIFFBUS_C0201-DIFF BUS_0A
P5E_CPU1_PE0_TX_DP<5>    U1               AM14     SOCKET4677_AZIFS054P001C01-SOCA
P5E_CPU1_PE0_TX_DP<6>    C825             2        Q_CAP_DIFFBUS_C0201-DIFF BUS_0A
P5E_CPU1_PE0_TX_DP<6>    U1               AL15     SOCKET4677_AZIFS054P001C01-SOCA
P5E_CPU1_PE0_TX_DP<7>    C823             2        Q_CAP_DIFFBUS_C0201-DIFF BUS_0A
P5E_CPU1_PE0_TX_DP<7>    U1               AH14     SOCKET4677_AZIFS054P001C01-SOCA
P5E_CPU1_PE0_TX_DP<8>    C821             2        Q_CAP_DIFFBUS_C0201-DIFF BUS_0A
P5E_CPU1_PE0_TX_DP<8>    U1               AG15     SOCKET4677_AZIFS054P001C01-SOCA
P5E_CPU1_PE0_TX_DP<9>    C819             2        Q_CAP_DIFFBUS_C0201-DIFF BUS_0A
P5E_CPU1_PE0_TX_DP<9>    U1               AD14     SOCKET4677_AZIFS054P001C01-SOCA
P5E_CPU1_PE0_TX_DP<10>   C817             2        Q_CAP_DIFFBUS_C0201-DIFF BUS_0A
P5E_CPU1_PE0_TX_DP<10>   U1               AC15     SOCKET4677_AZIFS054P001C01-SOCA
P5E_CPU1_PE0_TX_DP<11>   C815             2        Q_CAP_DIFFBUS_C0201-DIFF BUS_0A
P5E_CPU1_PE0_TX_DP<11>   U1               Y14      SOCKET4677_AZIFS054P001C01-SOCA
P5E_CPU1_PE0_TX_DP<12>   C813             2        Q_CAP_DIFFBUS_C0201-DIFF BUS_0A
P5E_CPU1_PE0_TX_DP<12>   U1               W15      SOCKET4677_AZIFS054P001C01-SOCA
P5E_CPU1_PE0_TX_DP<13>   C811             2        Q_CAP_DIFFBUS_C0201-DIFF BUS_0A
P5E_CPU1_PE0_TX_DP<13>   U1               T14      SOCKET4677_AZIFS054P001C01-SOCA
P5E_CPU1_PE0_TX_DP<14>   C809             2        Q_CAP_DIFFBUS_C0201-DIFF BUS_0A
P5E_CPU1_PE0_TX_DP<14>   U1               R15      SOCKET4677_AZIFS054P001C01-SOCA
P5E_CPU1_PE0_TX_DP<15>   C807             2        Q_CAP_DIFFBUS_C0201-DIFF BUS_0A
P5E_CPU1_PE0_TX_DP<15>   U1               M14      SOCKET4677_AZIFS054P001C01-SOCA
P5E_CPU1_PE1_RX_DN<0>    J57              B66      SCONN140_G64V3431BHR-SCONN140_A
P5E_CPU1_PE1_RX_DN<0>    U1               BC11     SOCKET4677_AZIFS054P001C01-SOCA
P5E_CPU1_PE1_RX_DN<1>    J57              B63      SCONN140_G64V3431BHR-SCONN140_A
P5E_CPU1_PE1_RX_DN<1>    U1               BF10     SOCKET4677_AZIFS054P001C01-SOCA
P5E_CPU1_PE1_RX_DN<2>    J57              B60      SCONN140_G64V3431BHR-SCONN140_A
P5E_CPU1_PE1_RX_DN<2>    U1               BG11     SOCKET4677_AZIFS054P001C01-SOCA
P5E_CPU1_PE1_RX_DN<3>    J57              B57      SCONN140_G64V3431BHR-SCONN140_A
P5E_CPU1_PE1_RX_DN<3>    U1               BK10     SOCKET4677_AZIFS054P001C01-SOCA
P5E_CPU1_PE1_RX_DN<4>    J57              B54      SCONN140_G64V3431BHR-SCONN140_A
P5E_CPU1_PE1_RX_DN<4>    U1               BL11     SOCKET4677_AZIFS054P001C01-SOCA
P5E_CPU1_PE1_RX_DN<5>    J57              B51      SCONN140_G64V3431BHR-SCONN140_A
P5E_CPU1_PE1_RX_DN<5>    U1               BP10     SOCKET4677_AZIFS054P001C01-SOCA
P5E_CPU1_PE1_RX_DN<6>    J57              B48      SCONN140_G64V3431BHR-SCONN140_A
P5E_CPU1_PE1_RX_DN<6>    U1               BR11     SOCKET4677_AZIFS054P001C01-SOCA
P5E_CPU1_PE1_RX_DN<7>    J57              B45      SCONN140_G64V3431BHR-SCONN140_A
P5E_CPU1_PE1_RX_DN<7>    U1               BV10     SOCKET4677_AZIFS054P001C01-SOCA
P5E_CPU1_PE1_RX_DN<8>    J57              B40      SCONN140_G64V3431BHR-SCONN140_A
P5E_CPU1_PE1_RX_DN<8>    U1               BW11     SOCKET4677_AZIFS054P001C01-SOCA
P5E_CPU1_PE1_RX_DN<9>    J57              B37      SCONN140_G64V3431BHR-SCONN140_A
P5E_CPU1_PE1_RX_DN<9>    U1               CB10     SOCKET4677_AZIFS054P001C01-SOCA
P5E_CPU1_PE1_RX_DN<10>   J57              B34      SCONN140_G64V3431BHR-SCONN140_A
P5E_CPU1_PE1_RX_DN<10>   U1               CC11     SOCKET4677_AZIFS054P001C01-SOCA
P5E_CPU1_PE1_RX_DN<11>   J57              B31      SCONN140_G64V3431BHR-SCONN140_A
P5E_CPU1_PE1_RX_DN<11>   U1               CF10     SOCKET4677_AZIFS054P001C01-SOCA
P5E_CPU1_PE1_RX_DN<12>   J57              B27      SCONN140_G64V3431BHR-SCONN140_A
P5E_CPU1_PE1_RX_DN<12>   U1               CG11     SOCKET4677_AZIFS054P001C01-SOCA
P5E_CPU1_PE1_RX_DN<13>   J57              B24      SCONN140_G64V3431BHR-SCONN140_A
P5E_CPU1_PE1_RX_DN<13>   U1               CK10     SOCKET4677_AZIFS054P001C01-SOCA
P5E_CPU1_PE1_RX_DN<14>   J57              B21      SCONN140_G64V3431BHR-SCONN140_A
P5E_CPU1_PE1_RX_DN<14>   U1               CL11     SOCKET4677_AZIFS054P001C01-SOCA
P5E_CPU1_PE1_RX_DN<15>   J57              B18      SCONN140_G64V3431BHR-SCONN140_A
P5E_CPU1_PE1_RX_DN<15>   U1               CP10     SOCKET4677_AZIFS054P001C01-SOCA
P5E_CPU1_PE1_RX_DP<0>    J57              B65      SCONN140_G64V3431BHR-SCONN140_A
P5E_CPU1_PE1_RX_DP<0>    U1               BD10     SOCKET4677_AZIFS054P001C01-SOCA
P5E_CPU1_PE1_RX_DP<1>    J57              B62      SCONN140_G64V3431BHR-SCONN140_A
P5E_CPU1_PE1_RX_DP<1>    U1               BE9      SOCKET4677_AZIFS054P001C01-SOCA
P5E_CPU1_PE1_RX_DP<2>    J57              B59      SCONN140_G64V3431BHR-SCONN140_A
P5E_CPU1_PE1_RX_DP<2>    U1               BH10     SOCKET4677_AZIFS054P001C01-SOCA
P5E_CPU1_PE1_RX_DP<3>    J57              B56      SCONN140_G64V3431BHR-SCONN140_A
P5E_CPU1_PE1_RX_DP<3>    U1               BJ9      SOCKET4677_AZIFS054P001C01-SOCA
P5E_CPU1_PE1_RX_DP<4>    J57              B53      SCONN140_G64V3431BHR-SCONN140_A
P5E_CPU1_PE1_RX_DP<4>    U1               BM10     SOCKET4677_AZIFS054P001C01-SOCA
P5E_CPU1_PE1_RX_DP<5>    J57              B50      SCONN140_G64V3431BHR-SCONN140_A
P5E_CPU1_PE1_RX_DP<5>    U1               BN9      SOCKET4677_AZIFS054P001C01-SOCA
P5E_CPU1_PE1_RX_DP<6>    J57              B47      SCONN140_G64V3431BHR-SCONN140_A
P5E_CPU1_PE1_RX_DP<6>    U1               BT10     SOCKET4677_AZIFS054P001C01-SOCA
P5E_CPU1_PE1_RX_DP<7>    J57              B44      SCONN140_G64V3431BHR-SCONN140_A
P5E_CPU1_PE1_RX_DP<7>    U1               BU9      SOCKET4677_AZIFS054P001C01-SOCA
P5E_CPU1_PE1_RX_DP<8>    J57              B39      SCONN140_G64V3431BHR-SCONN140_A
P5E_CPU1_PE1_RX_DP<8>    U1               BY10     SOCKET4677_AZIFS054P001C01-SOCA
P5E_CPU1_PE1_RX_DP<9>    J57              B36      SCONN140_G64V3431BHR-SCONN140_A
P5E_CPU1_PE1_RX_DP<9>    U1               CA9      SOCKET4677_AZIFS054P001C01-SOCA
P5E_CPU1_PE1_RX_DP<10>   J57              B33      SCONN140_G64V3431BHR-SCONN140_A
P5E_CPU1_PE1_RX_DP<10>   U1               CD10     SOCKET4677_AZIFS054P001C01-SOCA
P5E_CPU1_PE1_RX_DP<11>   J57              B30      SCONN140_G64V3431BHR-SCONN140_A
P5E_CPU1_PE1_RX_DP<11>   U1               CE9      SOCKET4677_AZIFS054P001C01-SOCA
P5E_CPU1_PE1_RX_DP<12>   J57              B26      SCONN140_G64V3431BHR-SCONN140_A
P5E_CPU1_PE1_RX_DP<12>   U1               CH10     SOCKET4677_AZIFS054P001C01-SOCA
P5E_CPU1_PE1_RX_DP<13>   J57              B23      SCONN140_G64V3431BHR-SCONN140_A
P5E_CPU1_PE1_RX_DP<13>   U1               CJ9      SOCKET4677_AZIFS054P001C01-SOCA
P5E_CPU1_PE1_RX_DP<14>   J57              B20      SCONN140_G64V3431BHR-SCONN140_A
P5E_CPU1_PE1_RX_DP<14>   U1               CM10     SOCKET4677_AZIFS054P001C01-SOCA
P5E_CPU1_PE1_RX_DP<15>   J57              B17      SCONN140_G64V3431BHR-SCONN140_A
P5E_CPU1_PE1_RX_DP<15>   U1               CN9      SOCKET4677_AZIFS054P001C01-SOCA
P5E_CPU1_PE1_TX_C_DN<0>  C740             1        Q_CAP_DIFFBUS_C0201-DIFF BUS_0A
P5E_CPU1_PE1_TX_C_DN<0>  J57              A66      SCONN140_G64V3431BHR-SCONN140_A
P5E_CPU1_PE1_TX_C_DN<1>  C738             1        Q_CAP_DIFFBUS_C0201-DIFF BUS_0A
P5E_CPU1_PE1_TX_C_DN<1>  J57              A63      SCONN140_G64V3431BHR-SCONN140_A
P5E_CPU1_PE1_TX_C_DN<2>  C736             1        Q_CAP_DIFFBUS_C0201-DIFF BUS_0A
P5E_CPU1_PE1_TX_C_DN<2>  J57              A60      SCONN140_G64V3431BHR-SCONN140_A
P5E_CPU1_PE1_TX_C_DN<3>  C734             1        Q_CAP_DIFFBUS_C0201-DIFF BUS_0A
P5E_CPU1_PE1_TX_C_DN<3>  J57              A57      SCONN140_G64V3431BHR-SCONN140_A
P5E_CPU1_PE1_TX_C_DN<4>  C732             1        Q_CAP_DIFFBUS_C0201-DIFF BUS_0A
P5E_CPU1_PE1_TX_C_DN<4>  J57              A54      SCONN140_G64V3431BHR-SCONN140_A
P5E_CPU1_PE1_TX_C_DN<5>  C730             1        Q_CAP_DIFFBUS_C0201-DIFF BUS_0A
P5E_CPU1_PE1_TX_C_DN<5>  J57              A51      SCONN140_G64V3431BHR-SCONN140_A
P5E_CPU1_PE1_TX_C_DN<6>  C728             1        Q_CAP_DIFFBUS_C0201-DIFF BUS_0A
P5E_CPU1_PE1_TX_C_DN<6>  J57              A48      SCONN140_G64V3431BHR-SCONN140_A
P5E_CPU1_PE1_TX_C_DN<7>  C726             1        Q_CAP_DIFFBUS_C0201-DIFF BUS_0A
P5E_CPU1_PE1_TX_C_DN<7>  J57              A45      SCONN140_G64V3431BHR-SCONN140_A
P5E_CPU1_PE1_TX_C_DN<8>  C724             1        Q_CAP_DIFFBUS_C0201-DIFF BUS_0A
P5E_CPU1_PE1_TX_C_DN<8>  J57              A40      SCONN140_G64V3431BHR-SCONN140_A
P5E_CPU1_PE1_TX_C_DN<9>  C722             1        Q_CAP_DIFFBUS_C0201-DIFF BUS_0A
P5E_CPU1_PE1_TX_C_DN<9>  J57              A37      SCONN140_G64V3431BHR-SCONN140_A
P5E_CPU1_PE1_TX_C_DN<10> C720             1        Q_CAP_DIFFBUS_C0201-DIFF BUS_0A
P5E_CPU1_PE1_TX_C_DN<10> J57              A34      SCONN140_G64V3431BHR-SCONN140_A
P5E_CPU1_PE1_TX_C_DN<11> C718             1        Q_CAP_DIFFBUS_C0201-DIFF BUS_0A
P5E_CPU1_PE1_TX_C_DN<11> J57              A31      SCONN140_G64V3431BHR-SCONN140_A
P5E_CPU1_PE1_TX_C_DN<12> C716             1        Q_CAP_DIFFBUS_C0201-DIFF BUS_0A
P5E_CPU1_PE1_TX_C_DN<12> J57              A27      SCONN140_G64V3431BHR-SCONN140_A
P5E_CPU1_PE1_TX_C_DN<13> C714             1        Q_CAP_DIFFBUS_C0201-DIFF BUS_0A
P5E_CPU1_PE1_TX_C_DN<13> J57              A24      SCONN140_G64V3431BHR-SCONN140_A
P5E_CPU1_PE1_TX_C_DN<14> C712             1        Q_CAP_DIFFBUS_C0201-DIFF BUS_0A
P5E_CPU1_PE1_TX_C_DN<14> J57              A21      SCONN140_G64V3431BHR-SCONN140_A
P5E_CPU1_PE1_TX_C_DN<15> C710             1        Q_CAP_DIFFBUS_C0201-DIFF BUS_0A
P5E_CPU1_PE1_TX_C_DN<15> J57              A18      SCONN140_G64V3431BHR-SCONN140_A
P5E_CPU1_PE1_TX_C_DP<0>  C741             1        Q_CAP_DIFFBUS_C0201-DIFF BUS_0A
P5E_CPU1_PE1_TX_C_DP<0>  J57              A65      SCONN140_G64V3431BHR-SCONN140_A
P5E_CPU1_PE1_TX_C_DP<1>  C739             1        Q_CAP_DIFFBUS_C0201-DIFF BUS_0A
P5E_CPU1_PE1_TX_C_DP<1>  J57              A62      SCONN140_G64V3431BHR-SCONN140_A
P5E_CPU1_PE1_TX_C_DP<2>  C737             1        Q_CAP_DIFFBUS_C0201-DIFF BUS_0A
P5E_CPU1_PE1_TX_C_DP<2>  J57              A59      SCONN140_G64V3431BHR-SCONN140_A
P5E_CPU1_PE1_TX_C_DP<3>  C735             1        Q_CAP_DIFFBUS_C0201-DIFF BUS_0A
P5E_CPU1_PE1_TX_C_DP<3>  J57              A56      SCONN140_G64V3431BHR-SCONN140_A
P5E_CPU1_PE1_TX_C_DP<4>  C733             1        Q_CAP_DIFFBUS_C0201-DIFF BUS_0A
P5E_CPU1_PE1_TX_C_DP<4>  J57              A53      SCONN140_G64V3431BHR-SCONN140_A
P5E_CPU1_PE1_TX_C_DP<5>  C731             1        Q_CAP_DIFFBUS_C0201-DIFF BUS_0A
P5E_CPU1_PE1_TX_C_DP<5>  J57              A50      SCONN140_G64V3431BHR-SCONN140_A
P5E_CPU1_PE1_TX_C_DP<6>  C729             1        Q_CAP_DIFFBUS_C0201-DIFF BUS_0A
P5E_CPU1_PE1_TX_C_DP<6>  J57              A47      SCONN140_G64V3431BHR-SCONN140_A
P5E_CPU1_PE1_TX_C_DP<7>  C727             1        Q_CAP_DIFFBUS_C0201-DIFF BUS_0A
P5E_CPU1_PE1_TX_C_DP<7>  J57              A44      SCONN140_G64V3431BHR-SCONN140_A
P5E_CPU1_PE1_TX_C_DP<8>  C725             1        Q_CAP_DIFFBUS_C0201-DIFF BUS_0A
P5E_CPU1_PE1_TX_C_DP<8>  J57              A39      SCONN140_G64V3431BHR-SCONN140_A
P5E_CPU1_PE1_TX_C_DP<9>  C723             1        Q_CAP_DIFFBUS_C0201-DIFF BUS_0A
P5E_CPU1_PE1_TX_C_DP<9>  J57              A36      SCONN140_G64V3431BHR-SCONN140_A
P5E_CPU1_PE1_TX_C_DP<10> C721             1        Q_CAP_DIFFBUS_C0201-DIFF BUS_0A
P5E_CPU1_PE1_TX_C_DP<10> J57              A33      SCONN140_G64V3431BHR-SCONN140_A
P5E_CPU1_PE1_TX_C_DP<11> C719             1        Q_CAP_DIFFBUS_C0201-DIFF BUS_0A
P5E_CPU1_PE1_TX_C_DP<11> J57              A30      SCONN140_G64V3431BHR-SCONN140_A
P5E_CPU1_PE1_TX_C_DP<12> C717             1        Q_CAP_DIFFBUS_C0201-DIFF BUS_0A
P5E_CPU1_PE1_TX_C_DP<12> J57              A26      SCONN140_G64V3431BHR-SCONN140_A
P5E_CPU1_PE1_TX_C_DP<13> C715             1        Q_CAP_DIFFBUS_C0201-DIFF BUS_0A
P5E_CPU1_PE1_TX_C_DP<13> J57              A23      SCONN140_G64V3431BHR-SCONN140_A
P5E_CPU1_PE1_TX_C_DP<14> C713             1        Q_CAP_DIFFBUS_C0201-DIFF BUS_0A
P5E_CPU1_PE1_TX_C_DP<14> J57              A20      SCONN140_G64V3431BHR-SCONN140_A
P5E_CPU1_PE1_TX_C_DP<15> C711             1        Q_CAP_DIFFBUS_C0201-DIFF BUS_0A
P5E_CPU1_PE1_TX_C_DP<15> J57              A17      SCONN140_G64V3431BHR-SCONN140_A
P5E_CPU1_PE1_TX_DN<0>    C740             2        Q_CAP_DIFFBUS_C0201-DIFF BUS_0A
P5E_CPU1_PE1_TX_DN<0>    U1               BE13     SOCKET4677_AZIFS054P001C01-SOCA
P5E_CPU1_PE1_TX_DN<1>    C738             2        Q_CAP_DIFFBUS_C0201-DIFF BUS_0A
P5E_CPU1_PE1_TX_DN<1>    U1               BF14     SOCKET4677_AZIFS054P001C01-SOCA
P5E_CPU1_PE1_TX_DN<2>    C736             2        Q_CAP_DIFFBUS_C0201-DIFF BUS_0A
P5E_CPU1_PE1_TX_DN<2>    U1               BJ13     SOCKET4677_AZIFS054P001C01-SOCA
P5E_CPU1_PE1_TX_DN<3>    C734             2        Q_CAP_DIFFBUS_C0201-DIFF BUS_0A
P5E_CPU1_PE1_TX_DN<3>    U1               BK14     SOCKET4677_AZIFS054P001C01-SOCA
P5E_CPU1_PE1_TX_DN<4>    C732             2        Q_CAP_DIFFBUS_C0201-DIFF BUS_0A
P5E_CPU1_PE1_TX_DN<4>    U1               BN13     SOCKET4677_AZIFS054P001C01-SOCA
P5E_CPU1_PE1_TX_DN<5>    C730             2        Q_CAP_DIFFBUS_C0201-DIFF BUS_0A
P5E_CPU1_PE1_TX_DN<5>    U1               BP14     SOCKET4677_AZIFS054P001C01-SOCA
P5E_CPU1_PE1_TX_DN<6>    C728             2        Q_CAP_DIFFBUS_C0201-DIFF BUS_0A
P5E_CPU1_PE1_TX_DN<6>    U1               BU13     SOCKET4677_AZIFS054P001C01-SOCA
P5E_CPU1_PE1_TX_DN<7>    C726             2        Q_CAP_DIFFBUS_C0201-DIFF BUS_0A
P5E_CPU1_PE1_TX_DN<7>    U1               BV14     SOCKET4677_AZIFS054P001C01-SOCA
P5E_CPU1_PE1_TX_DN<8>    C724             2        Q_CAP_DIFFBUS_C0201-DIFF BUS_0A
P5E_CPU1_PE1_TX_DN<8>    U1               CA13     SOCKET4677_AZIFS054P001C01-SOCA
P5E_CPU1_PE1_TX_DN<9>    C722             2        Q_CAP_DIFFBUS_C0201-DIFF BUS_0A
P5E_CPU1_PE1_TX_DN<9>    U1               CB14     SOCKET4677_AZIFS054P001C01-SOCA
P5E_CPU1_PE1_TX_DN<10>   C720             2        Q_CAP_DIFFBUS_C0201-DIFF BUS_0A
P5E_CPU1_PE1_TX_DN<10>   U1               CE13     SOCKET4677_AZIFS054P001C01-SOCA
P5E_CPU1_PE1_TX_DN<11>   C718             2        Q_CAP_DIFFBUS_C0201-DIFF BUS_0A
P5E_CPU1_PE1_TX_DN<11>   U1               CF14     SOCKET4677_AZIFS054P001C01-SOCA
P5E_CPU1_PE1_TX_DN<12>   C716             2        Q_CAP_DIFFBUS_C0201-DIFF BUS_0A
P5E_CPU1_PE1_TX_DN<12>   U1               CJ13     SOCKET4677_AZIFS054P001C01-SOCA
P5E_CPU1_PE1_TX_DN<13>   C714             2        Q_CAP_DIFFBUS_C0201-DIFF BUS_0A
P5E_CPU1_PE1_TX_DN<13>   U1               CK14     SOCKET4677_AZIFS054P001C01-SOCA
P5E_CPU1_PE1_TX_DN<14>   C712             2        Q_CAP_DIFFBUS_C0201-DIFF BUS_0A
P5E_CPU1_PE1_TX_DN<14>   U1               CN13     SOCKET4677_AZIFS054P001C01-SOCA
P5E_CPU1_PE1_TX_DN<15>   C710             2        Q_CAP_DIFFBUS_C0201-DIFF BUS_0A
P5E_CPU1_PE1_TX_DN<15>   U1               CP14     SOCKET4677_AZIFS054P001C01-SOCA
P5E_CPU1_PE1_TX_DP<0>    C741             2        Q_CAP_DIFFBUS_C0201-DIFF BUS_0A
P5E_CPU1_PE1_TX_DP<0>    U1               BD14     SOCKET4677_AZIFS054P001C01-SOCA
P5E_CPU1_PE1_TX_DP<1>    C739             2        Q_CAP_DIFFBUS_C0201-DIFF BUS_0A
P5E_CPU1_PE1_TX_DP<1>    U1               BG15     SOCKET4677_AZIFS054P001C01-SOCA
P5E_CPU1_PE1_TX_DP<2>    C737             2        Q_CAP_DIFFBUS_C0201-DIFF BUS_0A
P5E_CPU1_PE1_TX_DP<2>    U1               BH14     SOCKET4677_AZIFS054P001C01-SOCA
P5E_CPU1_PE1_TX_DP<3>    C735             2        Q_CAP_DIFFBUS_C0201-DIFF BUS_0A
P5E_CPU1_PE1_TX_DP<3>    U1               BL15     SOCKET4677_AZIFS054P001C01-SOCA
P5E_CPU1_PE1_TX_DP<4>    C733             2        Q_CAP_DIFFBUS_C0201-DIFF BUS_0A
P5E_CPU1_PE1_TX_DP<4>    U1               BM14     SOCKET4677_AZIFS054P001C01-SOCA
P5E_CPU1_PE1_TX_DP<5>    C731             2        Q_CAP_DIFFBUS_C0201-DIFF BUS_0A
P5E_CPU1_PE1_TX_DP<5>    U1               BR15     SOCKET4677_AZIFS054P001C01-SOCA
P5E_CPU1_PE1_TX_DP<6>    C729             2        Q_CAP_DIFFBUS_C0201-DIFF BUS_0A
P5E_CPU1_PE1_TX_DP<6>    U1               BT14     SOCKET4677_AZIFS054P001C01-SOCA
P5E_CPU1_PE1_TX_DP<7>    C727             2        Q_CAP_DIFFBUS_C0201-DIFF BUS_0A
P5E_CPU1_PE1_TX_DP<7>    U1               BW15     SOCKET4677_AZIFS054P001C01-SOCA
P5E_CPU1_PE1_TX_DP<8>    C725             2        Q_CAP_DIFFBUS_C0201-DIFF BUS_0A
P5E_CPU1_PE1_TX_DP<8>    U1               BY14     SOCKET4677_AZIFS054P001C01-SOCA
P5E_CPU1_PE1_TX_DP<9>    C723             2        Q_CAP_DIFFBUS_C0201-DIFF BUS_0A
P5E_CPU1_PE1_TX_DP<9>    U1               CC15     SOCKET4677_AZIFS054P001C01-SOCA
P5E_CPU1_PE1_TX_DP<10>   C721             2        Q_CAP_DIFFBUS_C0201-DIFF BUS_0A
P5E_CPU1_PE1_TX_DP<10>   U1               CD14     SOCKET4677_AZIFS054P001C01-SOCA
P5E_CPU1_PE1_TX_DP<11>   C719             2        Q_CAP_DIFFBUS_C0201-DIFF BUS_0A
P5E_CPU1_PE1_TX_DP<11>   U1               CG15     SOCKET4677_AZIFS054P001C01-SOCA
P5E_CPU1_PE1_TX_DP<12>   C717             2        Q_CAP_DIFFBUS_C0201-DIFF BUS_0A
P5E_CPU1_PE1_TX_DP<12>   U1               CH14     SOCKET4677_AZIFS054P001C01-SOCA
P5E_CPU1_PE1_TX_DP<13>   C715             2        Q_CAP_DIFFBUS_C0201-DIFF BUS_0A
P5E_CPU1_PE1_TX_DP<13>   U1               CL15     SOCKET4677_AZIFS054P001C01-SOCA
P5E_CPU1_PE1_TX_DP<14>   C713             2        Q_CAP_DIFFBUS_C0201-DIFF BUS_0A
P5E_CPU1_PE1_TX_DP<14>   U1               CM14     SOCKET4677_AZIFS054P001C01-SOCA
P5E_CPU1_PE1_TX_DP<15>   C711             2        Q_CAP_DIFFBUS_C0201-DIFF BUS_0A
P5E_CPU1_PE1_TX_DP<15>   U1               CR15     SOCKET4677_AZIFS054P001C01-SOCA
P5E_CPU1_PE2_RX_DN<0>    J89              A133     SCONN280_ME1028040102011-SCONNA
P5E_CPU1_PE2_RX_DN<0>    U1               CU9      SOCKET4677_AZIFS054P001C01-SOCA
P5E_CPU1_PE2_RX_DN<1>    J89              A130     SCONN280_ME1028040102011-SCONNA
P5E_CPU1_PE2_RX_DN<1>    U1               CY10     SOCKET4677_AZIFS054P001C01-SOCA
P5E_CPU1_PE2_RX_DN<2>    J89              A127     SCONN280_ME1028040102011-SCONNA
P5E_CPU1_PE2_RX_DN<2>    U1               DA9      SOCKET4677_AZIFS054P001C01-SOCA
P5E_CPU1_PE2_RX_DN<3>    J89              A124     SCONN280_ME1028040102011-SCONNA
P5E_CPU1_PE2_RX_DN<3>    U1               DD10     SOCKET4677_AZIFS054P001C01-SOCA
P5E_CPU1_PE2_RX_DN<4>    J89              A121     SCONN280_ME1028040102011-SCONNA
P5E_CPU1_PE2_RX_DN<4>    U1               DE9      SOCKET4677_AZIFS054P001C01-SOCA
P5E_CPU1_PE2_RX_DN<5>    J89              A118     SCONN280_ME1028040102011-SCONNA
P5E_CPU1_PE2_RX_DN<5>    U1               DH10     SOCKET4677_AZIFS054P001C01-SOCA
P5E_CPU1_PE2_RX_DN<6>    J89              A115     SCONN280_ME1028040102011-SCONNA
P5E_CPU1_PE2_RX_DN<6>    U1               DJ9      SOCKET4677_AZIFS054P001C01-SOCA
P5E_CPU1_PE2_RX_DN<7>    J89              A111     SCONN280_ME1028040102011-SCONNA
P5E_CPU1_PE2_RX_DN<7>    U1               DM10     SOCKET4677_AZIFS054P001C01-SOCA
P5E_CPU1_PE2_RX_DN<8>    J89              A108     SCONN280_ME1028040102011-SCONNA
P5E_CPU1_PE2_RX_DN<8>    U1               DN9      SOCKET4677_AZIFS054P001C01-SOCA
P5E_CPU1_PE2_RX_DN<9>    J89              A105     SCONN280_ME1028040102011-SCONNA
P5E_CPU1_PE2_RX_DN<9>    U1               DT10     SOCKET4677_AZIFS054P001C01-SOCA
P5E_CPU1_PE2_RX_DN<10>   J89              A102     SCONN280_ME1028040102011-SCONNA
P5E_CPU1_PE2_RX_DN<10>   U1               DU9      SOCKET4677_AZIFS054P001C01-SOCA
P5E_CPU1_PE2_RX_DN<11>   J89              A99      SCONN280_ME1028040102011-SCONNA
P5E_CPU1_PE2_RX_DN<11>   U1               DY10     SOCKET4677_AZIFS054P001C01-SOCA
P5E_CPU1_PE2_RX_DN<12>   J89              A96      SCONN280_ME1028040102011-SCONNA
P5E_CPU1_PE2_RX_DN<12>   U1               EA9      SOCKET4677_AZIFS054P001C01-SOCA
P5E_CPU1_PE2_RX_DN<13>   J89              A93      SCONN280_ME1028040102011-SCONNA
P5E_CPU1_PE2_RX_DN<13>   U1               ED10     SOCKET4677_AZIFS054P001C01-SOCA
P5E_CPU1_PE2_RX_DN<14>   J89              A90      SCONN280_ME1028040102011-SCONNA
P5E_CPU1_PE2_RX_DN<14>   U1               EE9      SOCKET4677_AZIFS054P001C01-SOCA
P5E_CPU1_PE2_RX_DN<15>   J89              A87      SCONN280_ME1028040102011-SCONNA
P5E_CPU1_PE2_RX_DN<15>   U1               EH10     SOCKET4677_AZIFS054P001C01-SOCA
P5E_CPU1_PE2_RX_DP<0>    J89              A132     SCONN280_ME1028040102011-SCONNA
P5E_CPU1_PE2_RX_DP<0>    U1               CV10     SOCKET4677_AZIFS054P001C01-SOCA
P5E_CPU1_PE2_RX_DP<1>    J89              A129     SCONN280_ME1028040102011-SCONNA
P5E_CPU1_PE2_RX_DP<1>    U1               CW11     SOCKET4677_AZIFS054P001C01-SOCA
P5E_CPU1_PE2_RX_DP<2>    J89              A126     SCONN280_ME1028040102011-SCONNA
P5E_CPU1_PE2_RX_DP<2>    U1               DB10     SOCKET4677_AZIFS054P001C01-SOCA
P5E_CPU1_PE2_RX_DP<3>    J89              A123     SCONN280_ME1028040102011-SCONNA
P5E_CPU1_PE2_RX_DP<3>    U1               DC11     SOCKET4677_AZIFS054P001C01-SOCA
P5E_CPU1_PE2_RX_DP<4>    J89              A120     SCONN280_ME1028040102011-SCONNA
P5E_CPU1_PE2_RX_DP<4>    U1               DF10     SOCKET4677_AZIFS054P001C01-SOCA
P5E_CPU1_PE2_RX_DP<5>    J89              A117     SCONN280_ME1028040102011-SCONNA
P5E_CPU1_PE2_RX_DP<5>    U1               DG11     SOCKET4677_AZIFS054P001C01-SOCA
P5E_CPU1_PE2_RX_DP<6>    J89              A114     SCONN280_ME1028040102011-SCONNA
P5E_CPU1_PE2_RX_DP<6>    U1               DK10     SOCKET4677_AZIFS054P001C01-SOCA
P5E_CPU1_PE2_RX_DP<7>    J89              A110     SCONN280_ME1028040102011-SCONNA
P5E_CPU1_PE2_RX_DP<7>    U1               DL11     SOCKET4677_AZIFS054P001C01-SOCA
P5E_CPU1_PE2_RX_DP<8>    J89              A107     SCONN280_ME1028040102011-SCONNA
P5E_CPU1_PE2_RX_DP<8>    U1               DP10     SOCKET4677_AZIFS054P001C01-SOCA
P5E_CPU1_PE2_RX_DP<9>    J89              A104     SCONN280_ME1028040102011-SCONNA
P5E_CPU1_PE2_RX_DP<9>    U1               DR11     SOCKET4677_AZIFS054P001C01-SOCA
P5E_CPU1_PE2_RX_DP<10>   J89              A101     SCONN280_ME1028040102011-SCONNA
P5E_CPU1_PE2_RX_DP<10>   U1               DV10     SOCKET4677_AZIFS054P001C01-SOCA
P5E_CPU1_PE2_RX_DP<11>   J89              A98      SCONN280_ME1028040102011-SCONNA
P5E_CPU1_PE2_RX_DP<11>   U1               DW11     SOCKET4677_AZIFS054P001C01-SOCA
P5E_CPU1_PE2_RX_DP<12>   J89              A95      SCONN280_ME1028040102011-SCONNA
P5E_CPU1_PE2_RX_DP<12>   U1               EB10     SOCKET4677_AZIFS054P001C01-SOCA
P5E_CPU1_PE2_RX_DP<13>   J89              A92      SCONN280_ME1028040102011-SCONNA
P5E_CPU1_PE2_RX_DP<13>   U1               EC11     SOCKET4677_AZIFS054P001C01-SOCA
P5E_CPU1_PE2_RX_DP<14>   J89              A89      SCONN280_ME1028040102011-SCONNA
P5E_CPU1_PE2_RX_DP<14>   U1               EF10     SOCKET4677_AZIFS054P001C01-SOCA
P5E_CPU1_PE2_RX_DP<15>   J89              A86      SCONN280_ME1028040102011-SCONNA
P5E_CPU1_PE2_RX_DP<15>   U1               EG11     SOCKET4677_AZIFS054P001C01-SOCA
P5E_CPU1_PE2_TX_C_DN<0>  C772             1        Q_CAP_DIFFBUS_C0201-DIFF BUS_0A
P5E_CPU1_PE2_TX_C_DN<0>  J89              B133     SCONN280_ME1028040102011-SCONNA
P5E_CPU1_PE2_TX_C_DN<1>  C770             1        Q_CAP_DIFFBUS_C0201-DIFF BUS_0A
P5E_CPU1_PE2_TX_C_DN<1>  J89              B130     SCONN280_ME1028040102011-SCONNA
P5E_CPU1_PE2_TX_C_DN<2>  C768             1        Q_CAP_DIFFBUS_C0201-DIFF BUS_0A
P5E_CPU1_PE2_TX_C_DN<2>  J89              B127     SCONN280_ME1028040102011-SCONNA
P5E_CPU1_PE2_TX_C_DN<3>  C766             1        Q_CAP_DIFFBUS_C0201-DIFF BUS_0A
P5E_CPU1_PE2_TX_C_DN<3>  J89              B124     SCONN280_ME1028040102011-SCONNA
P5E_CPU1_PE2_TX_C_DN<4>  C764             1        Q_CAP_DIFFBUS_C0201-DIFF BUS_0A
P5E_CPU1_PE2_TX_C_DN<4>  J89              B121     SCONN280_ME1028040102011-SCONNA
P5E_CPU1_PE2_TX_C_DN<5>  C762             1        Q_CAP_DIFFBUS_C0201-DIFF BUS_0A
P5E_CPU1_PE2_TX_C_DN<5>  J89              B118     SCONN280_ME1028040102011-SCONNA
P5E_CPU1_PE2_TX_C_DN<6>  C760             1        Q_CAP_DIFFBUS_C0201-DIFF BUS_0A
P5E_CPU1_PE2_TX_C_DN<6>  J89              B115     SCONN280_ME1028040102011-SCONNA
P5E_CPU1_PE2_TX_C_DN<7>  C758             1        Q_CAP_DIFFBUS_C0201-DIFF BUS_0A
P5E_CPU1_PE2_TX_C_DN<7>  J89              B111     SCONN280_ME1028040102011-SCONNA
P5E_CPU1_PE2_TX_C_DN<8>  C756             1        Q_CAP_DIFFBUS_C0201-DIFF BUS_0A
P5E_CPU1_PE2_TX_C_DN<8>  J89              B108     SCONN280_ME1028040102011-SCONNA
P5E_CPU1_PE2_TX_C_DN<9>  C754             1        Q_CAP_DIFFBUS_C0201-DIFF BUS_0A
P5E_CPU1_PE2_TX_C_DN<9>  J89              B105     SCONN280_ME1028040102011-SCONNA
P5E_CPU1_PE2_TX_C_DN<10> C752             1        Q_CAP_DIFFBUS_C0201-DIFF BUS_0A
P5E_CPU1_PE2_TX_C_DN<10> J89              B102     SCONN280_ME1028040102011-SCONNA
P5E_CPU1_PE2_TX_C_DN<11> C750             1        Q_CAP_DIFFBUS_C0201-DIFF BUS_0A
P5E_CPU1_PE2_TX_C_DN<11> J89              B99      SCONN280_ME1028040102011-SCONNA
P5E_CPU1_PE2_TX_C_DN<12> C748             1        Q_CAP_DIFFBUS_C0201-DIFF BUS_0A
P5E_CPU1_PE2_TX_C_DN<12> J89              B96      SCONN280_ME1028040102011-SCONNA
P5E_CPU1_PE2_TX_C_DN<13> C746             1        Q_CAP_DIFFBUS_C0201-DIFF BUS_0A
P5E_CPU1_PE2_TX_C_DN<13> J89              B93      SCONN280_ME1028040102011-SCONNA
P5E_CPU1_PE2_TX_C_DN<14> C744             1        Q_CAP_DIFFBUS_C0201-DIFF BUS_0A
P5E_CPU1_PE2_TX_C_DN<14> J89              B90      SCONN280_ME1028040102011-SCONNA
P5E_CPU1_PE2_TX_C_DN<15> C742             1        Q_CAP_DIFFBUS_C0201-DIFF BUS_0A
P5E_CPU1_PE2_TX_C_DN<15> J89              B87      SCONN280_ME1028040102011-SCONNA
P5E_CPU1_PE2_TX_C_DP<0>  C773             1        Q_CAP_DIFFBUS_C0201-DIFF BUS_0A
P5E_CPU1_PE2_TX_C_DP<0>  J89              B132     SCONN280_ME1028040102011-SCONNA
P5E_CPU1_PE2_TX_C_DP<1>  C771             1        Q_CAP_DIFFBUS_C0201-DIFF BUS_0A
P5E_CPU1_PE2_TX_C_DP<1>  J89              B129     SCONN280_ME1028040102011-SCONNA
P5E_CPU1_PE2_TX_C_DP<2>  C769             1        Q_CAP_DIFFBUS_C0201-DIFF BUS_0A
P5E_CPU1_PE2_TX_C_DP<2>  J89              B126     SCONN280_ME1028040102011-SCONNA
P5E_CPU1_PE2_TX_C_DP<3>  C767             1        Q_CAP_DIFFBUS_C0201-DIFF BUS_0A
P5E_CPU1_PE2_TX_C_DP<3>  J89              B123     SCONN280_ME1028040102011-SCONNA
P5E_CPU1_PE2_TX_C_DP<4>  C765             1        Q_CAP_DIFFBUS_C0201-DIFF BUS_0A
P5E_CPU1_PE2_TX_C_DP<4>  J89              B120     SCONN280_ME1028040102011-SCONNA
P5E_CPU1_PE2_TX_C_DP<5>  C763             1        Q_CAP_DIFFBUS_C0201-DIFF BUS_0A
P5E_CPU1_PE2_TX_C_DP<5>  J89              B117     SCONN280_ME1028040102011-SCONNA
P5E_CPU1_PE2_TX_C_DP<6>  C761             1        Q_CAP_DIFFBUS_C0201-DIFF BUS_0A
P5E_CPU1_PE2_TX_C_DP<6>  J89              B114     SCONN280_ME1028040102011-SCONNA
P5E_CPU1_PE2_TX_C_DP<7>  C759             1        Q_CAP_DIFFBUS_C0201-DIFF BUS_0A
P5E_CPU1_PE2_TX_C_DP<7>  J89              B110     SCONN280_ME1028040102011-SCONNA
P5E_CPU1_PE2_TX_C_DP<8>  C757             1        Q_CAP_DIFFBUS_C0201-DIFF BUS_0A
P5E_CPU1_PE2_TX_C_DP<8>  J89              B107     SCONN280_ME1028040102011-SCONNA
P5E_CPU1_PE2_TX_C_DP<9>  C755             1        Q_CAP_DIFFBUS_C0201-DIFF BUS_0A
P5E_CPU1_PE2_TX_C_DP<9>  J89              B104     SCONN280_ME1028040102011-SCONNA
P5E_CPU1_PE2_TX_C_DP<10> C753             1        Q_CAP_DIFFBUS_C0201-DIFF BUS_0A
P5E_CPU1_PE2_TX_C_DP<10> J89              B101     SCONN280_ME1028040102011-SCONNA
P5E_CPU1_PE2_TX_C_DP<11> C751             1        Q_CAP_DIFFBUS_C0201-DIFF BUS_0A
P5E_CPU1_PE2_TX_C_DP<11> J89              B98      SCONN280_ME1028040102011-SCONNA
P5E_CPU1_PE2_TX_C_DP<12> C749             1        Q_CAP_DIFFBUS_C0201-DIFF BUS_0A
P5E_CPU1_PE2_TX_C_DP<12> J89              B95      SCONN280_ME1028040102011-SCONNA
P5E_CPU1_PE2_TX_C_DP<13> C747             1        Q_CAP_DIFFBUS_C0201-DIFF BUS_0A
P5E_CPU1_PE2_TX_C_DP<13> J89              B92      SCONN280_ME1028040102011-SCONNA
P5E_CPU1_PE2_TX_C_DP<14> C745             1        Q_CAP_DIFFBUS_C0201-DIFF BUS_0A
P5E_CPU1_PE2_TX_C_DP<14> J89              B89      SCONN280_ME1028040102011-SCONNA
P5E_CPU1_PE2_TX_C_DP<15> C743             1        Q_CAP_DIFFBUS_C0201-DIFF BUS_0A
P5E_CPU1_PE2_TX_C_DP<15> J89              B86      SCONN280_ME1028040102011-SCONNA
P5E_CPU1_PE2_TX_DN<0>    C772             2        Q_CAP_DIFFBUS_C0201-DIFF BUS_0A
P5E_CPU1_PE2_TX_DN<0>    U1               CU13     SOCKET4677_AZIFS054P001C01-SOCA
P5E_CPU1_PE2_TX_DN<1>    C770             2        Q_CAP_DIFFBUS_C0201-DIFF BUS_0A
P5E_CPU1_PE2_TX_DN<1>    U1               CV14     SOCKET4677_AZIFS054P001C01-SOCA
P5E_CPU1_PE2_TX_DN<2>    C768             2        Q_CAP_DIFFBUS_C0201-DIFF BUS_0A
P5E_CPU1_PE2_TX_DN<2>    U1               DA13     SOCKET4677_AZIFS054P001C01-SOCA
P5E_CPU1_PE2_TX_DN<3>    C766             2        Q_CAP_DIFFBUS_C0201-DIFF BUS_0A
P5E_CPU1_PE2_TX_DN<3>    U1               DB14     SOCKET4677_AZIFS054P001C01-SOCA
P5E_CPU1_PE2_TX_DN<4>    C764             2        Q_CAP_DIFFBUS_C0201-DIFF BUS_0A
P5E_CPU1_PE2_TX_DN<4>    U1               DE13     SOCKET4677_AZIFS054P001C01-SOCA
P5E_CPU1_PE2_TX_DN<5>    C762             2        Q_CAP_DIFFBUS_C0201-DIFF BUS_0A
P5E_CPU1_PE2_TX_DN<5>    U1               DF14     SOCKET4677_AZIFS054P001C01-SOCA
P5E_CPU1_PE2_TX_DN<6>    C760             2        Q_CAP_DIFFBUS_C0201-DIFF BUS_0A
P5E_CPU1_PE2_TX_DN<6>    U1               DJ13     SOCKET4677_AZIFS054P001C01-SOCA
P5E_CPU1_PE2_TX_DN<7>    C758             2        Q_CAP_DIFFBUS_C0201-DIFF BUS_0A
P5E_CPU1_PE2_TX_DN<7>    U1               DK14     SOCKET4677_AZIFS054P001C01-SOCA
P5E_CPU1_PE2_TX_DN<8>    C756             2        Q_CAP_DIFFBUS_C0201-DIFF BUS_0A
P5E_CPU1_PE2_TX_DN<8>    U1               DN13     SOCKET4677_AZIFS054P001C01-SOCA
P5E_CPU1_PE2_TX_DN<9>    C754             2        Q_CAP_DIFFBUS_C0201-DIFF BUS_0A
P5E_CPU1_PE2_TX_DN<9>    U1               DP14     SOCKET4677_AZIFS054P001C01-SOCA
P5E_CPU1_PE2_TX_DN<10>   C752             2        Q_CAP_DIFFBUS_C0201-DIFF BUS_0A
P5E_CPU1_PE2_TX_DN<10>   U1               DU13     SOCKET4677_AZIFS054P001C01-SOCA
P5E_CPU1_PE2_TX_DN<11>   C750             2        Q_CAP_DIFFBUS_C0201-DIFF BUS_0A
P5E_CPU1_PE2_TX_DN<11>   U1               DV14     SOCKET4677_AZIFS054P001C01-SOCA
P5E_CPU1_PE2_TX_DN<12>   C748             2        Q_CAP_DIFFBUS_C0201-DIFF BUS_0A
P5E_CPU1_PE2_TX_DN<12>   U1               EA13     SOCKET4677_AZIFS054P001C01-SOCA
P5E_CPU1_PE2_TX_DN<13>   C746             2        Q_CAP_DIFFBUS_C0201-DIFF BUS_0A
P5E_CPU1_PE2_TX_DN<13>   U1               EB14     SOCKET4677_AZIFS054P001C01-SOCA
P5E_CPU1_PE2_TX_DN<14>   C744             2        Q_CAP_DIFFBUS_C0201-DIFF BUS_0A
P5E_CPU1_PE2_TX_DN<14>   U1               EE13     SOCKET4677_AZIFS054P001C01-SOCA
P5E_CPU1_PE2_TX_DN<15>   C742             2        Q_CAP_DIFFBUS_C0201-DIFF BUS_0A
P5E_CPU1_PE2_TX_DN<15>   U1               EF14     SOCKET4677_AZIFS054P001C01-SOCA
P5E_CPU1_PE2_TX_DP<0>    C773             2        Q_CAP_DIFFBUS_C0201-DIFF BUS_0A
P5E_CPU1_PE2_TX_DP<0>    U1               CT14     SOCKET4677_AZIFS054P001C01-SOCA
P5E_CPU1_PE2_TX_DP<1>    C771             2        Q_CAP_DIFFBUS_C0201-DIFF BUS_0A
P5E_CPU1_PE2_TX_DP<1>    U1               CW15     SOCKET4677_AZIFS054P001C01-SOCA
P5E_CPU1_PE2_TX_DP<2>    C769             2        Q_CAP_DIFFBUS_C0201-DIFF BUS_0A
P5E_CPU1_PE2_TX_DP<2>    U1               CY14     SOCKET4677_AZIFS054P001C01-SOCA
P5E_CPU1_PE2_TX_DP<3>    C767             2        Q_CAP_DIFFBUS_C0201-DIFF BUS_0A
P5E_CPU1_PE2_TX_DP<3>    U1               DC15     SOCKET4677_AZIFS054P001C01-SOCA
P5E_CPU1_PE2_TX_DP<4>    C765             2        Q_CAP_DIFFBUS_C0201-DIFF BUS_0A
P5E_CPU1_PE2_TX_DP<4>    U1               DD14     SOCKET4677_AZIFS054P001C01-SOCA
P5E_CPU1_PE2_TX_DP<5>    C763             2        Q_CAP_DIFFBUS_C0201-DIFF BUS_0A
P5E_CPU1_PE2_TX_DP<5>    U1               DG15     SOCKET4677_AZIFS054P001C01-SOCA
P5E_CPU1_PE2_TX_DP<6>    C761             2        Q_CAP_DIFFBUS_C0201-DIFF BUS_0A
P5E_CPU1_PE2_TX_DP<6>    U1               DH14     SOCKET4677_AZIFS054P001C01-SOCA
P5E_CPU1_PE2_TX_DP<7>    C759             2        Q_CAP_DIFFBUS_C0201-DIFF BUS_0A
P5E_CPU1_PE2_TX_DP<7>    U1               DL15     SOCKET4677_AZIFS054P001C01-SOCA
P5E_CPU1_PE2_TX_DP<8>    C757             2        Q_CAP_DIFFBUS_C0201-DIFF BUS_0A
P5E_CPU1_PE2_TX_DP<8>    U1               DM14     SOCKET4677_AZIFS054P001C01-SOCA
P5E_CPU1_PE2_TX_DP<9>    C755             2        Q_CAP_DIFFBUS_C0201-DIFF BUS_0A
P5E_CPU1_PE2_TX_DP<9>    U1               DR15     SOCKET4677_AZIFS054P001C01-SOCA
P5E_CPU1_PE2_TX_DP<10>   C753             2        Q_CAP_DIFFBUS_C0201-DIFF BUS_0A
P5E_CPU1_PE2_TX_DP<10>   U1               DT14     SOCKET4677_AZIFS054P001C01-SOCA
P5E_CPU1_PE2_TX_DP<11>   C751             2        Q_CAP_DIFFBUS_C0201-DIFF BUS_0A
P5E_CPU1_PE2_TX_DP<11>   U1               DW15     SOCKET4677_AZIFS054P001C01-SOCA
P5E_CPU1_PE2_TX_DP<12>   C749             2        Q_CAP_DIFFBUS_C0201-DIFF BUS_0A
P5E_CPU1_PE2_TX_DP<12>   U1               DY14     SOCKET4677_AZIFS054P001C01-SOCA
P5E_CPU1_PE2_TX_DP<13>   C747             2        Q_CAP_DIFFBUS_C0201-DIFF BUS_0A
P5E_CPU1_PE2_TX_DP<13>   U1               EC15     SOCKET4677_AZIFS054P001C01-SOCA
P5E_CPU1_PE2_TX_DP<14>   C745             2        Q_CAP_DIFFBUS_C0201-DIFF BUS_0A
P5E_CPU1_PE2_TX_DP<14>   U1               ED14     SOCKET4677_AZIFS054P001C01-SOCA
P5E_CPU1_PE2_TX_DP<15>   C743             2        Q_CAP_DIFFBUS_C0201-DIFF BUS_0A
P5E_CPU1_PE2_TX_DP<15>   U1               EG15     SOCKET4677_AZIFS054P001C01-SOCA
P5E_CPU1_PE3_RX_DN<0>    J35              A21      SCONN140_G64V3431BHR-SCONN140_B
P5E_CPU1_PE3_RX_DN<0>    U1               EH89     SOCKET4677_AZIFS054P001C01-SOCA
P5E_CPU1_PE3_RX_DN<1>    J35              A24      SCONN140_G64V3431BHR-SCONN140_B
P5E_CPU1_PE3_RX_DN<1>    U1               ED91     SOCKET4677_AZIFS054P001C01-SOCA
P5E_CPU1_PE3_RX_DN<2>    J35              A26      SCONN140_G64V3431BHR-SCONN140_B
P5E_CPU1_PE3_RX_DN<2>    U1               EC90     SOCKET4677_AZIFS054P001C01-SOCA
P5E_CPU1_PE3_RX_DN<3>    J35              A31      SCONN140_G64V3431BHR-SCONN140_B
P5E_CPU1_PE3_RX_DN<3>    U1               DY91     SOCKET4677_AZIFS054P001C01-SOCA
P5E_CPU1_PE3_RX_DN<4>    J35              A34      SCONN140_G64V3431BHR-SCONN140_B
P5E_CPU1_PE3_RX_DN<4>    U1               DV89     SOCKET4677_AZIFS054P001C01-SOCA
P5E_CPU1_PE3_RX_DN<5>    J35              A36      SCONN140_G64V3431BHR-SCONN140_B
P5E_CPU1_PE3_RX_DN<5>    U1               DU90     SOCKET4677_AZIFS054P001C01-SOCA
P5E_CPU1_PE3_RX_DN<6>    J35              A40      SCONN140_G64V3431BHR-SCONN140_B
P5E_CPU1_PE3_RX_DN<6>    U1               DP89     SOCKET4677_AZIFS054P001C01-SOCA
P5E_CPU1_PE3_RX_DN<7>    J35              A44      SCONN140_G64V3431BHR-SCONN140_B
P5E_CPU1_PE3_RX_DN<7>    U1               DN90     SOCKET4677_AZIFS054P001C01-SOCA
P5E_CPU1_PE3_RX_DN<8>    J35              A47      SCONN140_G64V3431BHR-SCONN140_B
P5E_CPU1_PE3_RX_DN<8>    U1               DL90     SOCKET4677_AZIFS054P001C01-SOCA
P5E_CPU1_PE3_RX_DN<9>    J35              A51      SCONN140_G64V3431BHR-SCONN140_B
P5E_CPU1_PE3_RX_DN<9>    U1               DH91     SOCKET4677_AZIFS054P001C01-SOCA
P5E_CPU1_PE3_RX_DN<10>   J35              A53      SCONN140_G64V3431BHR-SCONN140_B
P5E_CPU1_PE3_RX_DN<10>   U1               DG90     SOCKET4677_AZIFS054P001C01-SOCA
P5E_CPU1_PE3_RX_DN<11>   J35              A57      SCONN140_G64V3431BHR-SCONN140_B
P5E_CPU1_PE3_RX_DN<11>   U1               DD91     SOCKET4677_AZIFS054P001C01-SOCA
P5E_CPU1_PE3_RX_DN<12>   J35              A60      SCONN140_G64V3431BHR-SCONN140_B
P5E_CPU1_PE3_RX_DN<12>   U1               DB89     SOCKET4677_AZIFS054P001C01-SOCA
P5E_CPU1_PE3_RX_DN<13>   J35              A62      SCONN140_G64V3431BHR-SCONN140_B
P5E_CPU1_PE3_RX_DN<13>   U1               DA90     SOCKET4677_AZIFS054P001C01-SOCA
P5E_CPU1_PE3_RX_DN<14>   J35              A66      SCONN140_G64V3431BHR-SCONN140_B
P5E_CPU1_PE3_RX_DN<14>   U1               CV89     SOCKET4677_AZIFS054P001C01-SOCA
P5E_CPU1_PE3_RX_DN<15>   J35              A68      SCONN140_G64V3431BHR-SCONN140_B
P5E_CPU1_PE3_RX_DN<15>   U1               CU90     SOCKET4677_AZIFS054P001C01-SOCA
P5E_CPU1_PE3_RX_DP<0>    J35              A20      SCONN140_G64V3431BHR-SCONN140_B
P5E_CPU1_PE3_RX_DP<0>    U1               EJ90     SOCKET4677_AZIFS054P001C01-SOCA
P5E_CPU1_PE3_RX_DP<1>    J35              A23      SCONN140_G64V3431BHR-SCONN140_B
P5E_CPU1_PE3_RX_DP<1>    U1               EE90     SOCKET4677_AZIFS054P001C01-SOCA
P5E_CPU1_PE3_RX_DP<2>    J35              A27      SCONN140_G64V3431BHR-SCONN140_B
P5E_CPU1_PE3_RX_DP<2>    U1               EB89     SOCKET4677_AZIFS054P001C01-SOCA
P5E_CPU1_PE3_RX_DP<3>    J35              A30      SCONN140_G64V3431BHR-SCONN140_B
P5E_CPU1_PE3_RX_DP<3>    U1               EA90     SOCKET4677_AZIFS054P001C01-SOCA
P5E_CPU1_PE3_RX_DP<4>    J35              A33      SCONN140_G64V3431BHR-SCONN140_B
P5E_CPU1_PE3_RX_DP<4>    U1               DW90     SOCKET4677_AZIFS054P001C01-SOCA
P5E_CPU1_PE3_RX_DP<5>    J35              A37      SCONN140_G64V3431BHR-SCONN140_B
P5E_CPU1_PE3_RX_DP<5>    U1               DT91     SOCKET4677_AZIFS054P001C01-SOCA
P5E_CPU1_PE3_RX_DP<6>    J35              A39      SCONN140_G64V3431BHR-SCONN140_B
P5E_CPU1_PE3_RX_DP<6>    U1               DR90     SOCKET4677_AZIFS054P001C01-SOCA
P5E_CPU1_PE3_RX_DP<7>    J35              A45      SCONN140_G64V3431BHR-SCONN140_B
P5E_CPU1_PE3_RX_DP<7>    U1               DM91     SOCKET4677_AZIFS054P001C01-SOCA
P5E_CPU1_PE3_RX_DP<8>    J35              A48      SCONN140_G64V3431BHR-SCONN140_B
P5E_CPU1_PE3_RX_DP<8>    U1               DK89     SOCKET4677_AZIFS054P001C01-SOCA
P5E_CPU1_PE3_RX_DP<9>    J35              A50      SCONN140_G64V3431BHR-SCONN140_B
P5E_CPU1_PE3_RX_DP<9>    U1               DJ90     SOCKET4677_AZIFS054P001C01-SOCA
P5E_CPU1_PE3_RX_DP<10>   J35              A54      SCONN140_G64V3431BHR-SCONN140_B
P5E_CPU1_PE3_RX_DP<10>   U1               DF89     SOCKET4677_AZIFS054P001C01-SOCA
P5E_CPU1_PE3_RX_DP<11>   J35              A56      SCONN140_G64V3431BHR-SCONN140_B
P5E_CPU1_PE3_RX_DP<11>   U1               DE90     SOCKET4677_AZIFS054P001C01-SOCA
P5E_CPU1_PE3_RX_DP<12>   J35              A59      SCONN140_G64V3431BHR-SCONN140_B
P5E_CPU1_PE3_RX_DP<12>   U1               DC90     SOCKET4677_AZIFS054P001C01-SOCA
P5E_CPU1_PE3_RX_DP<13>   J35              A63      SCONN140_G64V3431BHR-SCONN140_B
P5E_CPU1_PE3_RX_DP<13>   U1               CY91     SOCKET4677_AZIFS054P001C01-SOCA
P5E_CPU1_PE3_RX_DP<14>   J35              A65      SCONN140_G64V3431BHR-SCONN140_B
P5E_CPU1_PE3_RX_DP<14>   U1               CW90     SOCKET4677_AZIFS054P001C01-SOCA
P5E_CPU1_PE3_RX_DP<15>   J35              A69      SCONN140_G64V3431BHR-SCONN140_B
P5E_CPU1_PE3_RX_DP<15>   U1               CT91     SOCKET4677_AZIFS054P001C01-SOCA
P5E_CPU1_PE3_TX_C_DN<0>  C1546            1        Q_CAP_DIFFBUS_C0201-DIFF BUS_0A
P5E_CPU1_PE3_TX_C_DN<0>  J35              B20      SCONN140_G64V3431BHR-SCONN140_B
P5E_CPU1_PE3_TX_C_DN<1>  C1544            1        Q_CAP_DIFFBUS_C0201-DIFF BUS_0A
P5E_CPU1_PE3_TX_C_DN<1>  J35              B24      SCONN140_G64V3431BHR-SCONN140_B
P5E_CPU1_PE3_TX_C_DN<2>  C1542            1        Q_CAP_DIFFBUS_C0201-DIFF BUS_0A
P5E_CPU1_PE3_TX_C_DN<2>  J35              B27      SCONN140_G64V3431BHR-SCONN140_B
P5E_CPU1_PE3_TX_C_DN<3>  C1540            1        Q_CAP_DIFFBUS_C0201-DIFF BUS_0A
P5E_CPU1_PE3_TX_C_DN<3>  J35              B31      SCONN140_G64V3431BHR-SCONN140_B
P5E_CPU1_PE3_TX_C_DN<4>  C1538            1        Q_CAP_DIFFBUS_C0201-DIFF BUS_0A
P5E_CPU1_PE3_TX_C_DN<4>  J35              B34      SCONN140_G64V3431BHR-SCONN140_B
P5E_CPU1_PE3_TX_C_DN<5>  C1536            1        Q_CAP_DIFFBUS_C0201-DIFF BUS_0A
P5E_CPU1_PE3_TX_C_DN<5>  J35              B37      SCONN140_G64V3431BHR-SCONN140_B
P5E_CPU1_PE3_TX_C_DN<6>  C1534            1        Q_CAP_DIFFBUS_C0201-DIFF BUS_0A
P5E_CPU1_PE3_TX_C_DN<6>  J35              B40      SCONN140_G64V3431BHR-SCONN140_B
P5E_CPU1_PE3_TX_C_DN<7>  C1532            1        Q_CAP_DIFFBUS_C0201-DIFF BUS_0A
P5E_CPU1_PE3_TX_C_DN<7>  J35              B45      SCONN140_G64V3431BHR-SCONN140_B
P5E_CPU1_PE3_TX_C_DN<8>  C1530            1        Q_CAP_DIFFBUS_C0201-DIFF BUS_0A
P5E_CPU1_PE3_TX_C_DN<8>  J35              B48      SCONN140_G64V3431BHR-SCONN140_B
P5E_CPU1_PE3_TX_C_DN<9>  C1528            1        Q_CAP_DIFFBUS_C0201-DIFF BUS_0A
P5E_CPU1_PE3_TX_C_DN<9>  J35              B51      SCONN140_G64V3431BHR-SCONN140_B
P5E_CPU1_PE3_TX_C_DN<10> C1526            1        Q_CAP_DIFFBUS_C0201-DIFF BUS_0A
P5E_CPU1_PE3_TX_C_DN<10> J35              B54      SCONN140_G64V3431BHR-SCONN140_B
P5E_CPU1_PE3_TX_C_DN<11> C1524            1        Q_CAP_DIFFBUS_C0201-DIFF BUS_0A
P5E_CPU1_PE3_TX_C_DN<11> J35              B57      SCONN140_G64V3431BHR-SCONN140_B
P5E_CPU1_PE3_TX_C_DN<12> C1522            1        Q_CAP_DIFFBUS_C0201-DIFF BUS_0A
P5E_CPU1_PE3_TX_C_DN<12> J35              B60      SCONN140_G64V3431BHR-SCONN140_B
P5E_CPU1_PE3_TX_C_DN<13> C1520            1        Q_CAP_DIFFBUS_C0201-DIFF BUS_0A
P5E_CPU1_PE3_TX_C_DN<13> J35              B63      SCONN140_G64V3431BHR-SCONN140_B
P5E_CPU1_PE3_TX_C_DN<14> C1518            1        Q_CAP_DIFFBUS_C0201-DIFF BUS_0A
P5E_CPU1_PE3_TX_C_DN<14> J35              B66      SCONN140_G64V3431BHR-SCONN140_B
P5E_CPU1_PE3_TX_C_DN<15> C1516            1        Q_CAP_DIFFBUS_C0201-DIFF BUS_0A
P5E_CPU1_PE3_TX_C_DN<15> J35              B69      SCONN140_G64V3431BHR-SCONN140_B
P5E_CPU1_PE3_TX_C_DP<0>  C1547            1        Q_CAP_DIFFBUS_C0201-DIFF BUS_0A
P5E_CPU1_PE3_TX_C_DP<0>  J35              B21      SCONN140_G64V3431BHR-SCONN140_B
P5E_CPU1_PE3_TX_C_DP<1>  C1545            1        Q_CAP_DIFFBUS_C0201-DIFF BUS_0A
P5E_CPU1_PE3_TX_C_DP<1>  J35              B23      SCONN140_G64V3431BHR-SCONN140_B
P5E_CPU1_PE3_TX_C_DP<2>  C1543            1        Q_CAP_DIFFBUS_C0201-DIFF BUS_0A
P5E_CPU1_PE3_TX_C_DP<2>  J35              B26      SCONN140_G64V3431BHR-SCONN140_B
P5E_CPU1_PE3_TX_C_DP<3>  C1541            1        Q_CAP_DIFFBUS_C0201-DIFF BUS_0A
P5E_CPU1_PE3_TX_C_DP<3>  J35              B30      SCONN140_G64V3431BHR-SCONN140_B
P5E_CPU1_PE3_TX_C_DP<4>  C1539            1        Q_CAP_DIFFBUS_C0201-DIFF BUS_0A
P5E_CPU1_PE3_TX_C_DP<4>  J35              B33      SCONN140_G64V3431BHR-SCONN140_B
P5E_CPU1_PE3_TX_C_DP<5>  C1537            1        Q_CAP_DIFFBUS_C0201-DIFF BUS_0A
P5E_CPU1_PE3_TX_C_DP<5>  J35              B36      SCONN140_G64V3431BHR-SCONN140_B
P5E_CPU1_PE3_TX_C_DP<6>  C1535            1        Q_CAP_DIFFBUS_C0201-DIFF BUS_0A
P5E_CPU1_PE3_TX_C_DP<6>  J35              B39      SCONN140_G64V3431BHR-SCONN140_B
P5E_CPU1_PE3_TX_C_DP<7>  C1533            1        Q_CAP_DIFFBUS_C0201-DIFF BUS_0A
P5E_CPU1_PE3_TX_C_DP<7>  J35              B44      SCONN140_G64V3431BHR-SCONN140_B
P5E_CPU1_PE3_TX_C_DP<8>  C1531            1        Q_CAP_DIFFBUS_C0201-DIFF BUS_0A
P5E_CPU1_PE3_TX_C_DP<8>  J35              B47      SCONN140_G64V3431BHR-SCONN140_B
P5E_CPU1_PE3_TX_C_DP<9>  C1529            1        Q_CAP_DIFFBUS_C0201-DIFF BUS_0A
P5E_CPU1_PE3_TX_C_DP<9>  J35              B50      SCONN140_G64V3431BHR-SCONN140_B
P5E_CPU1_PE3_TX_C_DP<10> C1527            1        Q_CAP_DIFFBUS_C0201-DIFF BUS_0A
P5E_CPU1_PE3_TX_C_DP<10> J35              B53      SCONN140_G64V3431BHR-SCONN140_B
P5E_CPU1_PE3_TX_C_DP<11> C1525            1        Q_CAP_DIFFBUS_C0201-DIFF BUS_0A
P5E_CPU1_PE3_TX_C_DP<11> J35              B56      SCONN140_G64V3431BHR-SCONN140_B
P5E_CPU1_PE3_TX_C_DP<12> C1523            1        Q_CAP_DIFFBUS_C0201-DIFF BUS_0A
P5E_CPU1_PE3_TX_C_DP<12> J35              B59      SCONN140_G64V3431BHR-SCONN140_B
P5E_CPU1_PE3_TX_C_DP<13> C1521            1        Q_CAP_DIFFBUS_C0201-DIFF BUS_0A
P5E_CPU1_PE3_TX_C_DP<13> J35              B62      SCONN140_G64V3431BHR-SCONN140_B
P5E_CPU1_PE3_TX_C_DP<14> C1519            1        Q_CAP_DIFFBUS_C0201-DIFF BUS_0A
P5E_CPU1_PE3_TX_C_DP<14> J35              B65      SCONN140_G64V3431BHR-SCONN140_B
P5E_CPU1_PE3_TX_C_DP<15> C1517            1        Q_CAP_DIFFBUS_C0201-DIFF BUS_0A
P5E_CPU1_PE3_TX_C_DP<15> J35              B68      SCONN140_G64V3431BHR-SCONN140_B
P5E_CPU1_PE3_TX_DN<0>    C1546            2        Q_CAP_DIFFBUS_C0201-DIFF BUS_0A
P5E_CPU1_PE3_TX_DN<0>    U1               EE86     SOCKET4677_AZIFS054P001C01-SOCA
P5E_CPU1_PE3_TX_DN<1>    C1544            2        Q_CAP_DIFFBUS_C0201-DIFF BUS_0A
P5E_CPU1_PE3_TX_DN<1>    U1               EB85     SOCKET4677_AZIFS054P001C01-SOCA
P5E_CPU1_PE3_TX_DN<2>    C1542            2        Q_CAP_DIFFBUS_C0201-DIFF BUS_0A
P5E_CPU1_PE3_TX_DN<2>    U1               DY87     SOCKET4677_AZIFS054P001C01-SOCA
P5E_CPU1_PE3_TX_DN<3>    C1540            2        Q_CAP_DIFFBUS_C0201-DIFF BUS_0A
P5E_CPU1_PE3_TX_DN<3>    U1               DV85     SOCKET4677_AZIFS054P001C01-SOCA
P5E_CPU1_PE3_TX_DN<4>    C1538            2        Q_CAP_DIFFBUS_C0201-DIFF BUS_0A
P5E_CPU1_PE3_TX_DN<4>    U1               DT87     SOCKET4677_AZIFS054P001C01-SOCA
P5E_CPU1_PE3_TX_DN<5>    C1536            2        Q_CAP_DIFFBUS_C0201-DIFF BUS_0A
P5E_CPU1_PE3_TX_DN<5>    U1               DP85     SOCKET4677_AZIFS054P001C01-SOCA
P5E_CPU1_PE3_TX_DN<6>    C1534            2        Q_CAP_DIFFBUS_C0201-DIFF BUS_0A
P5E_CPU1_PE3_TX_DN<6>    U1               DM87     SOCKET4677_AZIFS054P001C01-SOCA
P5E_CPU1_PE3_TX_DN<7>    C1532            2        Q_CAP_DIFFBUS_C0201-DIFF BUS_0A
P5E_CPU1_PE3_TX_DN<7>    U1               DK85     SOCKET4677_AZIFS054P001C01-SOCA
P5E_CPU1_PE3_TX_DN<8>    C1530            2        Q_CAP_DIFFBUS_C0201-DIFF BUS_0A
P5E_CPU1_PE3_TX_DN<8>    U1               DH87     SOCKET4677_AZIFS054P001C01-SOCA
P5E_CPU1_PE3_TX_DN<9>    C1528            2        Q_CAP_DIFFBUS_C0201-DIFF BUS_0A
P5E_CPU1_PE3_TX_DN<9>    U1               DF85     SOCKET4677_AZIFS054P001C01-SOCA
P5E_CPU1_PE3_TX_DN<10>   C1526            2        Q_CAP_DIFFBUS_C0201-DIFF BUS_0A
P5E_CPU1_PE3_TX_DN<10>   U1               DD87     SOCKET4677_AZIFS054P001C01-SOCA
P5E_CPU1_PE3_TX_DN<11>   C1524            2        Q_CAP_DIFFBUS_C0201-DIFF BUS_0A
P5E_CPU1_PE3_TX_DN<11>   U1               DB85     SOCKET4677_AZIFS054P001C01-SOCA
P5E_CPU1_PE3_TX_DN<12>   C1522            2        Q_CAP_DIFFBUS_C0201-DIFF BUS_0A
P5E_CPU1_PE3_TX_DN<12>   U1               CY87     SOCKET4677_AZIFS054P001C01-SOCA
P5E_CPU1_PE3_TX_DN<13>   C1520            2        Q_CAP_DIFFBUS_C0201-DIFF BUS_0A
P5E_CPU1_PE3_TX_DN<13>   U1               CV85     SOCKET4677_AZIFS054P001C01-SOCA
P5E_CPU1_PE3_TX_DN<14>   C1518            2        Q_CAP_DIFFBUS_C0201-DIFF BUS_0A
P5E_CPU1_PE3_TX_DN<14>   U1               CT87     SOCKET4677_AZIFS054P001C01-SOCA
P5E_CPU1_PE3_TX_DN<15>   C1516            2        Q_CAP_DIFFBUS_C0201-DIFF BUS_0A
P5E_CPU1_PE3_TX_DN<15>   U1               CP85     SOCKET4677_AZIFS054P001C01-SOCA
P5E_CPU1_PE3_TX_DP<0>    C1547            2        Q_CAP_DIFFBUS_C0201-DIFF BUS_0A
P5E_CPU1_PE3_TX_DP<0>    U1               ED87     SOCKET4677_AZIFS054P001C01-SOCA
P5E_CPU1_PE3_TX_DP<1>    C1545            2        Q_CAP_DIFFBUS_C0201-DIFF BUS_0A
P5E_CPU1_PE3_TX_DP<1>    U1               EC86     SOCKET4677_AZIFS054P001C01-SOCA
P5E_CPU1_PE3_TX_DP<2>    C1543            2        Q_CAP_DIFFBUS_C0201-DIFF BUS_0A
P5E_CPU1_PE3_TX_DP<2>    U1               EA86     SOCKET4677_AZIFS054P001C01-SOCA
P5E_CPU1_PE3_TX_DP<3>    C1541            2        Q_CAP_DIFFBUS_C0201-DIFF BUS_0A
P5E_CPU1_PE3_TX_DP<3>    U1               DW86     SOCKET4677_AZIFS054P001C01-SOCA
P5E_CPU1_PE3_TX_DP<4>    C1539            2        Q_CAP_DIFFBUS_C0201-DIFF BUS_0A
P5E_CPU1_PE3_TX_DP<4>    U1               DU86     SOCKET4677_AZIFS054P001C01-SOCA
P5E_CPU1_PE3_TX_DP<5>    C1537            2        Q_CAP_DIFFBUS_C0201-DIFF BUS_0A
P5E_CPU1_PE3_TX_DP<5>    U1               DR86     SOCKET4677_AZIFS054P001C01-SOCA
P5E_CPU1_PE3_TX_DP<6>    C1535            2        Q_CAP_DIFFBUS_C0201-DIFF BUS_0A
P5E_CPU1_PE3_TX_DP<6>    U1               DN86     SOCKET4677_AZIFS054P001C01-SOCA
P5E_CPU1_PE3_TX_DP<7>    C1533            2        Q_CAP_DIFFBUS_C0201-DIFF BUS_0A
P5E_CPU1_PE3_TX_DP<7>    U1               DL86     SOCKET4677_AZIFS054P001C01-SOCA
P5E_CPU1_PE3_TX_DP<8>    C1531            2        Q_CAP_DIFFBUS_C0201-DIFF BUS_0A
P5E_CPU1_PE3_TX_DP<8>    U1               DJ86     SOCKET4677_AZIFS054P001C01-SOCA
P5E_CPU1_PE3_TX_DP<9>    C1529            2        Q_CAP_DIFFBUS_C0201-DIFF BUS_0A
P5E_CPU1_PE3_TX_DP<9>    U1               DG86     SOCKET4677_AZIFS054P001C01-SOCA
P5E_CPU1_PE3_TX_DP<10>   C1527            2        Q_CAP_DIFFBUS_C0201-DIFF BUS_0A
P5E_CPU1_PE3_TX_DP<10>   U1               DE86     SOCKET4677_AZIFS054P001C01-SOCA
P5E_CPU1_PE3_TX_DP<11>   C1525            2        Q_CAP_DIFFBUS_C0201-DIFF BUS_0A
P5E_CPU1_PE3_TX_DP<11>   U1               DC86     SOCKET4677_AZIFS054P001C01-SOCA
P5E_CPU1_PE3_TX_DP<12>   C1523            2        Q_CAP_DIFFBUS_C0201-DIFF BUS_0A
P5E_CPU1_PE3_TX_DP<12>   U1               DA86     SOCKET4677_AZIFS054P001C01-SOCA
P5E_CPU1_PE3_TX_DP<13>   C1521            2        Q_CAP_DIFFBUS_C0201-DIFF BUS_0A
P5E_CPU1_PE3_TX_DP<13>   U1               CW86     SOCKET4677_AZIFS054P001C01-SOCA
P5E_CPU1_PE3_TX_DP<14>   C1519            2        Q_CAP_DIFFBUS_C0201-DIFF BUS_0A
P5E_CPU1_PE3_TX_DP<14>   U1               CU86     SOCKET4677_AZIFS054P001C01-SOCA
P5E_CPU1_PE3_TX_DP<15>   C1517            2        Q_CAP_DIFFBUS_C0201-DIFF BUS_0A
P5E_CPU1_PE3_TX_DP<15>   U1               CR86     SOCKET4677_AZIFS054P001C01-SOCA
P5E_CPU1_PE4_RX_DN<0>    J88              A18      SCONN84_123318136-SCONN84_1-23A
P5E_CPU1_PE4_RX_DN<0>    U1               BB89     SOCKET4677_AZIFS054P001C01-SOCA
P5E_CPU1_PE4_RX_DN<1>    J88              A21      SCONN84_123318136-SCONN84_1-23A
P5E_CPU1_PE4_RX_DN<1>    U1               AY91     SOCKET4677_AZIFS054P001C01-SOCA
P5E_CPU1_PE4_RX_DN<2>    J88              A23      SCONN84_123318136-SCONN84_1-23A
P5E_CPU1_PE4_RX_DN<2>    U1               AV89     SOCKET4677_AZIFS054P001C01-SOCA
P5E_CPU1_PE4_RX_DN<3>    J88              A27      SCONN84_123318136-SCONN84_1-23A
P5E_CPU1_PE4_RX_DN<3>    U1               AT91     SOCKET4677_AZIFS054P001C01-SOCA
P5E_CPU1_PE4_RX_DN<4>    J88              A31      SCONN84_123318136-SCONN84_1-23A
P5E_CPU1_PE4_RX_DN<4>    U1               AP89     SOCKET4677_AZIFS054P001C01-SOCA
P5E_CPU1_PE4_RX_DN<5>    J88              A33      SCONN84_123318136-SCONN84_1-23A
P5E_CPU1_PE4_RX_DN<5>    U1               AM91     SOCKET4677_AZIFS054P001C01-SOCA
P5E_CPU1_PE4_RX_DN<6>    J88              A37      SCONN84_123318136-SCONN84_1-23A
P5E_CPU1_PE4_RX_DN<6>    U1               AK89     SOCKET4677_AZIFS054P001C01-SOCA
P5E_CPU1_PE4_RX_DN<7>    J88              A39      SCONN84_123318136-SCONN84_1-23A
P5E_CPU1_PE4_RX_DN<7>    U1               AH91     SOCKET4677_AZIFS054P001C01-SOCA
P5E_CPU1_PE4_RX_DN<8>    J61              A17      SCONN84_123318136-SCONN84_1-23A
P5E_CPU1_PE4_RX_DN<8>    U1               AF89     SOCKET4677_AZIFS054P001C01-SOCA
P5E_CPU1_PE4_RX_DN<9>    J61              A21      SCONN84_123318136-SCONN84_1-23A
P5E_CPU1_PE4_RX_DN<9>    U1               AD91     SOCKET4677_AZIFS054P001C01-SOCA
P5E_CPU1_PE4_RX_DN<10>   J61              A23      SCONN84_123318136-SCONN84_1-23A
P5E_CPU1_PE4_RX_DN<10>   U1               AB89     SOCKET4677_AZIFS054P001C01-SOCA
P5E_CPU1_PE4_RX_DN<11>   J61              A27      SCONN84_123318136-SCONN84_1-23A
P5E_CPU1_PE4_RX_DN<11>   U1               Y91      SOCKET4677_AZIFS054P001C01-SOCA
P5E_CPU1_PE4_RX_DN<12>   J61              A31      SCONN84_123318136-SCONN84_1-23A
P5E_CPU1_PE4_RX_DN<12>   U1               V89      SOCKET4677_AZIFS054P001C01-SOCA
P5E_CPU1_PE4_RX_DN<13>   J61              A33      SCONN84_123318136-SCONN84_1-23A
P5E_CPU1_PE4_RX_DN<13>   U1               T91      SOCKET4677_AZIFS054P001C01-SOCA
P5E_CPU1_PE4_RX_DN<14>   J61              A37      SCONN84_123318136-SCONN84_1-23A
P5E_CPU1_PE4_RX_DN<14>   U1               P89      SOCKET4677_AZIFS054P001C01-SOCA
P5E_CPU1_PE4_RX_DN<15>   J61              A39      SCONN84_123318136-SCONN84_1-23A
P5E_CPU1_PE4_RX_DN<15>   U1               J90      SOCKET4677_AZIFS054P001C01-SOCA
P5E_CPU1_PE4_RX_DP<0>    J88              A17      SCONN84_123318136-SCONN84_1-23A
P5E_CPU1_PE4_RX_DP<0>    U1               BA90     SOCKET4677_AZIFS054P001C01-SOCA
P5E_CPU1_PE4_RX_DP<1>    J88              A20      SCONN84_123318136-SCONN84_1-23A
P5E_CPU1_PE4_RX_DP<1>    U1               AW90     SOCKET4677_AZIFS054P001C01-SOCA
P5E_CPU1_PE4_RX_DP<2>    J88              A24      SCONN84_123318136-SCONN84_1-23A
P5E_CPU1_PE4_RX_DP<2>    U1               AU90     SOCKET4677_AZIFS054P001C01-SOCA
P5E_CPU1_PE4_RX_DP<3>    J88              A26      SCONN84_123318136-SCONN84_1-23A
P5E_CPU1_PE4_RX_DP<3>    U1               AR90     SOCKET4677_AZIFS054P001C01-SOCA
P5E_CPU1_PE4_RX_DP<4>    J88              A30      SCONN84_123318136-SCONN84_1-23A
P5E_CPU1_PE4_RX_DP<4>    U1               AN90     SOCKET4677_AZIFS054P001C01-SOCA
P5E_CPU1_PE4_RX_DP<5>    J88              A34      SCONN84_123318136-SCONN84_1-23A
P5E_CPU1_PE4_RX_DP<5>    U1               AL90     SOCKET4677_AZIFS054P001C01-SOCA
P5E_CPU1_PE4_RX_DP<6>    J88              A36      SCONN84_123318136-SCONN84_1-23A
P5E_CPU1_PE4_RX_DP<6>    U1               AJ90     SOCKET4677_AZIFS054P001C01-SOCA
P5E_CPU1_PE4_RX_DP<7>    J88              A40      SCONN84_123318136-SCONN84_1-23A
P5E_CPU1_PE4_RX_DP<7>    U1               AG90     SOCKET4677_AZIFS054P001C01-SOCA
P5E_CPU1_PE4_RX_DP<8>    J61              A18      SCONN84_123318136-SCONN84_1-23A
P5E_CPU1_PE4_RX_DP<8>    U1               AE90     SOCKET4677_AZIFS054P001C01-SOCA
P5E_CPU1_PE4_RX_DP<9>    J61              A20      SCONN84_123318136-SCONN84_1-23A
P5E_CPU1_PE4_RX_DP<9>    U1               AC90     SOCKET4677_AZIFS054P001C01-SOCA
P5E_CPU1_PE4_RX_DP<10>   J61              A24      SCONN84_123318136-SCONN84_1-23A
P5E_CPU1_PE4_RX_DP<10>   U1               AA90     SOCKET4677_AZIFS054P001C01-SOCA
P5E_CPU1_PE4_RX_DP<11>   J61              A26      SCONN84_123318136-SCONN84_1-23A
P5E_CPU1_PE4_RX_DP<11>   U1               W90      SOCKET4677_AZIFS054P001C01-SOCA
P5E_CPU1_PE4_RX_DP<12>   J61              A30      SCONN84_123318136-SCONN84_1-23A
P5E_CPU1_PE4_RX_DP<12>   U1               U90      SOCKET4677_AZIFS054P001C01-SOCA
P5E_CPU1_PE4_RX_DP<13>   J61              A34      SCONN84_123318136-SCONN84_1-23A
P5E_CPU1_PE4_RX_DP<13>   U1               R90      SOCKET4677_AZIFS054P001C01-SOCA
P5E_CPU1_PE4_RX_DP<14>   J61              A36      SCONN84_123318136-SCONN84_1-23A
P5E_CPU1_PE4_RX_DP<14>   U1               N90      SOCKET4677_AZIFS054P001C01-SOCA
P5E_CPU1_PE4_RX_DP<15>   J61              A40      SCONN84_123318136-SCONN84_1-23A
P5E_CPU1_PE4_RX_DP<15>   U1               K89      SOCKET4677_AZIFS054P001C01-SOCA
P5E_CPU1_PE4_TX_C_DN<0>  C708             1        Q_CAP_DIFFBUS_C0201-DIFF BUS_0A
P5E_CPU1_PE4_TX_C_DN<0>  J88              B17      SCONN84_123318136-SCONN84_1-23A
P5E_CPU1_PE4_TX_C_DN<1>  C706             1        Q_CAP_DIFFBUS_C0201-DIFF BUS_0A
P5E_CPU1_PE4_TX_C_DN<1>  J88              B21      SCONN84_123318136-SCONN84_1-23A
P5E_CPU1_PE4_TX_C_DN<2>  C704             1        Q_CAP_DIFFBUS_C0201-DIFF BUS_0A
P5E_CPU1_PE4_TX_C_DN<2>  J88              B24      SCONN84_123318136-SCONN84_1-23A
P5E_CPU1_PE4_TX_C_DN<3>  C702             1        Q_CAP_DIFFBUS_C0201-DIFF BUS_0A
P5E_CPU1_PE4_TX_C_DN<3>  J88              B27      SCONN84_123318136-SCONN84_1-23A
P5E_CPU1_PE4_TX_C_DN<4>  C700             1        Q_CAP_DIFFBUS_C0201-DIFF BUS_0A
P5E_CPU1_PE4_TX_C_DN<4>  J88              B31      SCONN84_123318136-SCONN84_1-23A
P5E_CPU1_PE4_TX_C_DN<5>  C698             1        Q_CAP_DIFFBUS_C0201-DIFF BUS_0A
P5E_CPU1_PE4_TX_C_DN<5>  J88              B34      SCONN84_123318136-SCONN84_1-23A
P5E_CPU1_PE4_TX_C_DN<6>  C696             1        Q_CAP_DIFFBUS_C0201-DIFF BUS_0A
P5E_CPU1_PE4_TX_C_DN<6>  J88              B37      SCONN84_123318136-SCONN84_1-23A
P5E_CPU1_PE4_TX_C_DN<7>  C694             1        Q_CAP_DIFFBUS_C0201-DIFF BUS_0A
P5E_CPU1_PE4_TX_C_DN<7>  J88              B40      SCONN84_123318136-SCONN84_1-23A
P5E_CPU1_PE4_TX_C_DN<8>  C692             1        Q_CAP_DIFFBUS_C0201-DIFF BUS_0A
P5E_CPU1_PE4_TX_C_DN<8>  J61              B18      SCONN84_123318136-SCONN84_1-23A
P5E_CPU1_PE4_TX_C_DN<9>  C690             1        Q_CAP_DIFFBUS_C0201-DIFF BUS_0A
P5E_CPU1_PE4_TX_C_DN<9>  J61              B21      SCONN84_123318136-SCONN84_1-23A
P5E_CPU1_PE4_TX_C_DN<10> C688             1        Q_CAP_DIFFBUS_C0201-DIFF BUS_0A
P5E_CPU1_PE4_TX_C_DN<10> J61              B24      SCONN84_123318136-SCONN84_1-23A
P5E_CPU1_PE4_TX_C_DN<11> C686             1        Q_CAP_DIFFBUS_C0201-DIFF BUS_0A
P5E_CPU1_PE4_TX_C_DN<11> J61              B27      SCONN84_123318136-SCONN84_1-23A
P5E_CPU1_PE4_TX_C_DN<12> C684             1        Q_CAP_DIFFBUS_C0201-DIFF BUS_0A
P5E_CPU1_PE4_TX_C_DN<12> J61              B31      SCONN84_123318136-SCONN84_1-23A
P5E_CPU1_PE4_TX_C_DN<13> C682             1        Q_CAP_DIFFBUS_C0201-DIFF BUS_0A
P5E_CPU1_PE4_TX_C_DN<13> J61              B34      SCONN84_123318136-SCONN84_1-23A
P5E_CPU1_PE4_TX_C_DN<14> C680             1        Q_CAP_DIFFBUS_C0201-DIFF BUS_0A
P5E_CPU1_PE4_TX_C_DN<14> J61              B37      SCONN84_123318136-SCONN84_1-23A
P5E_CPU1_PE4_TX_C_DN<15> C678             1        Q_CAP_DIFFBUS_C0201-DIFF BUS_0A
P5E_CPU1_PE4_TX_C_DN<15> J61              B40      SCONN84_123318136-SCONN84_1-23A
P5E_CPU1_PE4_TX_C_DP<0>  C709             1        Q_CAP_DIFFBUS_C0201-DIFF BUS_0A
P5E_CPU1_PE4_TX_C_DP<0>  J88              B18      SCONN84_123318136-SCONN84_1-23A
P5E_CPU1_PE4_TX_C_DP<1>  C707             1        Q_CAP_DIFFBUS_C0201-DIFF BUS_0A
P5E_CPU1_PE4_TX_C_DP<1>  J88              B20      SCONN84_123318136-SCONN84_1-23A
P5E_CPU1_PE4_TX_C_DP<2>  C705             1        Q_CAP_DIFFBUS_C0201-DIFF BUS_0A
P5E_CPU1_PE4_TX_C_DP<2>  J88              B23      SCONN84_123318136-SCONN84_1-23A
P5E_CPU1_PE4_TX_C_DP<3>  C703             1        Q_CAP_DIFFBUS_C0201-DIFF BUS_0A
P5E_CPU1_PE4_TX_C_DP<3>  J88              B26      SCONN84_123318136-SCONN84_1-23A
P5E_CPU1_PE4_TX_C_DP<4>  C701             1        Q_CAP_DIFFBUS_C0201-DIFF BUS_0A
P5E_CPU1_PE4_TX_C_DP<4>  J88              B30      SCONN84_123318136-SCONN84_1-23A
P5E_CPU1_PE4_TX_C_DP<5>  C699             1        Q_CAP_DIFFBUS_C0201-DIFF BUS_0A
P5E_CPU1_PE4_TX_C_DP<5>  J88              B33      SCONN84_123318136-SCONN84_1-23A
P5E_CPU1_PE4_TX_C_DP<6>  C697             1        Q_CAP_DIFFBUS_C0201-DIFF BUS_0A
P5E_CPU1_PE4_TX_C_DP<6>  J88              B36      SCONN84_123318136-SCONN84_1-23A
P5E_CPU1_PE4_TX_C_DP<7>  C695             1        Q_CAP_DIFFBUS_C0201-DIFF BUS_0A
P5E_CPU1_PE4_TX_C_DP<7>  J88              B39      SCONN84_123318136-SCONN84_1-23A
P5E_CPU1_PE4_TX_C_DP<8>  C693             1        Q_CAP_DIFFBUS_C0201-DIFF BUS_0A
P5E_CPU1_PE4_TX_C_DP<8>  J61              B17      SCONN84_123318136-SCONN84_1-23A
P5E_CPU1_PE4_TX_C_DP<9>  C691             1        Q_CAP_DIFFBUS_C0201-DIFF BUS_0A
P5E_CPU1_PE4_TX_C_DP<9>  J61              B20      SCONN84_123318136-SCONN84_1-23A
P5E_CPU1_PE4_TX_C_DP<10> C689             1        Q_CAP_DIFFBUS_C0201-DIFF BUS_0A
P5E_CPU1_PE4_TX_C_DP<10> J61              B23      SCONN84_123318136-SCONN84_1-23A
P5E_CPU1_PE4_TX_C_DP<11> C687             1        Q_CAP_DIFFBUS_C0201-DIFF BUS_0A
P5E_CPU1_PE4_TX_C_DP<11> J61              B26      SCONN84_123318136-SCONN84_1-23A
P5E_CPU1_PE4_TX_C_DP<12> C685             1        Q_CAP_DIFFBUS_C0201-DIFF BUS_0A
P5E_CPU1_PE4_TX_C_DP<12> J61              B30      SCONN84_123318136-SCONN84_1-23A
P5E_CPU1_PE4_TX_C_DP<13> C683             1        Q_CAP_DIFFBUS_C0201-DIFF BUS_0A
P5E_CPU1_PE4_TX_C_DP<13> J61              B33      SCONN84_123318136-SCONN84_1-23A
P5E_CPU1_PE4_TX_C_DP<14> C681             1        Q_CAP_DIFFBUS_C0201-DIFF BUS_0A
P5E_CPU1_PE4_TX_C_DP<14> J61              B36      SCONN84_123318136-SCONN84_1-23A
P5E_CPU1_PE4_TX_C_DP<15> C679             1        Q_CAP_DIFFBUS_C0201-DIFF BUS_0A
P5E_CPU1_PE4_TX_C_DP<15> J61              B39      SCONN84_123318136-SCONN84_1-23A
P5E_CPU1_PE4_TX_DN<0>    C708             2        Q_CAP_DIFFBUS_C0201-DIFF BUS_0A
P5E_CPU1_PE4_TX_DN<0>    U1               BA86     SOCKET4677_AZIFS054P001C01-SOCA
P5E_CPU1_PE4_TX_DN<1>    C706             2        Q_CAP_DIFFBUS_C0201-DIFF BUS_0A
P5E_CPU1_PE4_TX_DN<1>    U1               AW86     SOCKET4677_AZIFS054P001C01-SOCA
P5E_CPU1_PE4_TX_DN<2>    C704             2        Q_CAP_DIFFBUS_C0201-DIFF BUS_0A
P5E_CPU1_PE4_TX_DN<2>    U1               AU86     SOCKET4677_AZIFS054P001C01-SOCA
P5E_CPU1_PE4_TX_DN<3>    C702             2        Q_CAP_DIFFBUS_C0201-DIFF BUS_0A
P5E_CPU1_PE4_TX_DN<3>    U1               AR86     SOCKET4677_AZIFS054P001C01-SOCA
P5E_CPU1_PE4_TX_DN<4>    C700             2        Q_CAP_DIFFBUS_C0201-DIFF BUS_0A
P5E_CPU1_PE4_TX_DN<4>    U1               AP85     SOCKET4677_AZIFS054P001C01-SOCA
P5E_CPU1_PE4_TX_DN<5>    C698             2        Q_CAP_DIFFBUS_C0201-DIFF BUS_0A
P5E_CPU1_PE4_TX_DN<5>    U1               AL86     SOCKET4677_AZIFS054P001C01-SOCA
P5E_CPU1_PE4_TX_DN<6>    C696             2        Q_CAP_DIFFBUS_C0201-DIFF BUS_0A
P5E_CPU1_PE4_TX_DN<6>    U1               AJ86     SOCKET4677_AZIFS054P001C01-SOCA
P5E_CPU1_PE4_TX_DN<7>    C694             2        Q_CAP_DIFFBUS_C0201-DIFF BUS_0A
P5E_CPU1_PE4_TX_DN<7>    U1               AG86     SOCKET4677_AZIFS054P001C01-SOCA
P5E_CPU1_PE4_TX_DN<8>    C692             2        Q_CAP_DIFFBUS_C0201-DIFF BUS_0A
P5E_CPU1_PE4_TX_DN<8>    U1               AE86     SOCKET4677_AZIFS054P001C01-SOCA
P5E_CPU1_PE4_TX_DN<9>    C690             2        Q_CAP_DIFFBUS_C0201-DIFF BUS_0A
P5E_CPU1_PE4_TX_DN<9>    U1               AC86     SOCKET4677_AZIFS054P001C01-SOCA
P5E_CPU1_PE4_TX_DN<10>   C688             2        Q_CAP_DIFFBUS_C0201-DIFF BUS_0A
P5E_CPU1_PE4_TX_DN<10>   U1               AA86     SOCKET4677_AZIFS054P001C01-SOCA
P5E_CPU1_PE4_TX_DN<11>   C686             2        Q_CAP_DIFFBUS_C0201-DIFF BUS_0A
P5E_CPU1_PE4_TX_DN<11>   U1               W86      SOCKET4677_AZIFS054P001C01-SOCA
P5E_CPU1_PE4_TX_DN<12>   C684             2        Q_CAP_DIFFBUS_C0201-DIFF BUS_0A
P5E_CPU1_PE4_TX_DN<12>   U1               U86      SOCKET4677_AZIFS054P001C01-SOCA
P5E_CPU1_PE4_TX_DN<13>   C682             2        Q_CAP_DIFFBUS_C0201-DIFF BUS_0A
P5E_CPU1_PE4_TX_DN<13>   U1               R86      SOCKET4677_AZIFS054P001C01-SOCA
P5E_CPU1_PE4_TX_DN<14>   C680             2        Q_CAP_DIFFBUS_C0201-DIFF BUS_0A
P5E_CPU1_PE4_TX_DN<14>   U1               P85      SOCKET4677_AZIFS054P001C01-SOCA
P5E_CPU1_PE4_TX_DN<15>   C678             2        Q_CAP_DIFFBUS_C0201-DIFF BUS_0A
P5E_CPU1_PE4_TX_DN<15>   U1               L86      SOCKET4677_AZIFS054P001C01-SOCA
P5E_CPU1_PE4_TX_DP<0>    C709             2        Q_CAP_DIFFBUS_C0201-DIFF BUS_0A
P5E_CPU1_PE4_TX_DP<0>    U1               BB85     SOCKET4677_AZIFS054P001C01-SOCA
P5E_CPU1_PE4_TX_DP<1>    C707             2        Q_CAP_DIFFBUS_C0201-DIFF BUS_0A
P5E_CPU1_PE4_TX_DP<1>    U1               AY87     SOCKET4677_AZIFS054P001C01-SOCA
P5E_CPU1_PE4_TX_DP<2>    C705             2        Q_CAP_DIFFBUS_C0201-DIFF BUS_0A
P5E_CPU1_PE4_TX_DP<2>    U1               AV85     SOCKET4677_AZIFS054P001C01-SOCA
P5E_CPU1_PE4_TX_DP<3>    C703             2        Q_CAP_DIFFBUS_C0201-DIFF BUS_0A
P5E_CPU1_PE4_TX_DP<3>    U1               AT87     SOCKET4677_AZIFS054P001C01-SOCA
P5E_CPU1_PE4_TX_DP<4>    C701             2        Q_CAP_DIFFBUS_C0201-DIFF BUS_0A
P5E_CPU1_PE4_TX_DP<4>    U1               AN86     SOCKET4677_AZIFS054P001C01-SOCA
P5E_CPU1_PE4_TX_DP<5>    C699             2        Q_CAP_DIFFBUS_C0201-DIFF BUS_0A
P5E_CPU1_PE4_TX_DP<5>    U1               AM87     SOCKET4677_AZIFS054P001C01-SOCA
P5E_CPU1_PE4_TX_DP<6>    C697             2        Q_CAP_DIFFBUS_C0201-DIFF BUS_0A
P5E_CPU1_PE4_TX_DP<6>    U1               AK85     SOCKET4677_AZIFS054P001C01-SOCA
P5E_CPU1_PE4_TX_DP<7>    C695             2        Q_CAP_DIFFBUS_C0201-DIFF BUS_0A
P5E_CPU1_PE4_TX_DP<7>    U1               AH87     SOCKET4677_AZIFS054P001C01-SOCA
P5E_CPU1_PE4_TX_DP<8>    C693             2        Q_CAP_DIFFBUS_C0201-DIFF BUS_0A
P5E_CPU1_PE4_TX_DP<8>    U1               AF85     SOCKET4677_AZIFS054P001C01-SOCA
P5E_CPU1_PE4_TX_DP<9>    C691             2        Q_CAP_DIFFBUS_C0201-DIFF BUS_0A
P5E_CPU1_PE4_TX_DP<9>    U1               AD87     SOCKET4677_AZIFS054P001C01-SOCA
P5E_CPU1_PE4_TX_DP<10>   C689             2        Q_CAP_DIFFBUS_C0201-DIFF BUS_0A
P5E_CPU1_PE4_TX_DP<10>   U1               AB85     SOCKET4677_AZIFS054P001C01-SOCA
P5E_CPU1_PE4_TX_DP<11>   C687             2        Q_CAP_DIFFBUS_C0201-DIFF BUS_0A
P5E_CPU1_PE4_TX_DP<11>   U1               Y87      SOCKET4677_AZIFS054P001C01-SOCA
P5E_CPU1_PE4_TX_DP<12>   C685             2        Q_CAP_DIFFBUS_C0201-DIFF BUS_0A
P5E_CPU1_PE4_TX_DP<12>   U1               V85      SOCKET4677_AZIFS054P001C01-SOCA
P5E_CPU1_PE4_TX_DP<13>   C683             2        Q_CAP_DIFFBUS_C0201-DIFF BUS_0A
P5E_CPU1_PE4_TX_DP<13>   U1               T87      SOCKET4677_AZIFS054P001C01-SOCA
P5E_CPU1_PE4_TX_DP<14>   C681             2        Q_CAP_DIFFBUS_C0201-DIFF BUS_0A
P5E_CPU1_PE4_TX_DP<14>   U1               N86      SOCKET4677_AZIFS054P001C01-SOCA
P5E_CPU1_PE4_TX_DP<15>   C679             2        Q_CAP_DIFFBUS_C0201-DIFF BUS_0A
P5E_CPU1_PE4_TX_DP<15>   U1               M87      SOCKET4677_AZIFS054P001C01-SOCA
P5V                      C633             1        Q_CAP_C0805-22UF,25V,20%,X5R,CA
P5V                      C638             1        Q_CAP_0402-0.1UF,25V,10%,X7R,CA
P5V                      C1172            1        Q_CAP_C0402-100NF,50V,10%,X7R,A
P5V                      C1227            1        Q_CAP_C0402-100NF,50V,10%,X7R,A
P5V                      C1331            1        Q_CAP_C0805-10UF,16V,10%,X6S,CA
P5V                      C1337            1        Q_CAP_C0603-22UF,6.3V,20%,X6S,A
P5V                      C1341            1        Q_CAP_C0603-22UF,6.3V,20%,X6S,A
P5V                      D7               3        BAT547F-BAT547F,SMLF,IC,BC0BATA
P5V                      JP5              3        CONN3_HFK1030G000LAF-CONN3_HFKA
P5V                      PQ1              1        MOSFET_NCH_1D3S-PSMNR58-30YLH,A
P5V                      PQ1              2        MOSFET_NCH_1D3S-PSMNR58-30YLH,A
P5V                      PQ1              3        MOSFET_NCH_1D3S-PSMNR58-30YLH,A
P5V                      PR402            1        Q_RES_0402LF-0,5%,1/16W,CHIP,CA
P5V                      PR437            1        Q_RES_0402LF-0,5%,1/16W,CHIP,CA
P5V                      PR442            1        Q_RES_0402LF-0,5%,1/16W,CHIP,CA
P5V                      PR444            1        Q_RES_0402LF-0,5%,1/16W,CHIP,CA
P5V                      PR447            1        Q_RES_0402LF-0,5%,1/16W,CHIP,CA
P5V                      PR635            1        Q_RES_0402LF-0,5%,1/16W,CHIP,CA
P5V                      PR639            1        Q_RES_0402LF-0,5%,1/16W,CHIP,CA
P5V                      PR668            1        Q_RES_0402LF-0,5%,1/16W,CHIP,CA
P5V                      PR678            1        Q_RES_0402LF-0,5%,1/16W,CHIP,CA
P5V                      PR701            1        Q_RES_0402LF-0,5%,1/16W,CHIP,CA
P5V                      PR702            1        Q_RES_0402LF-0,5%,1/16W,CHIP,CA
P5V                      PR706            1        Q_RES_0402LF-0,5%,1/16W,CHIP,CA
P5V                      R461             1        Q_RES_0402LF-100K,5%,1/16W,CHIA
P5V                      R1655            1        Q_RES_0402LF-10K,5%,1/16W,CHIPA
P5V                      U27              1        TPS2553DBVR1-TPS2553DBVR-1,SMLA
P5V                      U99              3        RT9818C44GV-RT9818C-44GV,SMLF,A
P5V_AUX                  C1042            1        Q_CAP_C0402-100NF,50V,10%,X7R,A
P5V_AUX                  C1170            1        Q_CAP_C0805-10UF,16V,10%,X6S,CA
P5V_AUX                  C1171            1        Q_CAP_C0805-10UF,16V,10%,EMPTYA
P5V_AUX                  C1326            1        Q_CAP_C0402-100NF,50V,10%,X7R,A
P5V_AUX                  PC581            1        Q_CAP_C0603-4.7UF,16V,10%,X6S,A
P5V_AUX                  PC1845           1        Q_CAPP_SMLF-220UF,6.3V,20%,ALUA
P5V_AUX                  PC1852           1        Q_CAP_0402-0.1UF,25V,10%,X7R,CA
P5V_AUX                  PC1855           1        Q_CAP_C0805-22UF,10V,20%,X6S,CA
P5V_AUX                  PC1856           1        Q_CAP_C0805-22UF,10V,20%,X6S,CA
P5V_AUX                  PC1877           2        Q_CAP_0402-47PF,50V,5%,NPO,TMPA
P5V_AUX                  PL65             2        Q_INDUCTOR_SMLF-3.3UH/10A,IND,A
P5V_AUX                  PQ1              5        MOSFET_NCH_1D3S-PSMNR58-30YLH,A
P5V_AUX                  PR92             2        Q_RES_0402LF-86.6K,1%,1/16W,CHA
P5V_AUX                  PR389            1        Q_RES_0402LF-1,1%,1/16W,CHIP,CA
P5V_AUX                  PR396            1        Q_RES_0402LF-0,5%,1/16W,EMPTY,A
P5V_AUX                  PU9              3        NCP3284MNTXG-NCP3284MNTXG,SMLFA
P5V_AUX                  PU9              5        NCP3284MNTXG-NCP3284MNTXG,SMLFA
P5V_AUX                  U79              1        SLG55221120010VTR-SLG55221-120A
P5V_AUX_CS               PR89             1        Q_RES_0402LF-15K,1%,1/16W,CHIPA
P5V_AUX_CS               PU181            3        MPQ8633BGLEC838Z-MPQ8633BGLE-CA
P5V_AUX_EN               PC1870           1        Q_CAP_0402-0.1UF,25V,10%,EMPTYA
P5V_AUX_EN               PR1945           2        Q_RES_0402LF-510K,5%,1/16W,CHIA
P5V_AUX_EN               PR1948           1        Q_RES_0402LF-75K,1%,1/16W,CHIPA
P5V_AUX_EN               PU181            8        MPQ8633BGLEC838Z-MPQ8633BGLE-CA
P5V_AUX_FB               PC1877           1        Q_CAP_0402-47PF,50V,5%,NPO,TMPA
P5V_AUX_FB               PR91             1        Q_RES_0402LF-11.8K,1%,1/16W,CHA
P5V_AUX_FB               PR92             1        Q_RES_0402LF-86.6K,1%,1/16W,CHA
P5V_AUX_FB               PU181            7        MPQ8633BGLEC838Z-MPQ8633BGLE-CA
P5V_AUX_REF              PC1853           1        Q_CAP_0402-0.1UF,25V,10%,X7R,CA
P5V_AUX_REF              PU181            5        MPQ8633BGLEC838Z-MPQ8633BGLE-CA
P5V_AUX_VCC              PC1848           1        Q_CAP_C0402-1UF,25V,10%,X6S,CHA
P5V_AUX_VCC              PR90             1        Q_RES_0402LF-10K,5%,1/16W,CHIPA
P5V_AUX_VCC              PU181            4        MPQ8633BGLEC838Z-MPQ8633BGLE-CA
P5V_AUX_VCC              PU181            19       MPQ8633BGLEC838Z-MPQ8633BGLE-CA
P5V_USB_INT              C1342            1        Q_CAP_C0603-22UF,6.3V,20%,X6S,A
P5V_USB_INT              C1343            1        Q_CAP_C0603-22UF,6.3V,20%,X6S,A
P5V_USB_INT              J48              1        CONN9_2UB3903013101F-CONN9_2UBA
P5V_USB_INT              U27              6        TPS2553DBVR1-TPS2553DBVR-1,SMLA
PCA9546_PCIE0_ADDR0      R540             2        Q_RES_0402LF-10K,1%,1/16W,EMPTA
PCA9546_PCIE0_ADDR0      R587             1        Q_RES_0402LF-1K,1%,1/16W,CHIP,A
PCA9546_PCIE0_ADDR0      U36              1        PCA9546APWR-PCA9546APWR,SMLF,IA
PCA9546_PCIE0_ADDR1      R538             2        Q_RES_0402LF-10K,1%,1/16W,EMPTA
PCA9546_PCIE0_ADDR1      R539             1        Q_RES_0402LF-1K,1%,1/16W,CHIP,A
PCA9546_PCIE0_ADDR1      U36              2        PCA9546APWR-PCA9546APWR,SMLF,IA
PCA9546_PCIE0_ADDR2      R536             2        Q_RES_0402LF-10K,1%,1/16W,EMPTA
PCA9546_PCIE0_ADDR2      R537             1        Q_RES_0402LF-1K,1%,1/16W,CHIP,A
PCA9546_PCIE0_ADDR2      U36              13       PCA9546APWR-PCA9546APWR,SMLF,IA
PCA9546_PCIE1_ADDR0      R645             2        Q_RES_0402LF-10K,1%,1/16W,CHIPA
PCA9546_PCIE1_ADDR0      R646             1        Q_RES_0402LF-1K,1%,1/16W,EMPTYA
PCA9546_PCIE1_ADDR0      U10              1        PCA9546APWR-PCA9546APWR,SMLF,IA
PCA9546_PCIE1_ADDR1      R643             2        Q_RES_0402LF-10K,1%,1/16W,EMPTA
PCA9546_PCIE1_ADDR1      R644             1        Q_RES_0402LF-1K,1%,1/16W,CHIP,A
PCA9546_PCIE1_ADDR1      U10              2        PCA9546APWR-PCA9546APWR,SMLF,IA
PCA9546_PCIE1_ADDR2      R641             2        Q_RES_0402LF-10K,1%,1/16W,EMPTA
PCA9546_PCIE1_ADDR2      R642             1        Q_RES_0402LF-1K,1%,1/16W,CHIP,A
PCA9546_PCIE1_ADDR2      U10              13       PCA9546APWR-PCA9546APWR,SMLF,IA
PCA9546_PCIE3_ADDR0      R2195            2        Q_RES_0402LF-10K,1%,1/16W,EMPTA
PCA9546_PCIE3_ADDR0      R2196            1        Q_RES_0402LF-1K,1%,1/16W,CHIP,A
PCA9546_PCIE3_ADDR0      U141             1        PCA9546APWR-PCA9546APWR,SMLF,IA
PCA9546_PCIE3_ADDR1      R2193            2        Q_RES_0402LF-10K,1%,1/16W,CHIPA
PCA9546_PCIE3_ADDR1      R2194            1        Q_RES_0402LF-1K,1%,1/16W,EMPTYA
PCA9546_PCIE3_ADDR1      U141             2        PCA9546APWR-PCA9546APWR,SMLF,IA
PCA9546_PCIE3_ADDR2      R2191            2        Q_RES_0402LF-10K,1%,1/16W,EMPTA
PCA9546_PCIE3_ADDR2      R2192            1        Q_RES_0402LF-1K,1%,1/16W,CHIP,A
PCA9546_PCIE3_ADDR2      U141             13       PCA9546APWR-PCA9546APWR,SMLF,IA
PCA9548_PCIE2_ADDR0      R785             2        Q_RES_0402LF-10K,1%,1/16W,EMPTA
PCA9548_PCIE2_ADDR0      R786             1        Q_RES_0402LF-1K,1%,1/16W,CHIP,A
PCA9548_PCIE2_ADDR0      U24              1        PCA9548APW-PCA9548APW,SMLF,IC,A
PCA9548_PCIE2_ADDR1      R783             2        Q_RES_0402LF-10K,1%,1/16W,CHIPA
PCA9548_PCIE2_ADDR1      R784             1        Q_RES_0402LF-1K,1%,1/16W,EMPTYA
PCA9548_PCIE2_ADDR1      U24              2        PCA9548APW-PCA9548APW,SMLF,IC,A
PCA9548_PCIE2_ADDR2      R781             2        Q_RES_0402LF-10K,1%,1/16W,EMPTA
PCA9548_PCIE2_ADDR2      R782             1        Q_RES_0402LF-1K,1%,1/16W,CHIP,A
PCA9548_PCIE2_ADDR2      U24              21       PCA9548APW-PCA9548APW,SMLF,IC,A
PCA9555_1_ADD0           R2097            2        Q_RES_0402LF-1K,5%,1/16W,EMPTYA
PCA9555_1_ADD0           R2098            1        Q_RES_0402LF-1K,5%,1/16W,CHIP,A
PCA9555_1_ADD0           U130             21       PCA9555PW_SMLF-PCA9555PW,IC,TMA
PCA9555_1_ADD1           R2093            2        Q_RES_0402LF-1K,5%,1/16W,EMPTYA
PCA9555_1_ADD1           R2094            1        Q_RES_0402LF-1K,5%,1/16W,CHIP,A
PCA9555_1_ADD1           U130             2        PCA9555PW_SMLF-PCA9555PW,IC,TMA
PCA9555_1_ADD2           R2089            2        Q_RES_0402LF-1K,5%,1/16W,EMPTYA
PCA9555_1_ADD2           R2090            1        Q_RES_0402LF-1K,5%,1/16W,CHIP,A
PCA9555_1_ADD2           U130             3        PCA9555PW_SMLF-PCA9555PW,IC,TMA
PCA9555_2_ADD0           R2099            2        Q_RES_0402LF-1K,5%,1/16W,EMPTYA
PCA9555_2_ADD0           R2100            1        Q_RES_0402LF-1K,5%,1/16W,CHIP,A
PCA9555_2_ADD0           U131             21       PCA9555PW_SMLF-PCA9555PW,IC,TMA
PCA9555_2_ADD1           R2095            2        Q_RES_0402LF-1K,5%,1/16W,EMPTYA
PCA9555_2_ADD1           R2096            1        Q_RES_0402LF-1K,5%,1/16W,CHIP,A
PCA9555_2_ADD1           U131             2        PCA9555PW_SMLF-PCA9555PW,IC,TMA
PCA9555_2_ADD2           R2091            2        Q_RES_0402LF-1K,5%,1/16W,EMPTYA
PCA9555_2_ADD2           R2092            1        Q_RES_0402LF-1K,5%,1/16W,CHIP,A
PCA9555_2_ADD2           U131             3        PCA9555PW_SMLF-PCA9555PW,IC,TMA
PCH_PCIEUP_RCOMPN        R495             2        Q_RES_0402LF-100,1%,1/16W,CHIPA
PCH_PCIEUP_RCOMPN        U4               AP31     EMMITSBURG_REV0P9-GFNOCPU04302A
PCH_PCIEUP_RCOMPP        R495             1        Q_RES_0402LF-100,1%,1/16W,CHIPA
PCH_PCIEUP_RCOMPP        U4               AR29     EMMITSBURG_REV0P9-GFNOCPU04302A
PCIE_M2_SSD0_PRSNT_N     J59              1        SCONN75K_APCI0155P004A-SCONN75A
PCIE_M2_SSD0_PRSNT_N     R478             2        Q_RES_0402LF-4.7K,1%,1/16W,CHIA
PCIE_M2_SSD0_PRSNT_N     U122             F10      10M04SAU324I7G-10M04SAU324I7G,A
PCIE_RISER1_PRSNT2_N     J55              A70      SCONN140_G64V3431BHR-SCONN140_A
PCIE_RISER1_PRSNT2_N     R2170            2        Q_RES_0402LF-10K,5%,1/16W,CHIPA
PCIE_RISER2_PRSNT_N      J89              A140     SCONN280_ME1028040102011-SCONNA
PCIE_RISER2_PRSNT_N      R2158            2        Q_RES_0402LF-10K,5%,1/16W,CHIPA
PCIE_RISER3_PRSNT2_N     J57              A70      SCONN140_G64V3431BHR-SCONN140_A
PCIE_RISER3_PRSNT2_N     R392             2        Q_RES_0402LF-10K,5%,1/16W,CHIPA
PCIE_RISER3_PRSNT2_N     U4               V8       EMMITSBURG_REV0P9-GFNOCPU04302A
PD_74CB_A9               R746             1        Q_RES_0402LF-0,5%,1/16W,CHIP,CA
PD_74CB_A9               U17              9        74CBTLV3126PW-74CBTLV3126PW,SMA
PD_BIOS_IMAGE_SWAP_N     R1324            2        Q_RES_0402LF-1K,1%,1/16W,CHIP,A
PD_BIOS_IMAGE_SWAP_N     S1               4        SW8S_DHNF04FTVTR-SW8S_DHNF04FTA
PD_CHA_CPU0_DIMM1_SAA    J1               148      SCONN288_ADR50001P013C01-SCONNA
PD_CHA_CPU0_DIMM1_SAA    R26              1        Q_RES_0402LF-10K,1%,1/16W,CHIPA
PD_CHA_CPU0_DIMM2_SAA    J2               148      SCONN288_ADR50001P003C01-SCONNA
PD_CHA_CPU0_DIMM2_SAA    R27              1        Q_RES_0402LF-15.4K,1%,1/16W,CHA
PD_CHA_CPU1_DIMM1_SAA    J17              148      SCONN288_ADR50001P013C01-SCONNA
PD_CHA_CPU1_DIMM1_SAA    R42              1        Q_RES_0402LF-10K,1%,1/16W,CHIPA
PD_CHA_CPU1_DIMM2_SAA    J18              148      SCONN288_ADR50001P003C01-SCONNA
PD_CHA_CPU1_DIMM2_SAA    R43              1        Q_RES_0402LF-15.4K,1%,1/16W,CHA
PD_CHB_CPU0_DIMM1_SAA    J3               148      SCONN288_ADR50001P013C01-SCONNA
PD_CHB_CPU0_DIMM1_SAA    R28              1        Q_RES_0402LF-23.2K,1%,1/16W,CHA
PD_CHB_CPU0_DIMM2_SAA    J4               148      SCONN288_ADR50001P003C01-SCONNA
PD_CHB_CPU0_DIMM2_SAA    R29              1        Q_RES_0402LF-35.7K,1%,1/16W,CHA
PD_CHB_CPU1_DIMM1_SAA    J19              148      SCONN288_ADR50001P013C01-SCONNA
PD_CHB_CPU1_DIMM1_SAA    R44              1        Q_RES_0402LF-23.2K,1%,1/16W,CHA
PD_CHB_CPU1_DIMM2_SAA    J20              148      SCONN288_ADR50001P003C01-SCONNA
PD_CHB_CPU1_DIMM2_SAA    R45              1        Q_RES_0402LF-35.7K,1%,1/16W,CHA
PD_CHC_CPU0_DIMM1_SAA    J5               148      SCONN288_ADR50001P013C01-SCONNA
PD_CHC_CPU0_DIMM1_SAA    R30              1        Q_RES_0402LF-54.9K,1%,1/16W,CHA
PD_CHC_CPU0_DIMM2_SAA    J6               148      SCONN288_ADR50001P003C01-SCONNA
PD_CHC_CPU0_DIMM2_SAA    R31              1        Q_RES_0402LF-84.5K,1%,1/16W,CHA
PD_CHC_CPU1_DIMM1_SAA    J21              148      SCONN288_ADR50001P013C01-SCONNA
PD_CHC_CPU1_DIMM1_SAA    R46              1        Q_RES_0402LF-54.9K,1%,1/16W,CHA
PD_CHC_CPU1_DIMM2_SAA    J22              148      SCONN288_ADR50001P003C01-SCONNA
PD_CHC_CPU1_DIMM2_SAA    R47              1        Q_RES_0402LF-84.5K,1%,1/16W,CHA
PD_CHD_CPU0_DIMM1_SAA    J7               148      SCONN288_ADR50001P013C01-SCONNA
PD_CHD_CPU0_DIMM1_SAA    R32              1        Q_RES_0402LF-127K,1%,1/16W,CHIA
PD_CHD_CPU0_DIMM2_SAA    J8               148      SCONN288_ADR50001P003C01-SCONNA
PD_CHD_CPU0_DIMM2_SAA    R33              1        Q_RES_0402LF-196K,1%,1/16W,CHIA
PD_CHD_CPU1_DIMM1_SAA    J23              148      SCONN288_ADR50001P013C01-SCONNA
PD_CHD_CPU1_DIMM1_SAA    R48              1        Q_RES_0402LF-127K,1%,1/16W,CHIA
PD_CHD_CPU1_DIMM2_SAA    J24              148      SCONN288_ADR50001P003C01-SCONNA
PD_CHD_CPU1_DIMM2_SAA    R80              1        Q_RES_0402LF-196K,1%,1/16W,CHIA
PD_CHE_CPU0_DIMM1_SAA    J9               148      SCONN288_ADR50001P013C01-SCONNA
PD_CHE_CPU0_DIMM1_SAA    R34              1        Q_RES_0402LF-10K,1%,1/16W,CHIPA
PD_CHE_CPU0_DIMM2_SAA    J10              148      SCONN288_ADR50001P003C01-SCONNA
PD_CHE_CPU0_DIMM2_SAA    R35              1        Q_RES_0402LF-15.4K,1%,1/16W,CHA
PD_CHE_CPU1_DIMM1_SAA    J25              148      SCONN288_ADR50001P013C01-SCONNA
PD_CHE_CPU1_DIMM1_SAA    R79              1        Q_RES_0402LF-10K,1%,1/16W,CHIPA
PD_CHE_CPU1_DIMM2_SAA    J26              148      SCONN288_ADR50001P003C01-SCONNA
PD_CHE_CPU1_DIMM2_SAA    R78              1        Q_RES_0402LF-15.4K,1%,1/16W,CHA
PD_CHF_CPU0_DIMM1_SAA    J11              148      SCONN288_ADR50001P013C01-SCONNA
PD_CHF_CPU0_DIMM1_SAA    R36              1        Q_RES_0402LF-23.2K,1%,1/16W,CHA
PD_CHF_CPU0_DIMM2_SAA    J12              148      SCONN288_ADR50001P003C01-SCONNA
PD_CHF_CPU0_DIMM2_SAA    R37              1        Q_RES_0402LF-35.7K,1%,1/16W,CHA
PD_CHF_CPU1_DIMM1_SAA    J27              148      SCONN288_ADR50001P013C01-SCONNA
PD_CHF_CPU1_DIMM1_SAA    R77              1        Q_RES_0402LF-23.2K,1%,1/16W,CHA
PD_CHF_CPU1_DIMM2_SAA    J28              148      SCONN288_ADR50001P003C01-SCONNA
PD_CHF_CPU1_DIMM2_SAA    R76              1        Q_RES_0402LF-35.7K,1%,1/16W,CHA
PD_CHG_CPU0_DIMM1_SAA    J13              148      SCONN288_ADR50001P013C01-SCONNA
PD_CHG_CPU0_DIMM1_SAA    R38              1        Q_RES_0402LF-54.9K,1%,1/16W,CHA
PD_CHG_CPU0_DIMM2_SAA    J14              148      SCONN288_ADR50001P003C01-SCONNA
PD_CHG_CPU0_DIMM2_SAA    R39              1        Q_RES_0402LF-84.5K,1%,1/16W,CHA
PD_CHG_CPU1_DIMM1_SAA    J29              148      SCONN288_ADR50001P013C01-SCONNA
PD_CHG_CPU1_DIMM1_SAA    R75              1        Q_RES_0402LF-54.9K,1%,1/16W,CHA
PD_CHG_CPU1_DIMM2_SAA    J30              148      SCONN288_ADR50001P003C01-SCONNA
PD_CHG_CPU1_DIMM2_SAA    R74              1        Q_RES_0402LF-84.5K,1%,1/16W,CHA
PD_CHH_CPU0_DIMM1_SAA    J15              148      SCONN288_ADR50001P013C01-SCONNA
PD_CHH_CPU0_DIMM1_SAA    R40              1        Q_RES_0402LF-127K,1%,1/16W,CHIA
PD_CHH_CPU0_DIMM2_SAA    J16              148      SCONN288_ADR50001P003C01-SCONNA
PD_CHH_CPU0_DIMM2_SAA    R41              1        Q_RES_0402LF-196K,1%,1/16W,CHIA
PD_CHH_CPU1_DIMM1_SAA    J31              148      SCONN288_ADR50001P013C01-SCONNA
PD_CHH_CPU1_DIMM1_SAA    R73              1        Q_RES_0402LF-127K,1%,1/16W,CHIA
PD_CHH_CPU1_DIMM2_SAA    J32              148      SCONN288_ADR50001P003C01-SCONNA
PD_CHH_CPU1_DIMM2_SAA    R72              1        Q_RES_0402LF-196K,1%,1/16W,CHIA
PD_CK440_SBI_CLK         R1462            1        Q_RES_0402LF-1K,1%,1/16W,CHIP,A
PD_CK440_SBI_CLK         U13              A54      9SQ440NQQI8-9SQ440NQQI8,SMLF,IA
PD_CK440_SBI_DATA_IN     R1500            1        Q_RES_0402LF-4.75K,1%,1/16W,CHA
PD_CK440_SBI_DATA_IN     U13              B43      9SQ440NQQI8-9SQ440NQQI8,SMLF,IA
PD_CPU0_BIST_ENABLE      R293             2        Q_RES_0402LF-240,1%,1/16W,CHIPA
PD_CPU0_BIST_ENABLE      U2               AT18     SOCKET4677_AZIFS054P001C01-SOCA
PD_CPU0_DMIMODE_OVERRIDE R294             2        Q_RES_0402LF-240,1%,1/16W,EMPTA
PD_CPU0_DMIMODE_OVERRIDE U2               AW17     SOCKET4677_AZIFS054P001C01-SOCA
PD_CPU0_ENH_MCECC_DIS    R295             2        Q_RES_0402LF-240,1%,1/16W,EMPTA
PD_CPU0_ENH_MCECC_DIS    U2               CH22     SOCKET4677_AZIFS054P001C01-SOCA
PD_CPU0_TXT_PLTEN        R292             2        Q_RES_0402LF-240,1%,1/16W,CHIPA
PD_CPU0_TXT_PLTEN        U2               CT20     SOCKET4677_AZIFS054P001C01-SOCA
PD_CPU1_BIST_ENABLE      R289             2        Q_RES_0402LF-240,1%,1/16W,CHIPA
PD_CPU1_BIST_ENABLE      U1               AT18     SOCKET4677_AZIFS054P001C01-SOCA
PD_CPU1_DMIMODE_OVERRIDE R290             2        Q_RES_0402LF-240,1%,1/16W,CHIPA
PD_CPU1_DMIMODE_OVERRIDE U1               AW17     SOCKET4677_AZIFS054P001C01-SOCA
PD_CPU1_ENH_MCECC_DIS    R291             2        Q_RES_0402LF-240,1%,1/16W,EMPTA
PD_CPU1_ENH_MCECC_DIS    U1               CH22     SOCKET4677_AZIFS054P001C01-SOCA
PD_CPU1_PROCDIS_COD_GTL_N R1270            1        Q_RES_0402LF-240,1%,1/16W,EMPTA
PD_CPU1_PROCDIS_COD_GTL_N U1               DA52     SOCKET4677_AZIFS054P001C01-SOCA
PD_CPU1_TXT_PLTEN        R288             2        Q_RES_0402LF-240,1%,1/16W,CHIPA
PD_CPU1_TXT_PLTEN        U1               CT20     SOCKET4677_AZIFS054P001C01-SOCA
PD_DB2000_SMB_SA0        R569             2        Q_RES_0402LF-4.7K,1%,1/16W,EMPA
PD_DB2000_SMB_SA0        R570             1        Q_RES_0402LF-4.7K,1%,1/16W,CHIA
PD_DB2000_SMB_SA0        U38              B4       9QXL2001BNHGI8-9QXL2001BNHGI8,A
PD_DB2000_SMB_SA1        R567             2        Q_RES_0402LF-4.7K,1%,1/16W,EMPA
PD_DB2000_SMB_SA1        R568             1        Q_RES_0402LF-4.7K,1%,1/16W,CHIA
PD_DB2000_SMB_SA1        U38              B8       9QXL2001BNHGI8-9QXL2001BNHGI8,A
PD_EDSFF1A_PWRDIS        J62              B12      SCONN84_123318136-SCONN84_1-23A
PD_EDSFF1A_PWRDIS        R1970            1        Q_RES_0402LF-10K,1%,1/16W,CHIPA
PD_EDSFF1B_PWRDIS        J87              B12      SCONN84_123318136-SCONN84_1-23A
PD_EDSFF1B_PWRDIS        R1980            1        Q_RES_0402LF-10K,1%,1/16W,CHIPA
PD_EDSFF2A_PWRDIS        J33              B12      SCONN84_123318136-SCONN84_1-23A
PD_EDSFF2A_PWRDIS        R396             1        Q_RES_0402LF-10K,1%,1/16W,CHIPA
PD_EDSFF2B_PWRDIS        J34              B12      SCONN84_123318136-SCONN84_1-23A
PD_EDSFF2B_PWRDIS        R400             1        Q_RES_0402LF-10K,1%,1/16W,CHIPA
PD_EDSFF4A_PWRDIS        J88              B12      SCONN84_123318136-SCONN84_1-23A
PD_EDSFF4A_PWRDIS        R1990            1        Q_RES_0402LF-10K,1%,1/16W,CHIPA
PD_EDSFF4B_PWRDIS        J61              B12      SCONN84_123318136-SCONN84_1-23A
PD_EDSFF4B_PWRDIS        R2002            1        Q_RES_0402LF-10K,1%,1/16W,CHIPA
PD_EXT_CLK_SEL_CPU0      R1237            2        Q_RES_0402LF-240,1%,1/16W,EMPTA
PD_EXT_CLK_SEL_CPU0      U2               BY24     SOCKET4677_AZIFS054P001C01-SOCA
PD_EXT_CLK_SEL_CPU1      R1234            2        Q_RES_0402LF-240,1%,1/16W,EMPTA
PD_EXT_CLK_SEL_CPU1      U1               BY24     SOCKET4677_AZIFS054P001C01-SOCA
PD_GTL2014_BMC_JTAG_VREF_1 R1347            1        Q_RES_0402LF-1K,1%,1/16W,CHIP,A
PD_GTL2014_BMC_JTAG_VREF_1 U84              4        GTL2014PW-GTL2014PW,SMLF,IC,ALA
PD_GTL2014_BMC_JTAG_VREF_2 R1346            1        Q_RES_0402LF-1K,1%,1/16W,CHIP,A
PD_GTL2014_BMC_JTAG_VREF_2 U83              4        GTL2014PW-GTL2014PW,SMLF,IC,ALA
PD_I3C_SPD_DDR_CPU0_OE_N R678             1        Q_RES_0402LF-1K,1%,1/16W,CHIP,A
PD_I3C_SPD_DDR_CPU0_OE_N U15              15       IDTQS3VH257QG_SMLF-IDTQS3VH257A
PD_I3C_SPD_DDR_CPU1_OE_N R661             1        Q_RES_0402LF-1K,1%,1/16W,CHIP,A
PD_I3C_SPD_DDR_CPU1_OE_N U14              15       IDTQS3VH257QG_SMLF-IDTQS3VH257A
PD_JTAG_BMC_NTRST_N      R1374            1        Q_RES_0402LF-1K,1%,1/16W,CHIP,A
PD_JTAG_BMC_NTRST_N      U86              1        74CBTLV3126PW-74CBTLV3126PW,SMA
PD_JTAG_BMC_NTRST_N      U86              13       74CBTLV3126PW-74CBTLV3126PW,SMA
PD_JTAG_CPU1_PLD_TCK     R1227            1        Q_RES_0402LF-10K,1%,1/16W,CHIPA
PD_JTAG_CPU1_PLD_TCK     U1               CY22     SOCKET4677_AZIFS054P001C01-SOCA
PD_JTAG_DBP_B0           R1369            1        Q_RES_0402LF-1K,1%,1/16W,CHIP,A
PD_JTAG_DBP_B0           U83              2        GTL2014PW-GTL2014PW,SMLF,IC,ALA
PD_JTAG_DBP_B2           R1368            1        Q_RES_0402LF-1K,1%,1/16W,CHIP,A
PD_JTAG_DBP_B2           U83              5        GTL2014PW-GTL2014PW,SMLF,IC,ALA
PD_M2_1_DEVSLP           J59              38       SCONN75K_APCI0155P004A-SCONN75A
PD_M2_1_DEVSLP           R1605            1        Q_RES_0402LF-1K,1%,1/16W,CHIP,A
PD_MAIN_FPGA_CONFIG_SEL  R1491            1        Q_RES_0402LF-1K,1%,1/16W,CHIP,A
PD_MAIN_FPGA_CONFIG_SEL  U122             G9       10M04SAU324I7G-10M04SAU324I7G,A
PD_MAIN_FPGA_F7          R1739            1        Q_RES_0402LF-100,1%,1/16W,CHIPA
PD_MAIN_FPGA_F7          U122             F7       10M04SAU324I7G-10M04SAU324I7G,A
PD_MAIN_FPGA_N13         R1738            1        Q_RES_0402LF-100,1%,1/16W,CHIPA
PD_MAIN_FPGA_N13         U122             N13      10M04SAU324I7G-10M04SAU324I7G,A
PD_MB_FRU_WP             R710             1        Q_RES_0402LF-1K,1%,1/16W,CHIP,A
PD_MB_FRU_WP             U64              7        M24128BWDW6TP-M24128-BWDW6TP,SA
PD_MB_PRSNT              J44              23       CONN24_52SH90245BRD-CONN24_52SA
PD_MB_PRSNT              R2156            1        Q_RES_0402LF-0,5%,1/16W,CHIP,CA
PD_ME_RCVR_N             R1334            2        Q_RES_0402LF-1K,1%,1/16W,CHIP,A
PD_ME_RCVR_N             S2               3        SW8S_DHNF04FTVTR-SW8S_DHNF04FTA
PD_MP5981_0_MODE         R2074            1        Q_RES_0402LF-0,5%,1/16W,CHIP,CA
PD_MP5981_0_MODE         U107             8        MP5981GLUZ-MP5981GLU-Z,SMLF,ICA
PD_MP5981_1_MODE         R2086            1        Q_RES_0402LF-0,5%,1/16W,CHIP,CA
PD_MP5981_1_MODE         U81              8        MP5981GLUZ-MP5981GLU-Z,SMLF,ICA
PD_PASSWORD_CLEAR        R1335            2        Q_RES_0402LF-1K,1%,1/16W,CHIP,A
PD_PASSWORD_CLEAR        S2               4        SW8S_DHNF04FTVTR-SW8S_DHNF04FTA
PD_PCH_USB2_COMP         R496             1        Q_RES_0402LF-113,1%,1/16W,CHIPA
PD_PCH_USB2_COMP         U4               BB41     EMMITSBURG_REV0P9-GFNOCPU04302A
PD_PCH_XCLK_BIASREF      R477             1        Q_RES_0402LF-60.4,1%,1/16W,CHIA
PD_PCH_XCLK_BIASREF      U4               N29      EMMITSBURG_REV0P9-GFNOCPU04302A
PD_PCIE_EDSFF1A_PRSNT_0_N J62              A12      SCONN84_123318136-SCONN84_1-23A
PD_PCIE_EDSFF1A_PRSNT_0_N R1972            1        Q_RES_0402LF-100,1%,1/16W,CHIPA
PD_PCIE_EDSFF1B_PRSNT_0_N J87              A12      SCONN84_123318136-SCONN84_1-23A
PD_PCIE_EDSFF1B_PRSNT_0_N R1982            1        Q_RES_0402LF-100,1%,1/16W,CHIPA
PD_PCIE_EDSFF2A_PRSNT_0_N J33              A12      SCONN84_123318136-SCONN84_1-23A
PD_PCIE_EDSFF2A_PRSNT_0_N R1614            1        Q_RES_0402LF-100,1%,1/16W,CHIPA
PD_PCIE_EDSFF2B_PRSNT_0_N J34              A12      SCONN84_123318136-SCONN84_1-23A
PD_PCIE_EDSFF2B_PRSNT_0_N R1616            1        Q_RES_0402LF-100,1%,1/16W,CHIPA
PD_PCIE_EDSFF4A_PRSNT_0_N J88              A12      SCONN84_123318136-SCONN84_1-23A
PD_PCIE_EDSFF4A_PRSNT_0_N R1992            1        Q_RES_0402LF-100,1%,1/16W,CHIPA
PD_PCIE_EDSFF4B_PRSNT_0_N J61              A12      SCONN84_123318136-SCONN84_1-23A
PD_PCIE_EDSFF4B_PRSNT_0_N R2004            1        Q_RES_0402LF-100,1%,1/16W,CHIPA
PD_PIROM_CPU0_ADDR0      R335             2        Q_RES_0402LF-1K,1%,1/16W,EMPTYA
PD_PIROM_CPU0_ADDR0      R515             1        Q_RES_0402LF-10K,1%,1/16W,CHIPA
PD_PIROM_CPU0_ADDR0      U2               CR70     SOCKET4677_AZIFS054P001C01-SOCA
PD_PIROM_CPU0_ADDR1      R333             2        Q_RES_0402LF-1K,1%,1/16W,EMPTYA
PD_PIROM_CPU0_ADDR1      R334             1        Q_RES_0402LF-10K,1%,1/16W,CHIPA
PD_PIROM_CPU0_ADDR1      U2               CT71     SOCKET4677_AZIFS054P001C01-SOCA
PD_PIROM_CPU0_ADDR2      R331             2        Q_RES_0402LF-1K,1%,1/16W,EMPTYA
PD_PIROM_CPU0_ADDR2      R332             1        Q_RES_0402LF-10K,1%,1/16W,CHIPA
PD_PIROM_CPU0_ADDR2      U2               CP71     SOCKET4677_AZIFS054P001C01-SOCA
PD_PIROM_CPU1_ADDR1      R627             2        Q_RES_0402LF-1K,1%,1/16W,EMPTYA
PD_PIROM_CPU1_ADDR1      R628             1        Q_RES_0402LF-10K,1%,1/16W,CHIPA
PD_PIROM_CPU1_ADDR1      U1               CT71     SOCKET4677_AZIFS054P001C01-SOCA
PD_PIROM_CPU1_ADDR2      R625             2        Q_RES_0402LF-1K,1%,1/16W,EMPTYA
PD_PIROM_CPU1_ADDR2      R626             1        Q_RES_0402LF-10K,1%,1/16W,CHIPA
PD_PIROM_CPU1_ADDR2      U1               CP71     SOCKET4677_AZIFS054P001C01-SOCA
PD_RCOMP_1P8_3P3         R497             1        Q_RES_0402LF-200,1%,1/16W,CHIPA
PD_RCOMP_1P8_3P3         U4               AC13     EMMITSBURG_REV0P9-GFNOCPU04302A
PD_RISER1_PRSNT1         J55              B1       SCONN140_G64V3431BHR-SCONN140_A
PD_RISER1_PRSNT1         R2172            1        Q_RES_0402LF-100,1%,1/16W,CHIPA
PD_RISER2_PRSNT1         J89              A1       SCONN280_ME1028040102011-SCONNA
PD_RISER2_PRSNT1         R1574            1        Q_RES_0402LF-100,1%,1/16W,CHIPA
PD_RISER3_PRSNT1         J57              B1       SCONN140_G64V3431BHR-SCONN140_A
PD_RISER3_PRSNT1         R1578            1        Q_RES_0402LF-100,1%,1/16W,CHIPA
PD_RST_RTCRST_N          R1333            2        Q_RES_0402LF-1K,1%,1/16W,CHIP,A
PD_RST_RTCRST_N          S2               2        SW8S_DHNF04FTVTR-SW8S_DHNF04FTA
PD_SMB_OCP1_HP_ADD0      R1127            2        Q_RES_0402LF-1K,5%,1/16W,EMPTYA
PD_SMB_OCP1_HP_ADD0      R1128            1        Q_RES_0402LF-1K,5%,1/16W,CHIP,A
PD_SMB_OCP1_HP_ADD0      U51              21       PCA9555PW_SMLF-PCA9555PW,IC,TMA
PD_SMB_OCP1_HP_ADD1      R1125            2        Q_RES_0402LF-1K,5%,1/16W,EMPTYA
PD_SMB_OCP1_HP_ADD1      R1126            1        Q_RES_0402LF-1K,5%,1/16W,CHIP,A
PD_SMB_OCP1_HP_ADD1      U51              2        PCA9555PW_SMLF-PCA9555PW,IC,TMA
PD_SMB_OCP1_HP_ADD2      R1123            2        Q_RES_0402LF-1K,5%,1/16W,EMPTYA
PD_SMB_OCP1_HP_ADD2      R1124            1        Q_RES_0402LF-1K,5%,1/16W,CHIP,A
PD_SMB_OCP1_HP_ADD2      U51              3        PCA9555PW_SMLF-PCA9555PW,IC,TMA
PD_SUSCLK                R1197            2        Q_RES_0402LF-1K,5%,1/16W,EMPTYA
PD_SUSCLK                U4               AR7      EMMITSBURG_REV0P9-GFNOCPU04302A
PD_TRST_P3               J42              8        SCONN60_QSH03001LDAKTR-SCONN60A
PD_TRST_P3               R769             1        Q_RES_0402LF-10K,1%,1/16W,CHIPA
PD_USB_INT_ILIM          R462             1        Q_RES_0402LF-20K,1%,1/16W,CHIPA
PD_USB_INT_ILIM          U27              5        TPS2553DBVR1-TPS2553DBVR-1,SMLA
PECI_BMC                 J41              B27      SCONN168_623403212-SCONN168_6-A
PECI_BMC                 R144             1        Q_RES_0402LF-10,1%,1/16W,CHIP,A
PECI_CPU0_GTL_R          R3               2        Q_RES_0402LF-33.2,1%,1/16W,CHIA
PECI_CPU0_GTL_R          U2               BH24     SOCKET4677_AZIFS054P001C01-SOCA
PECI_CPU1_GTL_R          R63              2        Q_RES_0402LF-33.2,1%,1/16W,CHIA
PECI_CPU1_GTL_R          U1               BH24     SOCKET4677_AZIFS054P001C01-SOCA
PECI_CPU_GTL             R3               1        Q_RES_0402LF-33.2,1%,1/16W,CHIA
PECI_CPU_GTL             R63              1        Q_RES_0402LF-33.2,1%,1/16W,CHIA
PECI_CPU_GTL             R143             2        Q_RES_0402LF-0,5%,1/16W,EMPTY,A
PECI_CPU_GTL             R144             2        Q_RES_0402LF-10,1%,1/16W,CHIP,A
PECI_CPU_GTL             R146             2        Q_RES_0402LF-4.75K,1%,1/16W,EMA
PECI_CPU_GTL             R148             1        Q_RES_0402LF-10K,1%,1/16W,CHIPA
PECI_PCH                 R143             1        Q_RES_0402LF-0,5%,1/16W,EMPTY,A
PECI_PCH                 U4               J10      EMMITSBURG_REV0P9-GFNOCPU04302A
PGPPA_AUX                C513             1        Q_CAP_C0805-22UF,16V,20%,X6S,CA
PGPPA_AUX                C535             1        Q_CAP_C0805-22UF,16V,20%,X6S,CA
PGPPA_AUX                C605             1        Q_CAP_C0402-1UF,25V,10%,X6S,CHA
PGPPA_AUX                C606             1        Q_CAP_C0402-1UF,25V,10%,X6S,CHA
PGPPA_AUX                C607             1        Q_CAP_0402-0.1UF,25V,10%,X7R,CA
PGPPA_AUX                C608             1        Q_CAP_0402-0.1UF,25V,10%,X7R,CA
PGPPA_AUX                C1229            1        Q_CAP_0402-0.1UF,25V,10%,X7R,CA
PGPPA_AUX                C1408            1        Q_CAP_0402-0.1UF,25V,10%,X7R,CA
PGPPA_AUX                R1253            1        Q_RES_0402LF-1K,1%,1/16W,CHIP,A
PGPPA_AUX                R1254            1        Q_RES_0402LF-10K,1%,1/16W,CHIPA
PGPPA_AUX                R1255            1        Q_RES_0402LF-1K,1%,1/16W,CHIP,A
PGPPA_AUX                R1271            1        Q_RES_0402LF-2.21K    ,1%  ,1/A
PGPPA_AUX                R1697            1        Q_RES_0402LF-10K,1%,1/16W,CHIPA
PGPPA_AUX                R1747            2        Q_RES_0805LF-0,5%,1/8W,CHIP,CSA
PGPPA_AUX                R1750            1        Q_RES_0402LF-1K,1%,1/16W,CHIP,A
PGPPA_AUX                R1763            1        Q_RES_0402LF-10K,1%,1/16W,EMPTA
PGPPA_AUX                R1765            1        Q_RES_0805LF-0,5%,1/8W,EMPTY,CA
PGPPA_AUX                R1961            1        Q_RES_0402LF-10K,1%,1/16W,CHIPA
PGPPA_AUX                U54              5        74LVC1G07GV-74LVC1G07GV,SMLF,IA
PGPPA_AUX                U60              5        NC7SB3157_SMLF-NC7SB3157P6X,NCA
PGPPA_AUX                U61              5        NC7SB3157_SMLF-NC7SB3157P6X,NCA
PGPPA_AUX                U101             5        SN74LVC1G17DCKR-SN74LVC1G17DCKA
PRSNT0_N                 J41              OCP_B3   SCONN168_623403212-SCONN168_6-A
PRSNT0_N                 R1801            1        Q_RES_0402LF-0,5%,1/16W,CHIP,CA
PSU1_THROTTLE_R          J44              19       CONN24_52SH90245BRD-CONN24_52SA
PSU1_THROTTLE_R          L12              1        Q_INDUCTOR_SMLF-BLM15AG121SN1DA
PUD_PCH_BOOT_MODE_CPU0   R252             2        Q_RES_0402LF-240,1%,1/16W,CHIPA
PUD_PCH_BOOT_MODE_CPU0   U2               CF61     SOCKET4677_AZIFS054P001C01-SOCA
PUD_PCH_BOOT_MODE_CPU1   R258             2        Q_RES_0402LF-240,1%,1/16W,CHIPA
PUD_PCH_BOOT_MODE_CPU1   U1               CF61     SOCKET4677_AZIFS054P001C01-SOCA
PUD_XTAL_CPU0_MODE0      R1232            2        Q_RES_0402LF-240,1%,1/16W,EMPTA
PUD_XTAL_CPU0_MODE0      R1238            2        Q_RES_0402LF-240,1%,1/16W,EMPTA
PUD_XTAL_CPU0_MODE0      U2               CL72     SOCKET4677_AZIFS054P001C01-SOCA
PUD_XTAL_CPU0_MODE1      R1233            2        Q_RES_0402LF-240,1%,1/16W,EMPTA
PUD_XTAL_CPU0_MODE1      R1239            2        Q_RES_0402LF-240,1%,1/16W,EMPTA
PUD_XTAL_CPU0_MODE1      U2               CJ72     SOCKET4677_AZIFS054P001C01-SOCA
PUD_XTAL_CPU1_MODE0      R1229            2        Q_RES_0402LF-240,1%,1/16W,EMPTA
PUD_XTAL_CPU1_MODE0      R1235            2        Q_RES_0402LF-240,1%,1/16W,EMPTA
PUD_XTAL_CPU1_MODE0      U1               CL72     SOCKET4677_AZIFS054P001C01-SOCA
PUD_XTAL_CPU1_MODE1      R1230            2        Q_RES_0402LF-240,1%,1/16W,EMPTA
PUD_XTAL_CPU1_MODE1      R1236            2        Q_RES_0402LF-240,1%,1/16W,EMPTA
PUD_XTAL_CPU1_MODE1      U1               CJ72     SOCKET4677_AZIFS054P001C01-SOCA
PU_ACPRESENT             R1198            2        Q_RES_0402LF-10K,1%,1/16W,CHIPA
PU_ACPRESENT             U4               AN7      EMMITSBURG_REV0P9-GFNOCPU04302A
PU_BIOS_RCVR_BOOT        R1317            2        Q_RES_0402LF-1K,1%,1/16W,CHIP,A
PU_BIOS_RCVR_BOOT        S1               2        SW8S_DHNF04FTVTR-SW8S_DHNF04FTA
PU_CK440_SHFT_LD_N       R1204            2        Q_RES_0402LF-10K,1%,1/16W,EMPTA
PU_CK440_SHFT_LD_N       R1267            1        Q_RES_0402LF-1K,1%,1/16W,CHIP,A
PU_CK440_SHFT_LD_N       U13              B42      9SQ440NQQI8-9SQ440NQQI8,SMLF,IA
PU_CLK25M_OSC_FPGA_EN    OSC2             1        Q_OSC4P_SMLF-25MHZ,OSC,BF62500A
PU_CLK25M_OSC_FPGA_EN    R1099            2        Q_RES_0402LF-10K,1%,1/16W,CHIPA
PU_CLK_PFT_LOST_N        R1958            2        Q_RES_0402LF-10K,1%,1/16W,CHIPA
PU_CLK_PFT_LOST_N        U13              B4       9SQ440NQQI8-9SQ440NQQI8,SMLF,IA
PU_CPU0_FRMAGENT         R277             2        Q_RES_0402LF-240,1%,1/16W,CHIPA
PU_CPU0_FRMAGENT         U2               AU17     SOCKET4677_AZIFS054P001C01-SOCA
PU_CPU0_LEGACY_SKT       R282             2        Q_RES_0402LF-240,1%,1/16W,CHIPA
PU_CPU0_LEGACY_SKT       U2               CY59     SOCKET4677_AZIFS054P001C01-SOCA
PU_CPU0_SAFE_MODE_BOOT   R276             2        Q_RES_0402LF-240,1%,1/16W,EMPTA
PU_CPU0_SAFE_MODE_BOOT   U2               AU23     SOCKET4677_AZIFS054P001C01-SOCA
PU_CPU0_SOCKET_ID0       R279             2        Q_RES_0402LF-240,1%,1/16W,EMPTA
PU_CPU0_SOCKET_ID0       U2               CW60     SOCKET4677_AZIFS054P001C01-SOCA
PU_CPU0_SOCKET_ID1       R280             2        Q_RES_0402LF-240,1%,1/16W,EMPTA
PU_CPU0_SOCKET_ID1       U2               CY61     SOCKET4677_AZIFS054P001C01-SOCA
PU_CPU0_SOCKET_ID2       R281             2        Q_RES_0402LF-240,1%,1/16W,EMPTA
PU_CPU0_SOCKET_ID2       U2               CT61     SOCKET4677_AZIFS054P001C01-SOCA
PU_CPU0_TXT_AGENT        R275             2        Q_RES_0402LF-240,1%,1/16W,CHIPA
PU_CPU0_TXT_AGENT        U2               BT26     SOCKET4677_AZIFS054P001C01-SOCA
PU_CPU0_UPI0_AC_COUPLING R94              2        Q_RES_0402LF-240,1%,1/16W,EMPTA
PU_CPU0_UPI0_AC_COUPLING U2               BA23     SOCKET4677_AZIFS054P001C01-SOCA
PU_CPU0_UPI1_AC_COUPLING R95              2        Q_RES_0402LF-240,1%,1/16W,EMPTA
PU_CPU0_UPI1_AC_COUPLING U2               CW19     SOCKET4677_AZIFS054P001C01-SOCA
PU_CPU0_UPI2_AC_COUPLING R96              2        Q_RES_0402LF-240,1%,1/16W,EMPTA
PU_CPU0_UPI2_AC_COUPLING U2               BB65     SOCKET4677_AZIFS054P001C01-SOCA
PU_CPU0_UPI3_AC_COUPLING R97              2        Q_RES_0402LF-240,1%,1/16W,EMPTA
PU_CPU0_UPI3_AC_COUPLING U2               CK71     SOCKET4677_AZIFS054P001C01-SOCA
PU_CPU1_FRMAGENT         R263             2        Q_RES_0402LF-240,1%,1/16W,EMPTA
PU_CPU1_FRMAGENT         U1               AU17     SOCKET4677_AZIFS054P001C01-SOCA
PU_CPU1_LEGACY_SKT       R268             2        Q_RES_0402LF-240,1%,1/16W,EMPTA
PU_CPU1_LEGACY_SKT       U1               CY59     SOCKET4677_AZIFS054P001C01-SOCA
PU_CPU1_SAFE_MODE_BOOT   R262             2        Q_RES_0402LF-240,1%,1/16W,EMPTA
PU_CPU1_SAFE_MODE_BOOT   U1               AU23     SOCKET4677_AZIFS054P001C01-SOCA
PU_CPU1_SOCKET_ID0       R265             2        Q_RES_0402LF-240,1%,1/16W,CHIPA
PU_CPU1_SOCKET_ID0       U1               CW60     SOCKET4677_AZIFS054P001C01-SOCA
PU_CPU1_SOCKET_ID1       R266             2        Q_RES_0402LF-240,1%,1/16W,EMPTA
PU_CPU1_SOCKET_ID1       U1               CY61     SOCKET4677_AZIFS054P001C01-SOCA
PU_CPU1_SOCKET_ID2       R267             2        Q_RES_0402LF-240,1%,1/16W,EMPTA
PU_CPU1_SOCKET_ID2       U1               CT61     SOCKET4677_AZIFS054P001C01-SOCA
PU_CPU1_TXT_AGENT        R261             2        Q_RES_0402LF-240,1%,1/16W,EMPTA
PU_CPU1_TXT_AGENT        U1               BT26     SOCKET4677_AZIFS054P001C01-SOCA
PU_CPU1_UPI0_AC_COUPLING R90              2        Q_RES_0402LF-240,1%,1/16W,EMPTA
PU_CPU1_UPI0_AC_COUPLING U1               BA23     SOCKET4677_AZIFS054P001C01-SOCA
PU_CPU1_UPI1_AC_COUPLING R91              2        Q_RES_0402LF-240,1%,1/16W,EMPTA
PU_CPU1_UPI1_AC_COUPLING U1               CW19     SOCKET4677_AZIFS054P001C01-SOCA
PU_CPU1_UPI2_AC_COUPLING R92              2        Q_RES_0402LF-240,1%,1/16W,EMPTA
PU_CPU1_UPI2_AC_COUPLING U1               BB65     SOCKET4677_AZIFS054P001C01-SOCA
PU_CPU1_UPI3_AC_COUPLING R93              2        Q_RES_0402LF-240,1%,1/16W,EMPTA
PU_CPU1_UPI3_AC_COUPLING U1               CK71     SOCKET4677_AZIFS054P001C01-SOCA
PU_DAS_DSS_N             J59              10       SCONN75K_APCI0155P004A-SCONN75A
PU_DAS_DSS_N             R484             2        Q_RES_0402LF-4.7K,1%,1/16W,EMPA
PU_EDSFF1B_PERST1_CLKREQ_N J87              A11      SCONN84_123318136-SCONN84_1-23A
PU_EDSFF1B_PERST1_CLKREQ_N R1979            1        Q_RES_0402LF-10K,1%,1/16W,CHIPA
PU_EDSFF2A_PERST1_CLKREQ_N J33              A11      SCONN84_123318136-SCONN84_1-23A
PU_EDSFF2A_PERST1_CLKREQ_N R395             1        Q_RES_0402LF-10K,1%,1/16W,CHIPA
PU_EDSFF2B_PERST1_CLKREQ_N J34              A11      SCONN84_123318136-SCONN84_1-23A
PU_EDSFF2B_PERST1_CLKREQ_N R399             1        Q_RES_0402LF-10K,1%,1/16W,CHIPA
PU_ESPI_ENABLE_STRAP     R2133            2        Q_RES_0402LF-1K,1%,1/16W,CHIP,A
PU_ESPI_ENABLE_STRAP     S1               1        SW8S_DHNF04FTVTR-SW8S_DHNF04FTA
PU_FLASH_SECURITY_STRAP  R1325            2        Q_RES_0402LF-1K,1%,1/16W,CHIP,A
PU_FLASH_SECURITY_STRAP  S2               1        SW8S_DHNF04FTVTR-SW8S_DHNF04FTA
PU_GTL2014_BMC_JTAG_DIR_1 R1377            2        Q_RES_0402LF-1K,1%,1/16W,CHIP,A
PU_GTL2014_BMC_JTAG_DIR_1 U84              1        GTL2014PW-GTL2014PW,SMLF,IC,ALA
PU_GTL2014_BMC_JTAG_DIR_2 R1376            2        Q_RES_0402LF-1K,1%,1/16W,CHIP,A
PU_GTL2014_BMC_JTAG_DIR_2 U83              1        GTL2014PW-GTL2014PW,SMLF,IC,ALA
PU_LAN_WAKE_N            R453             2        Q_RES_0402LF-10K,1%,1/16W,CHIPA
PU_LAN_WAKE_N            U4               AU7      EMMITSBURG_REV0P9-GFNOCPU04302A
PU_LPC_PME_N             R1259            2        Q_RES_0402LF-10K,1%,1/16W,CHIPA
PU_LPC_PME_N             U4               AJ3      EMMITSBURG_REV0P9-GFNOCPU04302A
PU_MAIN_FPGA_CONFIG_DONE R1401            1        Q_RES_0402LF-10K,1%,1/16W,CHIPA
PU_MAIN_FPGA_CONFIG_DONE U122             H8       10M04SAU324I7G-10M04SAU324I7G,A
PU_MAIN_FPGA_CONFIG_N    R1488            1        Q_RES_0402LF-10K,1%,1/16W,CHIPA
PU_MAIN_FPGA_CONFIG_N    U122             H9       10M04SAU324I7G-10M04SAU324I7G,A
PU_MAIN_FPGA_STATUS_N    R1436            1        Q_RES_0402LF-10K,1%,1/16W,CHIPA
PU_MAIN_FPGA_STATUS_N    U122             G8       10M04SAU324I7G-10M04SAU324I7G,A
PU_MP5981_0_D_OC         R2072            2        Q_RES_0402LF-100K,1%,1/16W,CHIA
PU_MP5981_0_D_OC         U107             3        MP5981GLUZ-MP5981GLU-Z,SMLF,ICA
PU_MP5981_0_GOK          R2073            2        Q_RES_0402LF-100K,1%,1/16W,CHIA
PU_MP5981_0_GOK          U107             5        MP5981GLUZ-MP5981GLU-Z,SMLF,ICA
PU_MP5981_1_D_OC         R2085            2        Q_RES_0402LF-100K,1%,1/16W,CHIA
PU_MP5981_1_D_OC         U81              3        MP5981GLUZ-MP5981GLU-Z,SMLF,ICA
PU_MP5981_1_GOK          R2084            2        Q_RES_0402LF-100K,1%,1/16W,CHIA
PU_MP5981_1_GOK          U81              5        MP5981GLUZ-MP5981GLU-Z,SMLF,ICA
PU_NO_REBOOT_STRAP       R367             2        Q_RES_0402LF-1K,5%,1/16W,CHIP,A
PU_NO_REBOOT_STRAP       U4               AU16     EMMITSBURG_REV0P9-GFNOCPU04302A
PU_OC3_USB_N             R635             1        Q_RES_0402LF-10K,1%,1/16W,CHIPA
PU_OC3_USB_N             U4               BG28     EMMITSBURG_REV0P9-GFNOCPU04302A
PU_OC4_USB_N             R727             1        Q_RES_0402LF-10K,1%,1/16W,CHIPA
PU_OC4_USB_N             U4               BG26     EMMITSBURG_REV0P9-GFNOCPU04302A
PU_OC5_USB_N             R770             1        Q_RES_0402LF-10K,1%,1/16W,CHIPA
PU_OC5_USB_N             U4               BG24     EMMITSBURG_REV0P9-GFNOCPU04302A
PU_OC6_USB_N             R913             1        Q_RES_0402LF-10K,1%,1/16W,CHIPA
PU_OC6_USB_N             U4               BG22     EMMITSBURG_REV0P9-GFNOCPU04302A
PU_OCP_SFF_WAKE_OE       R1592            2        Q_RES_0402LF-10K,1%,1/16W,CHIPA
PU_OCP_SFF_WAKE_OE       U82              1        74LVC1G126GW_SMLF-74LVC1G126GWA
PU_PCH_PLD_3V3AUX_ALERT_N R1583            1        Q_RES_0402LF-10K,1%,1/16W,CHIPA
PU_PCH_PLD_3V3AUX_ALERT_N U4               AN2      EMMITSBURG_REV0P9-GFNOCPU04302A
PU_PCH_PMCALERT_N        R456             2        Q_RES_0402LF-10K,1%,1/16W,CHIPA
PU_PCH_PMCALERT_N        U4               J4       EMMITSBURG_REV0P9-GFNOCPU04302A
PU_PCH_VRALERT_N         R1257            2        Q_RES_0402LF-10K,1%,1/16W,CHIPA
PU_PCH_VRALERT_N         U4               AC3      EMMITSBURG_REV0P9-GFNOCPU04302A
PU_PIROM_CPU0_SM_WP      R650             2        Q_RES_0402LF-1K,1%,1/16W,CHIP,A
PU_PIROM_CPU0_SM_WP      R997             1        Q_RES_0402LF-10K,1%,1/16W,EMPTA
PU_PIROM_CPU0_SM_WP      U2               CR72     SOCKET4677_AZIFS054P001C01-SOCA
PU_PIROM_CPU1_ADDR0      R629             2        Q_RES_0402LF-1K,1%,1/16W,CHIP,A
PU_PIROM_CPU1_ADDR0      R630             1        Q_RES_0402LF-10K,1%,1/16W,EMPTA
PU_PIROM_CPU1_ADDR0      U1               CR70     SOCKET4677_AZIFS054P001C01-SOCA
PU_PIROM_CPU1_SM_WP      R1004            2        Q_RES_0402LF-1K,1%,1/16W,CHIP,A
PU_PIROM_CPU1_SM_WP      R1005            1        Q_RES_0402LF-10K,1%,1/16W,EMPTA
PU_PIROM_CPU1_SM_WP      U1               CR72     SOCKET4677_AZIFS054P001C01-SOCA
PU_PLD_HEARTBEAT_LVC3    D0               A        Q_LED_SMLF-LED_GREEN,19-213/GVA
PU_PLD_HEARTBEAT_LVC3    R1195            2        Q_RES_0402LF-750,1%,1/16W,CHIPA
PU_RST_DEDI_BUSY_PLD_N   R1681            2        Q_RES_0402LF-10K,1%,1/16W,CHIPA
PU_RST_DEDI_BUSY_PLD_N   U122             K3       10M04SAU324I7G-10M04SAU324I7G,A
PU_RST_SMB_EDSFF_N       R1522            2        Q_RES_0402LF-10K,1%,1/16W,CHIPA
PU_RST_SMB_EDSFF_N       U24              3        PCA9548APW-PCA9548APW,SMLF,IC,A
PU_RST_SMB_OCP_SFF_N     J37              A9       SCONN168_623403212-SCONN168_6-A
PU_RST_SMB_OCP_SFF_N     R454             2        Q_RES_0402LF-10K,1%,1/16W,EMPTA
PU_RST_SMB_PCIE3_N       R1667            2        Q_RES_0402LF-10K,1%,1/16W,CHIPA
PU_RST_SMB_PCIE3_N       R1822            2        Q_RES_0402LF-10K,1%,1/16W,CHIPA
PU_RST_SMB_PCIE3_N       R2197            2        Q_RES_0402LF-10K,1%,1/16W,CHIPA
PU_RST_SMB_PCIE3_N       U10              3        PCA9546APWR-PCA9546APWR,SMLF,IA
PU_RST_SMB_PCIE3_N       U36              3        PCA9546APWR-PCA9546APWR,SMLF,IA
PU_RST_SMB_PCIE3_N       U141             3        PCA9546APWR-PCA9546APWR,SMLF,IA
PU_S3M_CPU0_CPLD_CONFD   R320             2        Q_RES_0402LF-10K,1%,1/16W,CHIPA
PU_S3M_CPU0_CPLD_CONFD   U2               CJ64     SOCKET4677_AZIFS054P001C01-SOCA
PU_S3M_CPU0_CPLD_STATUS  R319             2        Q_RES_0402LF-10K,1%,1/16W,CHIPA
PU_S3M_CPU0_CPLD_STATUS  U2               CH65     SOCKET4677_AZIFS054P001C01-SOCA
PU_S3M_CPU1_CPLD_CONFD   R326             2        Q_RES_0402LF-10K,1%,1/16W,CHIPA
PU_S3M_CPU1_CPLD_CONFD   U1               CJ64     SOCKET4677_AZIFS054P001C01-SOCA
PU_S3M_CPU1_CPLD_STATUS  R325             2        Q_RES_0402LF-10K,1%,1/16W,CHIPA
PU_S3M_CPU1_CPLD_STATUS  U1               CH65     SOCKET4677_AZIFS054P001C01-SOCA
PU_SMB_EDSFF_3V3AUX_SCL7 R2057            2        Q_RES_0402LF-2.2K ,5%,1/16W,CHA
PU_SMB_EDSFF_3V3AUX_SCL7 R2065            2        Q_RES_0402LF-0,5%,1/16W,CHIP,CA
PU_SMB_EDSFF_3V3AUX_SDA7 R2058            2        Q_RES_0402LF-2.2K ,5%,1/16W,CHA
PU_SMB_EDSFF_3V3AUX_SDA7 R2066            2        Q_RES_0402LF-0,5%,1/16W,CHIP,CA
PU_SMB_PCH_PLD_3V3AUX_SCL R1581            1        Q_RES_0402LF-2K,1%,1/16W,CHIP,A
PU_SMB_PCH_PLD_3V3AUX_SCL U4               AL1      EMMITSBURG_REV0P9-GFNOCPU04302A
PU_SMB_PCH_PLD_3V3AUX_SDA R1582            1        Q_RES_0402LF-2K,1%,1/16W,CHIP,A
PU_SMB_PCH_PLD_3V3AUX_SDA U4               AT1      EMMITSBURG_REV0P9-GFNOCPU04302A
PU_SMB_SML3_3V3AUX_PCH_SCL R1451            1        Q_RES_0402LF-2K,1%,1/16W,CHIP,A
PU_SMB_SML3_3V3AUX_PCH_SCL U4               AN4      EMMITSBURG_REV0P9-GFNOCPU04302A
PU_SMB_SML3_3V3AUX_PCH_SDA R1452            1        Q_RES_0402LF-2K,1%,1/16W,CHIP,A
PU_SMB_SML3_3V3AUX_PCH_SDA U4               AY1      EMMITSBURG_REV0P9-GFNOCPU04302A
PU_SMB_SML4_3V3AUX_PCH_SCL R1453            1        Q_RES_0402LF-2K,1%,1/16W,CHIP,A
PU_SMB_SML4_3V3AUX_PCH_SCL U4               BA2      EMMITSBURG_REV0P9-GFNOCPU04302A
PU_SMB_SML4_3V3AUX_PCH_SDA R1454            1        Q_RES_0402LF-2K,1%,1/16W,CHIP,A
PU_SMB_SML4_3V3AUX_PCH_SDA U4               AV1      EMMITSBURG_REV0P9-GFNOCPU04302A
PU_SWAP_OVERRIDE_N       R1320            2        Q_RES_0402LF-1K,1%,1/16W,CHIP,A
PU_SWAP_OVERRIDE_N       S1               3        SW8S_DHNF04FTVTR-SW8S_DHNF04FTA
PU_TAP_ODT_CPU0_EN       R1009            2        Q_RES_0402LF-1K,1%,1/16W,EMPTYA
PU_TAP_ODT_CPU0_EN       U2               AY20     SOCKET4677_AZIFS054P001C01-SOCA
PU_TAP_ODT_CPU1_EN       R1008            2        Q_RES_0402LF-1K,1%,1/16W,EMPTYA
PU_TAP_ODT_CPU1_EN       U1               AY20     SOCKET4677_AZIFS054P001C01-SOCA
PU_USB_INT_P5V_EN_N      C564             1        Q_CAP_0402-0.1UF,25V,10%,X7R,CA
PU_USB_INT_P5V_EN_N      R461             2        Q_RES_0402LF-100K,5%,1/16W,CHIA
PU_USB_INT_P5V_EN_N      U27              3        TPS2553DBVR1-TPS2553DBVR-1,SMLA
PVCC1_AUX                PR395            2        Q_RES_0402LF-0,5%,1/16W,CHIP,CA
PVCC1_AUX                PR396            2        Q_RES_0402LF-0,5%,1/16W,EMPTY,A
PVCC1_AUX                PR1329           1        Q_RES_0402LF-5.1,5%,1/16W,CHIPA
PVCCA_AUX_PLD            C1115            1        Q_CAP_C0402-2.2UF,6.3V,20%,EMPA
PVCCA_AUX_PLD            C1124            1        Q_CAP_0402-0.1UF,25V,10%,EMPTYA
PVCCA_AUX_PLD            C1130            1        Q_CAP_0402-0.1UF,25V,10%,EMPTYA
PVCCA_AUX_PLD            C1136            1        Q_CAP_0402-0.1UF,25V,10%,EMPTYA
PVCCA_AUX_PLD            C1140            1        Q_CAP_0402-0.1UF,25V,10%,EMPTYA
PVCCA_AUX_PLD            C1144            1        Q_CAP_0402-0.1UF,25V,10%,EMPTYA
PVCCA_AUX_PLD            C1148            1        Q_CAP_0402-0.1UF,25V,10%,EMPTYA
PVCCA_AUX_PLD            L36              2        Q_INDUCTOR_SMLF-BLM18PG121SN1DA
PVCCA_AUX_PLD            R507             1        Q_RES_0402LF-0,5%,1/16W,EMPTY,A
PVCCA_AUX_PLD            U122             F4       10M04SAU324I7G-10M04SAU324I7G,A
PVCCA_AUX_PLD            U122             F6       10M04SAU324I7G-10M04SAU324I7G,A
PVCCA_AUX_PLD            U122             F14      10M04SAU324I7G-10M04SAU324I7G,A
PVCCA_AUX_PLD            U122             M6       10M04SAU324I7G-10M04SAU324I7G,A
PVCCA_AUX_PLD            U122             P13      10M04SAU324I7G-10M04SAU324I7G,A
PVCCD_HV_CPU0            C399             1        Q_CAP_C0402-22UF,4V,20%,X6S,CHA
PVCCD_HV_CPU0            C401             1        Q_CAP_C0402-22UF,4V,20%,X6S,CHA
PVCCD_HV_CPU0            C403             1        Q_CAP_C0402-22UF,4V,20%,X6S,CHA
PVCCD_HV_CPU0            C405             1        Q_CAP_C0402-22UF,4V,20%,X6S,CHA
PVCCD_HV_CPU0            C491             1        Q_CAP_C0805-100UF,4V,20%,X6S,CA
PVCCD_HV_CPU0            C495             1        Q_CAP_C0805-100UF,4V,20%,X6S,CA
PVCCD_HV_CPU0            C499             1        Q_CAP_C0805-100UF,4V,20%,X6S,CA
PVCCD_HV_CPU0            C503             1        Q_CAP_C0805-100UF,4V,20%,X6S,CA
PVCCD_HV_CPU0            C507             1        Q_CAP_C0805-100UF,4V,20%,X6S,CA
PVCCD_HV_CPU0            C511             1        Q_CAP_C0805-100UF,4V,20%,X6S,CA
PVCCD_HV_CPU0            C515             1        Q_CAP_C0603-47UF,2.5V,20%,X6S,A
PVCCD_HV_CPU0            C518             1        Q_CAP_C0603-47UF,2.5V,20%,X6S,A
PVCCD_HV_CPU0            PC639            1        Q_CAP_C0402-100NF,50V,10%,X7R,A
PVCCD_HV_CPU0            PC641            1        Q_CAP_0805-22UF,4V,20%,X6S,TMPA
PVCCD_HV_CPU0            PC642            1        Q_CAP_0805-22UF,4V,20%,X6S,TMPA
PVCCD_HV_CPU0            PC1644           1        Q_CAPP_THLF-560UF,2.5V,20%,OSCA
PVCCD_HV_CPU0            PC1645           1        Q_CAPP_THLF-560UF,2.5V,20%,OSCA
PVCCD_HV_CPU0            PC1910           1        Q_CAPP_SMLF-330UF,2V,35%,SPCAPA
PVCCD_HV_CPU0            PL35             2        Q_INDUCTOR_SMLF-120NH/94A,IND,A
PVCCD_HV_CPU0            PR592            2        Q_RES_0402LF-100,1%,1/16W,CHIPA
PVCCD_HV_CPU0            R175             2        Q_RES_0402LF-100,1%,1/16W,EMPTA
PVCCD_HV_CPU0            R177             2        Q_RES_0402LF-100,1%,1/16W,EMPTA
PVCCD_HV_CPU0            R179             2        Q_RES_0402LF-100,1%,1/16W,EMPTA
PVCCD_HV_CPU0            R181             2        Q_RES_0402LF-100,1%,1/16W,EMPTA
PVCCD_HV_CPU0            R511             1        Q_RES_1206LF-0,5%,1/4W,CHIP,CSA
PVCCD_HV_CPU0            R839             1        Q_RES_0402LF-1K,1%,1/16W,EMPTYA
PVCCD_HV_CPU0            R840             1        Q_RES_0402LF-1K,1%,1/16W,EMPTYA
PVCCD_HV_CPU0            R841             1        Q_RES_0402LF-1K,1%,1/16W,EMPTYA
PVCCD_HV_CPU0            R842             1        Q_RES_0402LF-1K,1%,1/16W,EMPTYA
PVCCD_HV_CPU0            U2               AT36     SOCKET4677_AZIFS054P001C01-SOCA
PVCCD_HV_CPU0            U2               AT55     SOCKET4677_AZIFS054P001C01-SOCA
PVCCD_HV_CPU0            U2               AU3      SOCKET4677_AZIFS054P001C01-SOCA
PVCCD_HV_CPU0            U2               AU7      SOCKET4677_AZIFS054P001C01-SOCA
PVCCD_HV_CPU0            U2               AU35     SOCKET4677_AZIFS054P001C01-SOCA
PVCCD_HV_CPU0            U2               AU54     SOCKET4677_AZIFS054P001C01-SOCA
PVCCD_HV_CPU0            U2               AV34     SOCKET4677_AZIFS054P001C01-SOCA
PVCCD_HV_CPU0            U2               AV36     SOCKET4677_AZIFS054P001C01-SOCA
PVCCD_HV_CPU0            U2               AV53     SOCKET4677_AZIFS054P001C01-SOCA
PVCCD_HV_CPU0            U2               AV55     SOCKET4677_AZIFS054P001C01-SOCA
PVCCD_HV_CPU0            U2               BA3      SOCKET4677_AZIFS054P001C01-SOCA
PVCCD_HV_CPU0            U2               BA7      SOCKET4677_AZIFS054P001C01-SOCA
PVCCD_HV_CPU0            U2               BE3      SOCKET4677_AZIFS054P001C01-SOCA
PVCCD_HV_CPU0            U2               BE7      SOCKET4677_AZIFS054P001C01-SOCA
PVCCD_HV_CPU0            U2               BE11     SOCKET4677_AZIFS054P001C01-SOCA
PVCCD_HV_CPU0            U2               BJ3      SOCKET4677_AZIFS054P001C01-SOCA
PVCCD_HV_CPU0            U2               BJ7      SOCKET4677_AZIFS054P001C01-SOCA
PVCCD_HV_CPU0            U2               BJ11     SOCKET4677_AZIFS054P001C01-SOCA
PVCCD_HV_CPU0            U2               BN7      SOCKET4677_AZIFS054P001C01-SOCA
PVCCD_HV_CPU0            U2               CA7      SOCKET4677_AZIFS054P001C01-SOCA
PVCCD_HV_CPU0            U2               CE7      SOCKET4677_AZIFS054P001C01-SOCA
PVCCD_HV_CPU0            U2               CW35     SOCKET4677_AZIFS054P001C01-SOCA
PVCCD_HV_CPU0            U2               CW37     SOCKET4677_AZIFS054P001C01-SOCA
PVCCD_HV_CPU0            U2               CW52     SOCKET4677_AZIFS054P001C01-SOCA
PVCCD_HV_CPU0            U2               CW54     SOCKET4677_AZIFS054P001C01-SOCA
PVCCD_HV_CPU0            U2               CW56     SOCKET4677_AZIFS054P001C01-SOCA
PVCCD_HV_CPU0            U2               CY34     SOCKET4677_AZIFS054P001C01-SOCA
PVCCD_HV_CPU0            U2               CY36     SOCKET4677_AZIFS054P001C01-SOCA
PVCCD_HV_CPU0            U2               CY53     SOCKET4677_AZIFS054P001C01-SOCA
PVCCD_HV_CPU0_ACSP1      PU35             23       ISL69260IRAZT-ISL69260IRAZ-T,SA
PVCCD_HV_CPU0_ACSP1      PU36             25       RAA2213404GNPHB0-RAA2213404GNPA
PVCCD_HV_CPU0_ADDR       PR357            2        Q_RES_0402LF-28K,1%,1/16W,EMPTA
PVCCD_HV_CPU0_ADDR       PR358            2        Q_RES_0402LF-4.64K,0.5%,1/16W,A
PVCCD_HV_CPU0_ADDR       PU35             34       ISL69260IRAZT-ISL69260IRAZ-T,SA
PVCCD_HV_CPU0_APWM1      PU35             8        ISL69260IRAZT-ISL69260IRAZ-T,SA
PVCCD_HV_CPU0_APWM1      PU36             21       RAA2213404GNPHB0-RAA2213404GNPA
PVCCD_HV_CPU0_ATSEN      PC631            1        Q_CAP_0402-470PF,50V,10%,X7R,TA
PVCCD_HV_CPU0_ATSEN      PR634            1        Q_RES_0402LF-10K,1%,1/16W,EMPTB
PVCCD_HV_CPU0_ATSEN      PU35             35       ISL69260IRAZT-ISL69260IRAZ-T,SA
PVCCD_HV_CPU0_ATSEN      PU36             1        RAA2213404GNPHB0-RAA2213404GNPA
PVCCD_HV_CPU0_EN_R       PR363            2        Q_RES_0402LF-0,5%,1/16W,CHIP,CA
PVCCD_HV_CPU0_EN_R       PU35             13       ISL69260IRAZT-ISL69260IRAZ-T,SA
PVCCD_HV_CPU0_FAULT      PR372            2        Q_RES_0402LF-1K,1%,1/16W,CHIP,A
PVCCD_HV_CPU0_FAULT      PU35             33       ISL69260IRAZT-ISL69260IRAZ-T,SA
PVCCD_HV_CPU0_ISENSE_N   PC628            1        Q_CAP_0402-0.1UF,25V,10%,X7R,CA
PVCCD_HV_CPU0_ISENSE_N   PC813            1        Q_CAP_C0402-1UF,16V,10%,X6S,CHA
PVCCD_HV_CPU0_ISENSE_N   PR373            1        Q_RES_0402LF-1K,1%,1/16W,EMPTYA
PVCCD_HV_CPU0_ISENSE_N   PR1390           2        Q_RES_0402LF-49.9     ,1%  ,1/A
PVCCD_HV_CPU0_ISENSE_N   PU35             38       ISL69260IRAZT-ISL69260IRAZ-T,SA
PVCCD_HV_CPU0_ISENSE_P   PC624            1        Q_CAP_0402-0.1UF,25V,10%,X7R,CA
PVCCD_HV_CPU0_ISENSE_P   PC813            2        Q_CAP_C0402-1UF,16V,10%,X6S,CHA
PVCCD_HV_CPU0_ISENSE_P   PR369            1        Q_RES_0402LF-1K,1%,1/16W,EMPTYA
PVCCD_HV_CPU0_ISENSE_P   PR1380           2        Q_RES_0402LF-49.9     ,1%  ,1/A
PVCCD_HV_CPU0_ISENSE_P   PU35             37       ISL69260IRAZT-ISL69260IRAZ-T,SA
PVCCD_HV_CPU0_ISYS_R     PR409            1        Q_RES_0402LF-0,5%,1/16W,EMPTY,A
PVCCD_HV_CPU0_ISYS_R     PR1311           1        Q_RES_0402LF-0,5%,1/16W,CHIP,CA
PVCCD_HV_CPU0_ISYS_R     PU35             36       ISL69260IRAZT-ISL69260IRAZ-T,SA
PVCCD_HV_CPU0_LSET1      PR2718           1        Q_RES_0402LF-8.87K,1%,1/16W,EMA
PVCCD_HV_CPU0_LSET1      PU36             5        RAA2213404GNPHB0-RAA2213404GNPA
PVCCD_HV_CPU0_NC1        PR1785           1        Q_RES_0402LF-0,5%,1/16W,CHIP,CA
PVCCD_HV_CPU0_NC1        PU36             3        RAA2213404GNPHB0-RAA2213404GNPA
PVCCD_HV_CPU0_PIN_ALT    PR370            2        Q_RES_0402LF-1K,1%,1/16W,CHIP,A
PVCCD_HV_CPU0_PIN_ALT    PU35             15       ISL69260IRAZT-ISL69260IRAZ-T,SA
PVCCD_HV_CPU0_PVCC       PR380            1        Q_RES_0402LF-2.2,1%,1/16W,CHIPA
PVCCD_HV_CPU0_PVCC       PR635            2        Q_RES_0402LF-0,5%,1/16W,CHIP,CA
PVCCD_HV_CPU0_PVCC       PR636            2        Q_RES_0402LF-0,5%,1/16W,EMPTY,A
PVCCD_HV_CPU0_VCC        PC629            1        Q_CAP_C0402-100NF,50V,10%,EMPTA
PVCCD_HV_CPU0_VCC        PC632            1        Q_CAP_C0402-1UF,16V,10%,X6S,CHA
PVCCD_HV_CPU0_VCC        PR375            1        Q_RES_0402LF-1,1%,1/16W,CHIP,CA
PVCCD_HV_CPU0_VCC        PU35             39       ISL69260IRAZT-ISL69260IRAZ-T,SA
PVCCD_HV_CPU0_VDD1       PC633            1        Q_CAP_C0402-2.2UF,10V,10%,X6S,A
PVCCD_HV_CPU0_VDD1       PR380            2        Q_RES_0402LF-2.2,1%,1/16W,CHIPA
PVCCD_HV_CPU0_VDD1       PR1785           2        Q_RES_0402LF-0,5%,1/16W,CHIP,CA
PVCCD_HV_CPU0_VDD1       PU36             4        RAA2213404GNPHB0-RAA2213404GNPA
PVCCD_HV_CPU0_VDD1       PU36             22       RAA2213404GNPHB0-RAA2213404GNPA
PVCCD_HV_CPU0_VREF       PC630            1        Q_CAP_0402-4.7UF,6.3V,20%,X6S,A
PVCCD_HV_CPU0_VREF       PC1196           1        Q_CAP_C0402-1UF,16V,10%,X6S,CHA
PVCCD_HV_CPU0_VREF       PC1354           2        Q_CAP_0402-0.1UF,25V,10%,X7R,CA
PVCCD_HV_CPU0_VREF       PR357            1        Q_RES_0402LF-28K,1%,1/16W,EMPTA
PVCCD_HV_CPU0_VREF       PU35             40       ISL69260IRAZT-ISL69260IRAZ-T,SA
PVCCD_HV_CPU0_VREF       PU36             24       RAA2213404GNPHB0-RAA2213404GNPA
PVCCD_HV_CPU1            C423             1        Q_CAP_C0402-22UF,4V,20%,X6S,CHA
PVCCD_HV_CPU1            C425             1        Q_CAP_C0402-22UF,4V,20%,X6S,CHA
PVCCD_HV_CPU1            C427             1        Q_CAP_C0402-22UF,4V,20%,X6S,CHA
PVCCD_HV_CPU1            C429             1        Q_CAP_C0402-22UF,4V,20%,X6S,CHA
PVCCD_HV_CPU1            C447             1        Q_CAP_C0805-100UF,4V,20%,X6S,CA
PVCCD_HV_CPU1            C451             1        Q_CAP_C0805-100UF,4V,20%,X6S,CA
PVCCD_HV_CPU1            C455             1        Q_CAP_C0805-100UF,4V,20%,X6S,CA
PVCCD_HV_CPU1            C459             1        Q_CAP_C0805-100UF,4V,20%,X6S,CA
PVCCD_HV_CPU1            C463             1        Q_CAP_C0805-100UF,4V,20%,X6S,CA
PVCCD_HV_CPU1            C467             1        Q_CAP_C0805-100UF,4V,20%,X6S,CA
PVCCD_HV_CPU1            C471             1        Q_CAP_C0603-47UF,2.5V,20%,X6S,A
PVCCD_HV_CPU1            C474             1        Q_CAP_C0603-47UF,2.5V,20%,X6S,A
PVCCD_HV_CPU1            PC379            1        Q_CAP_C0402-100NF,50V,10%,X7R,A
PVCCD_HV_CPU1            PC381            1        Q_CAP_0805-22UF,4V,20%,X6S,TMPA
PVCCD_HV_CPU1            PC382            1        Q_CAP_0805-22UF,4V,20%,X6S,TMPA
PVCCD_HV_CPU1            PC384            1        Q_CAPP_THLF-560UF,2.5V,20%,OSCA
PVCCD_HV_CPU1            PC385            1        Q_CAPP_THLF-560UF,2.5V,20%,OSCA
PVCCD_HV_CPU1            PC1940           1        Q_CAPP_SMLF-330UF,2V,35%,SPCAPA
PVCCD_HV_CPU1            PL17             2        Q_INDUCTOR_SMLF-120NH/94A,IND,A
PVCCD_HV_CPU1            PR559            2        Q_RES_0402LF-100,1%,1/16W,CHIPA
PVCCD_HV_CPU1            R135             2        Q_RES_0402LF-100,1%,1/16W,EMPTA
PVCCD_HV_CPU1            R137             2        Q_RES_0402LF-100,1%,1/16W,EMPTA
PVCCD_HV_CPU1            R151             2        Q_RES_0402LF-100,1%,1/16W,EMPTA
PVCCD_HV_CPU1            R153             2        Q_RES_0402LF-100,1%,1/16W,EMPTA
PVCCD_HV_CPU1            R819             1        Q_RES_0402LF-1K,1%,1/16W,EMPTYA
PVCCD_HV_CPU1            R820             1        Q_RES_0402LF-1K,1%,1/16W,EMPTYA
PVCCD_HV_CPU1            R821             1        Q_RES_0402LF-1K,1%,1/16W,EMPTYA
PVCCD_HV_CPU1            R822             1        Q_RES_0402LF-1K,1%,1/16W,EMPTYA
PVCCD_HV_CPU1            U1               AT36     SOCKET4677_AZIFS054P001C01-SOCA
PVCCD_HV_CPU1            U1               AT55     SOCKET4677_AZIFS054P001C01-SOCA
PVCCD_HV_CPU1            U1               AU3      SOCKET4677_AZIFS054P001C01-SOCA
PVCCD_HV_CPU1            U1               AU7      SOCKET4677_AZIFS054P001C01-SOCA
PVCCD_HV_CPU1            U1               AU35     SOCKET4677_AZIFS054P001C01-SOCA
PVCCD_HV_CPU1            U1               AU54     SOCKET4677_AZIFS054P001C01-SOCA
PVCCD_HV_CPU1            U1               AV34     SOCKET4677_AZIFS054P001C01-SOCA
PVCCD_HV_CPU1            U1               AV36     SOCKET4677_AZIFS054P001C01-SOCA
PVCCD_HV_CPU1            U1               AV53     SOCKET4677_AZIFS054P001C01-SOCA
PVCCD_HV_CPU1            U1               AV55     SOCKET4677_AZIFS054P001C01-SOCA
PVCCD_HV_CPU1            U1               BA3      SOCKET4677_AZIFS054P001C01-SOCA
PVCCD_HV_CPU1            U1               BA7      SOCKET4677_AZIFS054P001C01-SOCA
PVCCD_HV_CPU1            U1               BE3      SOCKET4677_AZIFS054P001C01-SOCA
PVCCD_HV_CPU1            U1               BE7      SOCKET4677_AZIFS054P001C01-SOCA
PVCCD_HV_CPU1            U1               BE11     SOCKET4677_AZIFS054P001C01-SOCA
PVCCD_HV_CPU1            U1               BJ3      SOCKET4677_AZIFS054P001C01-SOCA
PVCCD_HV_CPU1            U1               BJ7      SOCKET4677_AZIFS054P001C01-SOCA
PVCCD_HV_CPU1            U1               BJ11     SOCKET4677_AZIFS054P001C01-SOCA
PVCCD_HV_CPU1            U1               BN7      SOCKET4677_AZIFS054P001C01-SOCA
PVCCD_HV_CPU1            U1               CA7      SOCKET4677_AZIFS054P001C01-SOCA
PVCCD_HV_CPU1            U1               CE7      SOCKET4677_AZIFS054P001C01-SOCA
PVCCD_HV_CPU1            U1               CW35     SOCKET4677_AZIFS054P001C01-SOCA
PVCCD_HV_CPU1            U1               CW37     SOCKET4677_AZIFS054P001C01-SOCA
PVCCD_HV_CPU1            U1               CW52     SOCKET4677_AZIFS054P001C01-SOCA
PVCCD_HV_CPU1            U1               CW54     SOCKET4677_AZIFS054P001C01-SOCA
PVCCD_HV_CPU1            U1               CW56     SOCKET4677_AZIFS054P001C01-SOCA
PVCCD_HV_CPU1            U1               CY34     SOCKET4677_AZIFS054P001C01-SOCA
PVCCD_HV_CPU1            U1               CY36     SOCKET4677_AZIFS054P001C01-SOCA
PVCCD_HV_CPU1            U1               CY53     SOCKET4677_AZIFS054P001C01-SOCA
PVCCD_HV_CPU1_ACSP1      PU17             25       RAA2213404GNPHB0-RAA2213404GNPA
PVCCD_HV_CPU1_ACSP1      PU18             23       ISL69260IRAZT-ISL69260IRAZ-T,SA
PVCCD_HV_CPU1_ADDR       PR202            2        Q_RES_0402LF-28K,1%,1/16W,EMPTA
PVCCD_HV_CPU1_ADDR       PR203            2        Q_RES_0402LF-30.1K    ,1%  ,1/A
PVCCD_HV_CPU1_ADDR       PU18             34       ISL69260IRAZT-ISL69260IRAZ-T,SA
PVCCD_HV_CPU1_APWM1      PU17             21       RAA2213404GNPHB0-RAA2213404GNPA
PVCCD_HV_CPU1_APWM1      PU18             8        ISL69260IRAZT-ISL69260IRAZ-T,SA
PVCCD_HV_CPU1_ATSEN      PC393            1        Q_CAP_0402-470PF,50V,10%,X7R,TA
PVCCD_HV_CPU1_ATSEN      PR705            1        Q_RES_0402LF-10K,1%,1/16W,EMPTB
PVCCD_HV_CPU1_ATSEN      PU17             1        RAA2213404GNPHB0-RAA2213404GNPA
PVCCD_HV_CPU1_ATSEN      PU18             35       ISL69260IRAZT-ISL69260IRAZ-T,SA
PVCCD_HV_CPU1_EN_R       PR208            2        Q_RES_0402LF-0,5%,1/16W,CHIP,CA
PVCCD_HV_CPU1_EN_R       PU18             13       ISL69260IRAZT-ISL69260IRAZ-T,SA
PVCCD_HV_CPU1_FAULT      PR217            2        Q_RES_0402LF-1K,1%,1/16W,CHIP,A
PVCCD_HV_CPU1_FAULT      PU18             33       ISL69260IRAZT-ISL69260IRAZ-T,SA
PVCCD_HV_CPU1_ISENSE_N   PC390            1        Q_CAP_0402-0.1UF,25V,10%,X7R,CA
PVCCD_HV_CPU1_ISENSE_N   PC814            1        Q_CAP_C0402-1UF,16V,10%,X6S,CHA
PVCCD_HV_CPU1_ISENSE_N   PR218            1        Q_RES_0402LF-1K,1%,1/16W,EMPTYA
PVCCD_HV_CPU1_ISENSE_N   PR1410           2        Q_RES_0402LF-49.9     ,1%  ,1/A
PVCCD_HV_CPU1_ISENSE_N   PU18             38       ISL69260IRAZT-ISL69260IRAZ-T,SA
PVCCD_HV_CPU1_ISENSE_P   PC386            1        Q_CAP_0402-0.1UF,25V,10%,X7R,CA
PVCCD_HV_CPU1_ISENSE_P   PC814            2        Q_CAP_C0402-1UF,16V,10%,X6S,CHA
PVCCD_HV_CPU1_ISENSE_P   PR214            1        Q_RES_0402LF-1K,1%,1/16W,EMPTYA
PVCCD_HV_CPU1_ISENSE_P   PR1400           2        Q_RES_0402LF-49.9     ,1%  ,1/A
PVCCD_HV_CPU1_ISENSE_P   PU18             37       ISL69260IRAZT-ISL69260IRAZ-T,SA
PVCCD_HV_CPU1_ISYS_R     PR410            1        Q_RES_0402LF-0,5%,1/16W,EMPTY,A
PVCCD_HV_CPU1_ISYS_R     PR1315           1        Q_RES_0402LF-0,5%,1/16W,CHIP,CA
PVCCD_HV_CPU1_ISYS_R     PU18             36       ISL69260IRAZT-ISL69260IRAZ-T,SA
PVCCD_HV_CPU1_LSET1      PR1746           1        Q_RES_0402LF-8.87K,1%,1/16W,EMA
PVCCD_HV_CPU1_LSET1      PU17             5        RAA2213404GNPHB0-RAA2213404GNPA
PVCCD_HV_CPU1_NC1        PR1805           1        Q_RES_0402LF-0,5%,1/16W,CHIP,CA
PVCCD_HV_CPU1_NC1        PU17             3        RAA2213404GNPHB0-RAA2213404GNPA
PVCCD_HV_CPU1_PIN_ALT    PR215            2        Q_RES_0402LF-1K,1%,1/16W,CHIP,A
PVCCD_HV_CPU1_PIN_ALT    PU18             15       ISL69260IRAZT-ISL69260IRAZ-T,SA
PVCCD_HV_CPU1_PVCC       PR200            1        Q_RES_0402LF-2.2,1%,1/16W,CHIPA
PVCCD_HV_CPU1_PVCC       PR706            2        Q_RES_0402LF-0,5%,1/16W,CHIP,CA
PVCCD_HV_CPU1_PVCC       PR707            2        Q_RES_0402LF-0,5%,1/16W,EMPTY,A
PVCCD_HV_CPU1_VCC        PC391            1        Q_CAP_C0402-100NF,50V,10%,EMPTA
PVCCD_HV_CPU1_VCC        PC394            1        Q_CAP_C0402-1UF,16V,10%,X6S,CHA
PVCCD_HV_CPU1_VCC        PR220            1        Q_RES_0402LF-1,1%,1/16W,CHIP,CA
PVCCD_HV_CPU1_VCC        PU18             39       ISL69260IRAZT-ISL69260IRAZ-T,SA
PVCCD_HV_CPU1_VDD1       PC373            1        Q_CAP_C0402-2.2UF,10V,10%,X6S,A
PVCCD_HV_CPU1_VDD1       PR200            2        Q_RES_0402LF-2.2,1%,1/16W,CHIPA
PVCCD_HV_CPU1_VDD1       PR1805           2        Q_RES_0402LF-0,5%,1/16W,CHIP,CA
PVCCD_HV_CPU1_VDD1       PU17             4        RAA2213404GNPHB0-RAA2213404GNPA
PVCCD_HV_CPU1_VDD1       PU17             22       RAA2213404GNPHB0-RAA2213404GNPA
PVCCD_HV_CPU1_VREF       PC392            1        Q_CAP_0402-4.7UF,6.3V,20%,X6S,A
PVCCD_HV_CPU1_VREF       PC1289           1        Q_CAP_C0402-1UF,16V,10%,X6S,CHA
PVCCD_HV_CPU1_VREF       PC1371           2        Q_CAP_0402-0.1UF,25V,10%,X7R,CA
PVCCD_HV_CPU1_VREF       PR202            1        Q_RES_0402LF-28K,1%,1/16W,EMPTA
PVCCD_HV_CPU1_VREF       PU17             24       RAA2213404GNPHB0-RAA2213404GNPA
PVCCD_HV_CPU1_VREF       PU18             40       ISL69260IRAZT-ISL69260IRAZ-T,SA
PVCCFA_EHV_CPU0          C419             1        Q_CAP_C0402-22UF,4V,20%,X6S,CHA
PVCCFA_EHV_CPU0          C420             1        Q_CAP_C0402-22UF,4V,20%,X6S,CHA
PVCCFA_EHV_CPU0          C421             1        Q_CAP_C0402-22UF,4V,20%,X6S,CHA
PVCCFA_EHV_CPU0          C422             1        Q_CAP_C0402-22UF,4V,20%,X6S,CHA
PVCCFA_EHV_CPU0          C492             1        Q_CAP_C0805-100UF,4V,20%,X6S,CA
PVCCFA_EHV_CPU0          C496             1        Q_CAP_C0805-100UF,4V,20%,X6S,CA
PVCCFA_EHV_CPU0          C500             1        Q_CAP_C0805-100UF,4V,20%,X6S,CA
PVCCFA_EHV_CPU0          C504             1        Q_CAP_C0805-100UF,4V,20%,X6S,CA
PVCCFA_EHV_CPU0          C508             1        Q_CAP_C0805-100UF,4V,20%,X6S,CA
PVCCFA_EHV_CPU0          C512             1        Q_CAP_C0805-100UF,4V,20%,X6S,CA
PVCCFA_EHV_CPU0          C516             1        Q_CAP_C0603-47UF,2.5V,20%,X6S,A
PVCCFA_EHV_CPU0          C519             1        Q_CAP_C0603-47UF,2.5V,20%,X6S,A
PVCCFA_EHV_CPU0          PC181            1        Q_CAP_C0402-100NF,50V,10%,X7R,A
PVCCFA_EHV_CPU0          PC184            1        Q_CAP_0805-22UF,4V,20%,X6S,TMPA
PVCCFA_EHV_CPU0          PC186            1        Q_CAP_0805-22UF,4V,20%,X6S,TMPA
PVCCFA_EHV_CPU0          PC1900           1        Q_CAPP_SMLF-470UF,2.5V,20%,SPCA
PVCCFA_EHV_CPU0          PC2180           1        Q_CAPP_THLF-560UF,2.5V,20%,OSCA
PVCCFA_EHV_CPU0          PL3              2        Q_INDUCTOR_SMLF-300NH/33A,IND,A
PVCCFA_EHV_CPU0          PR522            2        Q_RES_0402LF-100,1%,1/16W,CHIPA
PVCCFA_EHV_CPU0          U2               AA3      SOCKET4677_AZIFS054P001C01-SOCA
PVCCFA_EHV_CPU0          U2               AE3      SOCKET4677_AZIFS054P001C01-SOCA
PVCCFA_EHV_CPU0          U2               AJ3      SOCKET4677_AZIFS054P001C01-SOCA
PVCCFA_EHV_CPU0          U2               AN3      SOCKET4677_AZIFS054P001C01-SOCA
PVCCFA_EHV_CPU0          U2               AT61     SOCKET4677_AZIFS054P001C01-SOCA
PVCCFA_EHV_CPU0          U2               AU60     SOCKET4677_AZIFS054P001C01-SOCA
PVCCFA_EHV_CPU0          U2               AV61     SOCKET4677_AZIFS054P001C01-SOCA
PVCCFA_EHV_CPU0          U2               AW60     SOCKET4677_AZIFS054P001C01-SOCA
PVCCFA_EHV_CPU0          U2               N3       SOCKET4677_AZIFS054P001C01-SOCA
PVCCFA_EHV_CPU0          U2               U3       SOCKET4677_AZIFS054P001C01-SOCA
PVCCFA_EHV_CPU0_BCSP1    PU5              30       ISL69260IRAZT-ISL69260IRAZ-T,SA
PVCCFA_EHV_CPU0_BCSP1    PU42             25       RAA2213404GNPHB0-RAA2213404GNPA
PVCCFA_EHV_CPU0_BPWM1    PU5              1        ISL69260IRAZT-ISL69260IRAZ-T,SA
PVCCFA_EHV_CPU0_BPWM1    PU42             21       RAA2213404GNPHB0-RAA2213404GNPA
PVCCFA_EHV_CPU0_BTSEN    PC1271           1        Q_CAP_0402-470PF,50V,10%,X7R,TA
PVCCFA_EHV_CPU0_BTSEN    PR436            1        Q_RES_0402LF-10K,1%,1/16W,EMPTB
PVCCFA_EHV_CPU0_BTSEN    PU5              36       ISL69260IRAZT-ISL69260IRAZ-T,SA
PVCCFA_EHV_CPU0_BTSEN    PU42             1        RAA2213404GNPHB0-RAA2213404GNPA
PVCCFA_EHV_CPU0_EN_R     PC219            1        Q_CAP_0402-1000PF,50V,5%,X7R,TA
PVCCFA_EHV_CPU0_EN_R     PR119            2        Q_RES_0402LF-0,5%,1/16W,CHIP,CA
PVCCFA_EHV_CPU0_EN_R     PU5              20       ISL69260IRAZT-ISL69260IRAZ-T,SA
PVCCFA_EHV_CPU0_LSET1    PR1709           1        Q_RES_0402LF-8.87K,1%,1/16W,EMA
PVCCFA_EHV_CPU0_LSET1    PU42             5        RAA2213404GNPHB0-RAA2213404GNPA
PVCCFA_EHV_CPU0_NC1      PR1779           1        Q_RES_0402LF-0,5%,1/16W,CHIP,CA
PVCCFA_EHV_CPU0_NC1      PU42             3        RAA2213404GNPHB0-RAA2213404GNPA
PVCCFA_EHV_CPU0_PVCC     PR97             1        Q_RES_0402LF-2.2,1%,1/16W,CHIPA
PVCCFA_EHV_CPU0_PVCC     PR442            2        Q_RES_0402LF-0,5%,1/16W,CHIP,CA
PVCCFA_EHV_CPU0_PVCC     PR443            2        Q_RES_0402LF-0,5%,1/16W,EMPTY,A
PVCCFA_EHV_CPU0_VDD1     PC175            1        Q_CAP_C0402-2.2UF,10V,10%,X6S,A
PVCCFA_EHV_CPU0_VDD1     PR97             2        Q_RES_0402LF-2.2,1%,1/16W,CHIPA
PVCCFA_EHV_CPU0_VDD1     PR1779           2        Q_RES_0402LF-0,5%,1/16W,CHIP,CA
PVCCFA_EHV_CPU0_VDD1     PU42             4        RAA2213404GNPHB0-RAA2213404GNPA
PVCCFA_EHV_CPU0_VDD1     PU42             22       RAA2213404GNPHB0-RAA2213404GNPA
PVCCFA_EHV_CPU1          C443             1        Q_CAP_C0402-22UF,4V,20%,X6S,CHA
PVCCFA_EHV_CPU1          C444             1        Q_CAP_C0402-22UF,4V,20%,X6S,CHA
PVCCFA_EHV_CPU1          C445             1        Q_CAP_C0402-22UF,4V,20%,X6S,CHA
PVCCFA_EHV_CPU1          C446             1        Q_CAP_C0402-22UF,4V,20%,X6S,CHA
PVCCFA_EHV_CPU1          C448             1        Q_CAP_C0805-100UF,4V,20%,X6S,CA
PVCCFA_EHV_CPU1          C452             1        Q_CAP_C0805-100UF,4V,20%,X6S,CA
PVCCFA_EHV_CPU1          C456             1        Q_CAP_C0805-100UF,4V,20%,X6S,CA
PVCCFA_EHV_CPU1          C460             1        Q_CAP_C0805-100UF,4V,20%,X6S,CA
PVCCFA_EHV_CPU1          C464             1        Q_CAP_C0805-100UF,4V,20%,X6S,CA
PVCCFA_EHV_CPU1          C468             1        Q_CAP_C0805-100UF,4V,20%,X6S,CA
PVCCFA_EHV_CPU1          C472             1        Q_CAP_C0603-47UF,2.5V,20%,X6S,A
PVCCFA_EHV_CPU1          C475             1        Q_CAP_C0603-47UF,2.5V,20%,X6S,A
PVCCFA_EHV_CPU1          PC434            1        Q_CAP_C0402-100NF,50V,10%,X7R,A
PVCCFA_EHV_CPU1          PC435            1        Q_CAP_0805-22UF,4V,20%,X6S,TMPA
PVCCFA_EHV_CPU1          PC437            1        Q_CAP_0805-22UF,4V,20%,X6S,TMPA
PVCCFA_EHV_CPU1          PC1930           1        Q_CAPP_SMLF-470UF,2.5V,20%,SPCA
PVCCFA_EHV_CPU1          PC2199           1        Q_CAPP_THLF-560UF,2.5V,20%,OSCA
PVCCFA_EHV_CPU1          PL20             2        Q_INDUCTOR_SMLF-300NH/33A,IND,A
PVCCFA_EHV_CPU1          PR569            2        Q_RES_0402LF-100,1%,1/16W,CHIPA
PVCCFA_EHV_CPU1          U1               AA3      SOCKET4677_AZIFS054P001C01-SOCA
PVCCFA_EHV_CPU1          U1               AE3      SOCKET4677_AZIFS054P001C01-SOCA
PVCCFA_EHV_CPU1          U1               AJ3      SOCKET4677_AZIFS054P001C01-SOCA
PVCCFA_EHV_CPU1          U1               AN3      SOCKET4677_AZIFS054P001C01-SOCA
PVCCFA_EHV_CPU1          U1               AT61     SOCKET4677_AZIFS054P001C01-SOCA
PVCCFA_EHV_CPU1          U1               AU60     SOCKET4677_AZIFS054P001C01-SOCA
PVCCFA_EHV_CPU1          U1               AV61     SOCKET4677_AZIFS054P001C01-SOCA
PVCCFA_EHV_CPU1          U1               AW60     SOCKET4677_AZIFS054P001C01-SOCA
PVCCFA_EHV_CPU1          U1               N3       SOCKET4677_AZIFS054P001C01-SOCA
PVCCFA_EHV_CPU1          U1               U3       SOCKET4677_AZIFS054P001C01-SOCA
PVCCFA_EHV_CPU1_BCSP1    PU22             30       ISL69260IRAZT-ISL69260IRAZ-T,SA
PVCCFA_EHV_CPU1_BCSP1    PU49             25       RAA2213404GNPHB0-RAA2213404GNPA
PVCCFA_EHV_CPU1_BPWM1    PU22             1        ISL69260IRAZT-ISL69260IRAZ-T,SA
PVCCFA_EHV_CPU1_BPWM1    PU49             21       RAA2213404GNPHB0-RAA2213404GNPA
PVCCFA_EHV_CPU1_BTSEN    PC1292           1        Q_CAP_0402-470PF,50V,10%,X7R,TA
PVCCFA_EHV_CPU1_BTSEN    PR667            1        Q_RES_0402LF-10K,1%,1/16W,EMPTB
PVCCFA_EHV_CPU1_BTSEN    PU22             36       ISL69260IRAZT-ISL69260IRAZ-T,SA
PVCCFA_EHV_CPU1_BTSEN    PU49             1        RAA2213404GNPHB0-RAA2213404GNPA
PVCCFA_EHV_CPU1_EN_R     PC472            1        Q_CAP_0402-1000PF,50V,5%,X7R,TA
PVCCFA_EHV_CPU1_EN_R     PR272            2        Q_RES_0402LF-0,5%,1/16W,CHIP,CA
PVCCFA_EHV_CPU1_EN_R     PU22             20       ISL69260IRAZT-ISL69260IRAZ-T,SA
PVCCFA_EHV_CPU1_LSET1    PR1728           1        Q_RES_0402LF-8.87K,1%,1/16W,EMA
PVCCFA_EHV_CPU1_LSET1    PU49             5        RAA2213404GNPHB0-RAA2213404GNPA
PVCCFA_EHV_CPU1_NC1      PR1799           1        Q_RES_0402LF-0,5%,1/16W,CHIP,CA
PVCCFA_EHV_CPU1_NC1      PU49             3        RAA2213404GNPHB0-RAA2213404GNPA
PVCCFA_EHV_CPU1_PVCC     PR250            1        Q_RES_0402LF-2.2,1%,1/16W,CHIPA
PVCCFA_EHV_CPU1_PVCC     PR678            2        Q_RES_0402LF-0,5%,1/16W,CHIP,CA
PVCCFA_EHV_CPU1_PVCC     PR699            2        Q_RES_0402LF-0,5%,1/16W,EMPTY,A
PVCCFA_EHV_CPU1_VDD1     PC428            1        Q_CAP_C0402-2.2UF,10V,10%,X6S,A
PVCCFA_EHV_CPU1_VDD1     PR250            2        Q_RES_0402LF-2.2,1%,1/16W,CHIPA
PVCCFA_EHV_CPU1_VDD1     PR1799           2        Q_RES_0402LF-0,5%,1/16W,CHIP,CA
PVCCFA_EHV_CPU1_VDD1     PU49             4        RAA2213404GNPHB0-RAA2213404GNPA
PVCCFA_EHV_CPU1_VDD1     PU49             22       RAA2213404GNPHB0-RAA2213404GNPA
PVCCFA_EHV_FIVRA_CPU0    C400             1        Q_CAP_C0402-22UF,4V,20%,X6S,CHA
PVCCFA_EHV_FIVRA_CPU0    C402             1        Q_CAP_C0402-22UF,4V,20%,X6S,CHA
PVCCFA_EHV_FIVRA_CPU0    C404             1        Q_CAP_C0402-22UF,4V,20%,X6S,CHA
PVCCFA_EHV_FIVRA_CPU0    C406             1        Q_CAP_C0402-22UF,4V,20%,X6S,CHA
PVCCFA_EHV_FIVRA_CPU0    C407             1        Q_CAP_C0402-22UF,4V,20%,X6S,CHA
PVCCFA_EHV_FIVRA_CPU0    C409             1        Q_CAP_C0402-22UF,4V,20%,X6S,CHA
PVCCFA_EHV_FIVRA_CPU0    C411             1        Q_CAP_C0402-22UF,4V,20%,X6S,CHA
PVCCFA_EHV_FIVRA_CPU0    C413             1        Q_CAP_C0402-22UF,4V,20%,X6S,CHA
PVCCFA_EHV_FIVRA_CPU0    C415             1        Q_CAP_C0402-22UF,4V,20%,X6S,CHA
PVCCFA_EHV_FIVRA_CPU0    C417             1        Q_CAP_C0402-22UF,4V,20%,X6S,CHA
PVCCFA_EHV_FIVRA_CPU0    C418             1        Q_CAP_C0402-22UF,4V,20%,X6S,CHA
PVCCFA_EHV_FIVRA_CPU0    C493             1        Q_CAP_C0805-100UF,4V,20%,X6S,CA
PVCCFA_EHV_FIVRA_CPU0    C494             1        Q_CAP_C0805-100UF,4V,20%,X6S,CA
PVCCFA_EHV_FIVRA_CPU0    C497             1        Q_CAP_C0805-100UF,4V,20%,X6S,CA
PVCCFA_EHV_FIVRA_CPU0    C498             1        Q_CAP_C0805-100UF,4V,20%,X6S,CA
PVCCFA_EHV_FIVRA_CPU0    C501             1        Q_CAP_C0805-100UF,4V,20%,X6S,CA
PVCCFA_EHV_FIVRA_CPU0    C502             1        Q_CAP_C0805-100UF,4V,20%,X6S,CA
PVCCFA_EHV_FIVRA_CPU0    C505             1        Q_CAP_C0805-100UF,4V,20%,X6S,CA
PVCCFA_EHV_FIVRA_CPU0    C506             1        Q_CAP_C0805-100UF,4V,20%,X6S,CA
PVCCFA_EHV_FIVRA_CPU0    C509             1        Q_CAP_C0603-47UF,2.5V,20%,X6S,A
PVCCFA_EHV_FIVRA_CPU0    C510             1        Q_CAP_C0805-100UF,4V,20%,X6S,CA
PVCCFA_EHV_FIVRA_CPU0    C514             1        Q_CAP_C0805-100UF,4V,20%,X6S,CA
PVCCFA_EHV_FIVRA_CPU0    C517             1        Q_CAP_C0805-100UF,4V,20%,X6S,CA
PVCCFA_EHV_FIVRA_CPU0    C520             1        Q_CAP_C0805-100UF,4V,20%,X6S,CA
PVCCFA_EHV_FIVRA_CPU0    C521             1        Q_CAP_C0805-100UF,4V,20%,X6S,CA
PVCCFA_EHV_FIVRA_CPU0    C523             1        Q_CAP_C0805-100UF,4V,20%,X6S,CA
PVCCFA_EHV_FIVRA_CPU0    C526             1        Q_CAP_C0805-100UF,4V,20%,X6S,CA
PVCCFA_EHV_FIVRA_CPU0    C529             1        Q_CAP_C0805-100UF,4V,20%,X6S,CA
PVCCFA_EHV_FIVRA_CPU0    PC1183           1        Q_CAPP_THLF-560UF,2.5V,20%,OSCA
PVCCFA_EHV_FIVRA_CPU0    PC1183_P0_3      1        Q_CAP_C0402-1UF,16V,10%,EMPTY,A
PVCCFA_EHV_FIVRA_CPU0    PC1183_P0_4      1        Q_CAP_C0402-100NF,50V,10%,EMPTA
PVCCFA_EHV_FIVRA_CPU0    PC1185           1        Q_CAPP_THLF-560UF,2.5V,20%,OSCA
PVCCFA_EHV_FIVRA_CPU0    PC1185_P0_3      1        Q_CAP_0805-22UF,4V,20%,EMPTY,TA
PVCCFA_EHV_FIVRA_CPU0    PC1186           1        Q_CAPP_THLF-560UF,2.5V,20%,EMPA
PVCCFA_EHV_FIVRA_CPU0    PC1186_P0_4      1        Q_CAP_0805-22UF,4V,20%,EMPTY,TA
PVCCFA_EHV_FIVRA_CPU0    PC1187           1        Q_CAPP_SMLF-470UF,2.5V,20%,EMPA
PVCCFA_EHV_FIVRA_CPU0    PC1187_P0_3      1        Q_CAP_0805-22UF,4V,20%,EMPTY,TA
PVCCFA_EHV_FIVRA_CPU0    PC1188_P0_4      1        Q_CAP_0805-22UF,4V,20%,EMPTY,TA
PVCCFA_EHV_FIVRA_CPU0    PC2170           1        Q_CAPP_SMLF-470UF,2.5V,20%,EMPA
PVCCFA_EHV_FIVRA_CPU0    PC2645           1        Q_CAPP_SMLF-470UF,2.5V,20%,EMPA
PVCCFA_EHV_FIVRA_CPU0    PC612_P0_1       1        Q_CAP_C0402-100NF,50V,10%,X7R,A
PVCCFA_EHV_FIVRA_CPU0    PC613_P0_2       1        Q_CAP_C0402-1UF,16V,10%,X6S,CHA
PVCCFA_EHV_FIVRA_CPU0    PC615_P0_1       1        Q_CAP_0805-22UF,4V,20%,X6S,TMPA
PVCCFA_EHV_FIVRA_CPU0    PC616_P0_2       1        Q_CAP_0805-22UF,4V,20%,X6S,TMPA
PVCCFA_EHV_FIVRA_CPU0    PC617_P0_1       1        Q_CAP_0805-22UF,4V,20%,X6S,TMPA
PVCCFA_EHV_FIVRA_CPU0    PC618_P0_2       1        Q_CAP_0805-22UF,4V,20%,X6S,TMPA
PVCCFA_EHV_FIVRA_CPU0    PC619            1        Q_CAPP_THLF-560UF,2.5V,20%,OSCA
PVCCFA_EHV_FIVRA_CPU0    PC620            1        Q_CAPP_THLF-560UF,2.5V,20%,OSCA
PVCCFA_EHV_FIVRA_CPU0    PC621            1        Q_CAPP_THLF-560UF,2.5V,20%,EMPA
PVCCFA_EHV_FIVRA_CPU0    PC623            1        Q_CAPP_SMLF-470UF,2.5V,20%,EMPA
PVCCFA_EHV_FIVRA_CPU0    PL2              2        Q_INDUCTOR_SMLF-130NH/106A,EMPA
PVCCFA_EHV_FIVRA_CPU0    PL33             2        Q_INDUCTOR_SMLF-130NH/106A,INDA
PVCCFA_EHV_FIVRA_CPU0    PL34             2        Q_INDUCTOR_SMLF-130NH/106A,INDA
PVCCFA_EHV_FIVRA_CPU0    PL210            2        Q_INDUCTOR_SMLF-130NH/106A,EMPA
PVCCFA_EHV_FIVRA_CPU0    PR587            2        Q_RES_0402LF-100,1%,1/16W,CHIPA
PVCCFA_EHV_FIVRA_CPU0    PR1322           2        Q_RES_0402LF-0,5%,1/16W,CHIP,CA
PVCCFA_EHV_FIVRA_CPU0    PR1323           2        Q_RES_0402LF-0,5%,1/16W,CHIP,CA
PVCCFA_EHV_FIVRA_CPU0    PR1324           2        Q_RES_0402LF-0,5%,1/16W,EMPTY,A
PVCCFA_EHV_FIVRA_CPU0    PR1325           2        Q_RES_0402LF-0,5%,1/16W,EMPTY,A
PVCCFA_EHV_FIVRA_CPU0    U2               AA7      SOCKET4677_AZIFS054P001C01-SOCA
PVCCFA_EHV_FIVRA_CPU0    U2               AA11     SOCKET4677_AZIFS054P001C01-SOCA
PVCCFA_EHV_FIVRA_CPU0    U2               AA15     SOCKET4677_AZIFS054P001C01-SOCA
PVCCFA_EHV_FIVRA_CPU0    U2               AD85     SOCKET4677_AZIFS054P001C01-SOCA
PVCCFA_EHV_FIVRA_CPU0    U2               AD89     SOCKET4677_AZIFS054P001C01-SOCA
PVCCFA_EHV_FIVRA_CPU0    U2               AE7      SOCKET4677_AZIFS054P001C01-SOCA
PVCCFA_EHV_FIVRA_CPU0    U2               AE11     SOCKET4677_AZIFS054P001C01-SOCA
PVCCFA_EHV_FIVRA_CPU0    U2               AE15     SOCKET4677_AZIFS054P001C01-SOCA
PVCCFA_EHV_FIVRA_CPU0    U2               AF77     SOCKET4677_AZIFS054P001C01-SOCA
PVCCFA_EHV_FIVRA_CPU0    U2               AG78     SOCKET4677_AZIFS054P001C01-SOCA
PVCCFA_EHV_FIVRA_CPU0    U2               AH85     SOCKET4677_AZIFS054P001C01-SOCA
PVCCFA_EHV_FIVRA_CPU0    U2               AH89     SOCKET4677_AZIFS054P001C01-SOCA
PVCCFA_EHV_FIVRA_CPU0    U2               AJ7      SOCKET4677_AZIFS054P001C01-SOCA
PVCCFA_EHV_FIVRA_CPU0    U2               AJ11     SOCKET4677_AZIFS054P001C01-SOCA
PVCCFA_EHV_FIVRA_CPU0    U2               AJ15     SOCKET4677_AZIFS054P001C01-SOCA
PVCCFA_EHV_FIVRA_CPU0    U2               AM79     SOCKET4677_AZIFS054P001C01-SOCA
PVCCFA_EHV_FIVRA_CPU0    U2               AM85     SOCKET4677_AZIFS054P001C01-SOCA
PVCCFA_EHV_FIVRA_CPU0    U2               AM89     SOCKET4677_AZIFS054P001C01-SOCA
PVCCFA_EHV_FIVRA_CPU0    U2               AN7      SOCKET4677_AZIFS054P001C01-SOCA
PVCCFA_EHV_FIVRA_CPU0    U2               AN11     SOCKET4677_AZIFS054P001C01-SOCA
PVCCFA_EHV_FIVRA_CPU0    U2               AN15     SOCKET4677_AZIFS054P001C01-SOCA
PVCCFA_EHV_FIVRA_CPU0    U2               AN80     SOCKET4677_AZIFS054P001C01-SOCA
PVCCFA_EHV_FIVRA_CPU0    U2               AT73     SOCKET4677_AZIFS054P001C01-SOCA
PVCCFA_EHV_FIVRA_CPU0    U2               AT89     SOCKET4677_AZIFS054P001C01-SOCA
PVCCFA_EHV_FIVRA_CPU0    U2               AU15     SOCKET4677_AZIFS054P001C01-SOCA
PVCCFA_EHV_FIVRA_CPU0    U2               AW76     SOCKET4677_AZIFS054P001C01-SOCA
PVCCFA_EHV_FIVRA_CPU0    U2               AY89     SOCKET4677_AZIFS054P001C01-SOCA
PVCCFA_EHV_FIVRA_CPU0    U2               BE72     SOCKET4677_AZIFS054P001C01-SOCA
PVCCFA_EHV_FIVRA_CPU0    U2               BF77     SOCKET4677_AZIFS054P001C01-SOCA
PVCCFA_EHV_FIVRA_CPU0    U2               BH79     SOCKET4677_AZIFS054P001C01-SOCA
PVCCFA_EHV_FIVRA_CPU0    U2               BJ72     SOCKET4677_AZIFS054P001C01-SOCA
PVCCFA_EHV_FIVRA_CPU0    U2               BJ78     SOCKET4677_AZIFS054P001C01-SOCA
PVCCFA_EHV_FIVRA_CPU0    U2               C84      SOCKET4677_AZIFS054P001C01-SOCA
PVCCFA_EHV_FIVRA_CPU0    U2               C88      SOCKET4677_AZIFS054P001C01-SOCA
PVCCFA_EHV_FIVRA_CPU0    U2               CE74     SOCKET4677_AZIFS054P001C01-SOCA
PVCCFA_EHV_FIVRA_CPU0    U2               CK73     SOCKET4677_AZIFS054P001C01-SOCA
PVCCFA_EHV_FIVRA_CPU0    U2               CK79     SOCKET4677_AZIFS054P001C01-SOCA
PVCCFA_EHV_FIVRA_CPU0    U2               CM73     SOCKET4677_AZIFS054P001C01-SOCA
PVCCFA_EHV_FIVRA_CPU0    U2               CN78     SOCKET4677_AZIFS054P001C01-SOCA
PVCCFA_EHV_FIVRA_CPU0    U2               CP73     SOCKET4677_AZIFS054P001C01-SOCA
PVCCFA_EHV_FIVRA_CPU0    U2               CT77     SOCKET4677_AZIFS054P001C01-SOCA
PVCCFA_EHV_FIVRA_CPU0    U2               CT85     SOCKET4677_AZIFS054P001C01-SOCA
PVCCFA_EHV_FIVRA_CPU0    U2               CY75     SOCKET4677_AZIFS054P001C01-SOCA
PVCCFA_EHV_FIVRA_CPU0    U2               CY79     SOCKET4677_AZIFS054P001C01-SOCA
PVCCFA_EHV_FIVRA_CPU0    U2               CY85     SOCKET4677_AZIFS054P001C01-SOCA
PVCCFA_EHV_FIVRA_CPU0    U2               CY89     SOCKET4677_AZIFS054P001C01-SOCA
PVCCFA_EHV_FIVRA_CPU0    U2               DD77     SOCKET4677_AZIFS054P001C01-SOCA
PVCCFA_EHV_FIVRA_CPU0    U2               DD83     SOCKET4677_AZIFS054P001C01-SOCA
PVCCFA_EHV_FIVRA_CPU0    U2               DD85     SOCKET4677_AZIFS054P001C01-SOCA
PVCCFA_EHV_FIVRA_CPU0    U2               DD89     SOCKET4677_AZIFS054P001C01-SOCA
PVCCFA_EHV_FIVRA_CPU0    U2               DH89     SOCKET4677_AZIFS054P001C01-SOCA
PVCCFA_EHV_FIVRA_CPU0    U2               DM83     SOCKET4677_AZIFS054P001C01-SOCA
PVCCFA_EHV_FIVRA_CPU0    U2               DM85     SOCKET4677_AZIFS054P001C01-SOCA
PVCCFA_EHV_FIVRA_CPU0    U2               DM89     SOCKET4677_AZIFS054P001C01-SOCA
PVCCFA_EHV_FIVRA_CPU0    U2               DN3      SOCKET4677_AZIFS054P001C01-SOCA
PVCCFA_EHV_FIVRA_CPU0    U2               DN7      SOCKET4677_AZIFS054P001C01-SOCA
PVCCFA_EHV_FIVRA_CPU0    U2               DN11     SOCKET4677_AZIFS054P001C01-SOCA
PVCCFA_EHV_FIVRA_CPU0    U2               DN15     SOCKET4677_AZIFS054P001C01-SOCA
PVCCFA_EHV_FIVRA_CPU0    U2               DT79     SOCKET4677_AZIFS054P001C01-SOCA
PVCCFA_EHV_FIVRA_CPU0    U2               DT85     SOCKET4677_AZIFS054P001C01-SOCA
PVCCFA_EHV_FIVRA_CPU0    U2               DT89     SOCKET4677_AZIFS054P001C01-SOCA
PVCCFA_EHV_FIVRA_CPU0    U2               DU3      SOCKET4677_AZIFS054P001C01-SOCA
PVCCFA_EHV_FIVRA_CPU0    U2               DU7      SOCKET4677_AZIFS054P001C01-SOCA
PVCCFA_EHV_FIVRA_CPU0    U2               DU11     SOCKET4677_AZIFS054P001C01-SOCA
PVCCFA_EHV_FIVRA_CPU0    U2               DU15     SOCKET4677_AZIFS054P001C01-SOCA
PVCCFA_EHV_FIVRA_CPU0    U2               DY85     SOCKET4677_AZIFS054P001C01-SOCA
PVCCFA_EHV_FIVRA_CPU0    U2               DY89     SOCKET4677_AZIFS054P001C01-SOCA
PVCCFA_EHV_FIVRA_CPU0    U2               EA3      SOCKET4677_AZIFS054P001C01-SOCA
PVCCFA_EHV_FIVRA_CPU0    U2               EA7      SOCKET4677_AZIFS054P001C01-SOCA
PVCCFA_EHV_FIVRA_CPU0    U2               EA11     SOCKET4677_AZIFS054P001C01-SOCA
PVCCFA_EHV_FIVRA_CPU0    U2               EA15     SOCKET4677_AZIFS054P001C01-SOCA
PVCCFA_EHV_FIVRA_CPU0    U2               EC78     SOCKET4677_AZIFS054P001C01-SOCA
PVCCFA_EHV_FIVRA_CPU0    U2               ED79     SOCKET4677_AZIFS054P001C01-SOCA
PVCCFA_EHV_FIVRA_CPU0    U2               ED85     SOCKET4677_AZIFS054P001C01-SOCA
PVCCFA_EHV_FIVRA_CPU0    U2               ED89     SOCKET4677_AZIFS054P001C01-SOCA
PVCCFA_EHV_FIVRA_CPU0    U2               EE7      SOCKET4677_AZIFS054P001C01-SOCA
PVCCFA_EHV_FIVRA_CPU0    U2               EE11     SOCKET4677_AZIFS054P001C01-SOCA
PVCCFA_EHV_FIVRA_CPU0    U2               EE15     SOCKET4677_AZIFS054P001C01-SOCA
PVCCFA_EHV_FIVRA_CPU0    U2               EE84     SOCKET4677_AZIFS054P001C01-SOCA
PVCCFA_EHV_FIVRA_CPU0    U2               EF79     SOCKET4677_AZIFS054P001C01-SOCA
PVCCFA_EHV_FIVRA_CPU0    U2               EG80     SOCKET4677_AZIFS054P001C01-SOCA
PVCCFA_EHV_FIVRA_CPU0    U2               EJ15     SOCKET4677_AZIFS054P001C01-SOCA
PVCCFA_EHV_FIVRA_CPU0    U2               EJ84     SOCKET4677_AZIFS054P001C01-SOCA
PVCCFA_EHV_FIVRA_CPU0    U2               EN84     SOCKET4677_AZIFS054P001C01-SOCA
PVCCFA_EHV_FIVRA_CPU0    U2               H89      SOCKET4677_AZIFS054P001C01-SOCA
PVCCFA_EHV_FIVRA_CPU0    U2               J7       SOCKET4677_AZIFS054P001C01-SOCA
PVCCFA_EHV_FIVRA_CPU0    U2               J11      SOCKET4677_AZIFS054P001C01-SOCA
PVCCFA_EHV_FIVRA_CPU0    U2               J80      SOCKET4677_AZIFS054P001C01-SOCA
PVCCFA_EHV_FIVRA_CPU0    U2               K87      SOCKET4677_AZIFS054P001C01-SOCA
PVCCFA_EHV_FIVRA_CPU0    U2               L84      SOCKET4677_AZIFS054P001C01-SOCA
PVCCFA_EHV_FIVRA_CPU0    U2               M85      SOCKET4677_AZIFS054P001C01-SOCA
PVCCFA_EHV_FIVRA_CPU0    U2               M89      SOCKET4677_AZIFS054P001C01-SOCA
PVCCFA_EHV_FIVRA_CPU0    U2               N7       SOCKET4677_AZIFS054P001C01-SOCA
PVCCFA_EHV_FIVRA_CPU0    U2               N11      SOCKET4677_AZIFS054P001C01-SOCA
PVCCFA_EHV_FIVRA_CPU0    U2               P79      SOCKET4677_AZIFS054P001C01-SOCA
PVCCFA_EHV_FIVRA_CPU0    U2               R80      SOCKET4677_AZIFS054P001C01-SOCA
PVCCFA_EHV_FIVRA_CPU0    U2               T85      SOCKET4677_AZIFS054P001C01-SOCA
PVCCFA_EHV_FIVRA_CPU0    U2               T89      SOCKET4677_AZIFS054P001C01-SOCA
PVCCFA_EHV_FIVRA_CPU0    U2               U7       SOCKET4677_AZIFS054P001C01-SOCA
PVCCFA_EHV_FIVRA_CPU0    U2               U11      SOCKET4677_AZIFS054P001C01-SOCA
PVCCFA_EHV_FIVRA_CPU0    U2               U15      SOCKET4677_AZIFS054P001C01-SOCA
PVCCFA_EHV_FIVRA_CPU0    U2               W80      SOCKET4677_AZIFS054P001C01-SOCA
PVCCFA_EHV_FIVRA_CPU0    U2               Y79      SOCKET4677_AZIFS054P001C01-SOCA
PVCCFA_EHV_FIVRA_CPU0    U2               Y85      SOCKET4677_AZIFS054P001C01-SOCA
PVCCFA_EHV_FIVRA_CPU0    U2               Y89      SOCKET4677_AZIFS054P001C01-SOCA
PVCCFA_EHV_FIVRA_CPU0_EN_R PC592            1        Q_CAP_0402-1000PF,50V,5%,X7R,TA
PVCCFA_EHV_FIVRA_CPU0_EN_R PR337            2        Q_RES_0402LF-0,5%,1/16W,CHIP,CA
PVCCFA_EHV_FIVRA_CPU0_EN_R PU14             24       RAA229126GNPHA0-RAA229126GNP#HA
PVCCFA_EHV_FIVRA_CPU0_IMON1 PU14             38       RAA229126GNPHA0-RAA229126GNP#HA
PVCCFA_EHV_FIVRA_CPU0_IMON1 PU69_P0_1        38       ISL99390FRZTR5935-ISL99390FRZ-A
PVCCFA_EHV_FIVRA_CPU0_IMON2 PU14             37       RAA229126GNPHA0-RAA229126GNP#HA
PVCCFA_EHV_FIVRA_CPU0_IMON2 PU70_P0_2        38       ISL99390FRZTR5935-ISL99390FRZ-A
PVCCFA_EHV_FIVRA_CPU0_LSET1 PR354            1        Q_RES_0402LF-8.87K,1%,1/16W,EMA
PVCCFA_EHV_FIVRA_CPU0_LSET1 PU69_P0_1        37       ISL99390FRZTR5935-ISL99390FRZ-A
PVCCFA_EHV_FIVRA_CPU0_LSET2 PR353            1        Q_RES_0402LF-8.87K,1%,1/16W,EMA
PVCCFA_EHV_FIVRA_CPU0_LSET2 PU70_P0_2        37       ISL99390FRZTR5935-ISL99390FRZ-A
PVCCFA_EHV_FIVRA_CPU0_LSET3 PR1298           1        Q_RES_0402LF-8.87K,1%,1/16W,EMA
PVCCFA_EHV_FIVRA_CPU0_LSET3 PU71_P0_3        37       ISL99390FRZTR5935-ISL99390FRZ-B
PVCCFA_EHV_FIVRA_CPU0_LSET4 PR1297           1        Q_RES_0402LF-8.87K,1%,1/16W,EMA
PVCCFA_EHV_FIVRA_CPU0_LSET4 PU72_P0_4        37       ISL99390FRZTR5935-ISL99390FRZ-B
PVCCFA_EHV_FIVRA_CPU0_PVCC1 PC1211_P0_1      1        Q_CAP_C0402-2.2UF,10V,10%,X6S,A
PVCCFA_EHV_FIVRA_CPU0_PVCC1 PC1213_P0_3      1        Q_CAP_C0402-2.2UF,10V,10%,EMPTA
PVCCFA_EHV_FIVRA_CPU0_PVCC1 PR355            1        Q_RES_0402LF-2.2,1%,1/16W,CHIPA
PVCCFA_EHV_FIVRA_CPU0_PVCC1 PR444            2        Q_RES_0402LF-0,5%,1/16W,CHIP,CA
PVCCFA_EHV_FIVRA_CPU0_PVCC1 PR632            2        Q_RES_0402LF-0,5%,1/16W,EMPTY,A
PVCCFA_EHV_FIVRA_CPU0_PVCC1 PR1299           1        Q_RES_0402LF-2.2,1%,1/16W,EMPTA
PVCCFA_EHV_FIVRA_CPU0_PVCC1 PU69_P0_1        4        ISL99390FRZTR5935-ISL99390FRZ-A
PVCCFA_EHV_FIVRA_CPU0_PVCC1 PU71_P0_3        4        ISL99390FRZTR5935-ISL99390FRZ-B
PVCCFA_EHV_FIVRA_CPU0_PVCC2 PC1212_P0_2      1        Q_CAP_C0402-2.2UF,10V,10%,X6S,A
PVCCFA_EHV_FIVRA_CPU0_PVCC2 PC1214_P0_4      1        Q_CAP_C0402-2.2UF,10V,10%,EMPTA
PVCCFA_EHV_FIVRA_CPU0_PVCC2 PR356            1        Q_RES_0402LF-2.2,1%,1/16W,CHIPA
PVCCFA_EHV_FIVRA_CPU0_PVCC2 PR447            2        Q_RES_0402LF-0,5%,1/16W,CHIP,CA
PVCCFA_EHV_FIVRA_CPU0_PVCC2 PR633            2        Q_RES_0402LF-0,5%,1/16W,EMPTY,A
PVCCFA_EHV_FIVRA_CPU0_PVCC2 PR1300           1        Q_RES_0402LF-2.2,1%,1/16W,EMPTA
PVCCFA_EHV_FIVRA_CPU0_PVCC2 PU70_P0_2        4        ISL99390FRZTR5935-ISL99390FRZ-A
PVCCFA_EHV_FIVRA_CPU0_PVCC2 PU72_P0_4        4        ISL99390FRZTR5935-ISL99390FRZ-B
PVCCFA_EHV_FIVRA_CPU0_PWM1 PU14             1        RAA229126GNPHA0-RAA229126GNP#HA
PVCCFA_EHV_FIVRA_CPU0_PWM1 PU69_P0_1        34       ISL99390FRZTR5935-ISL99390FRZ-A
PVCCFA_EHV_FIVRA_CPU0_PWM2 PU14             2        RAA229126GNPHA0-RAA229126GNP#HA
PVCCFA_EHV_FIVRA_CPU0_PWM2 PU70_P0_2        34       ISL99390FRZTR5935-ISL99390FRZ-A
PVCCFA_EHV_FIVRA_CPU0_VDD1 PC600            1        Q_CAP_C0402-2.2UF,10V,10%,X6S,A
PVCCFA_EHV_FIVRA_CPU0_VDD1 PR355            2        Q_RES_0402LF-2.2,1%,1/16W,CHIPA
PVCCFA_EHV_FIVRA_CPU0_VDD1 PU69_P0_1        3        ISL99390FRZTR5935-ISL99390FRZ-A
PVCCFA_EHV_FIVRA_CPU0_VDD1 PU69_P0_1        35       ISL99390FRZTR5935-ISL99390FRZ-A
PVCCFA_EHV_FIVRA_CPU0_VDD2 PC601            1        Q_CAP_C0402-2.2UF,10V,10%,X6S,A
PVCCFA_EHV_FIVRA_CPU0_VDD2 PR356            2        Q_RES_0402LF-2.2,1%,1/16W,CHIPA
PVCCFA_EHV_FIVRA_CPU0_VDD2 PU70_P0_2        3        ISL99390FRZTR5935-ISL99390FRZ-A
PVCCFA_EHV_FIVRA_CPU0_VDD2 PU70_P0_2        35       ISL99390FRZTR5935-ISL99390FRZ-A
PVCCFA_EHV_FIVRA_CPU0_VDD3 PC1171           1        Q_CAP_C0402-2.2UF,10V,10%,EMPTA
PVCCFA_EHV_FIVRA_CPU0_VDD3 PR1299           2        Q_RES_0402LF-2.2,1%,1/16W,EMPTA
PVCCFA_EHV_FIVRA_CPU0_VDD3 PU71_P0_3        3        ISL99390FRZTR5935-ISL99390FRZ-B
PVCCFA_EHV_FIVRA_CPU0_VDD3 PU71_P0_3        35       ISL99390FRZTR5935-ISL99390FRZ-B
PVCCFA_EHV_FIVRA_CPU0_VDD4 PC1172           1        Q_CAP_C0402-2.2UF,10V,10%,EMPTA
PVCCFA_EHV_FIVRA_CPU0_VDD4 PR1300           2        Q_RES_0402LF-2.2,1%,1/16W,EMPTA
PVCCFA_EHV_FIVRA_CPU0_VDD4 PU72_P0_4        3        ISL99390FRZTR5935-ISL99390FRZ-B
PVCCFA_EHV_FIVRA_CPU0_VDD4 PU72_P0_4        35       ISL99390FRZTR5935-ISL99390FRZ-B
PVCCFA_EHV_FIVRA_CPU0_VOS1 PR1322           1        Q_RES_0402LF-0,5%,1/16W,CHIP,CA
PVCCFA_EHV_FIVRA_CPU0_VOS1 PU69_P0_1        1        ISL99390FRZTR5935-ISL99390FRZ-A
PVCCFA_EHV_FIVRA_CPU0_VOS2 PR1323           1        Q_RES_0402LF-0,5%,1/16W,CHIP,CA
PVCCFA_EHV_FIVRA_CPU0_VOS2 PU70_P0_2        1        ISL99390FRZTR5935-ISL99390FRZ-A
PVCCFA_EHV_FIVRA_CPU0_VOS3 PR1324           1        Q_RES_0402LF-0,5%,1/16W,EMPTY,A
PVCCFA_EHV_FIVRA_CPU0_VOS3 PU71_P0_3        1        ISL99390FRZTR5935-ISL99390FRZ-B
PVCCFA_EHV_FIVRA_CPU0_VOS4 PR1325           1        Q_RES_0402LF-0,5%,1/16W,EMPTY,A
PVCCFA_EHV_FIVRA_CPU0_VOS4 PU72_P0_4        1        ISL99390FRZTR5935-ISL99390FRZ-B
PVCCFA_EHV_FIVRA_CPU1    C424             1        Q_CAP_C0402-22UF,4V,20%,X6S,CHA
PVCCFA_EHV_FIVRA_CPU1    C426             1        Q_CAP_C0402-22UF,4V,20%,X6S,CHA
PVCCFA_EHV_FIVRA_CPU1    C428             1        Q_CAP_C0402-22UF,4V,20%,X6S,CHA
PVCCFA_EHV_FIVRA_CPU1    C430             1        Q_CAP_C0402-22UF,4V,20%,X6S,CHA
PVCCFA_EHV_FIVRA_CPU1    C431             1        Q_CAP_C0402-22UF,4V,20%,X6S,CHA
PVCCFA_EHV_FIVRA_CPU1    C433             1        Q_CAP_C0402-22UF,4V,20%,X6S,CHA
PVCCFA_EHV_FIVRA_CPU1    C435             1        Q_CAP_C0402-22UF,4V,20%,X6S,CHA
PVCCFA_EHV_FIVRA_CPU1    C437             1        Q_CAP_C0402-22UF,4V,20%,X6S,CHA
PVCCFA_EHV_FIVRA_CPU1    C439             1        Q_CAP_C0402-22UF,4V,20%,X6S,CHA
PVCCFA_EHV_FIVRA_CPU1    C441             1        Q_CAP_C0402-22UF,4V,20%,X6S,CHA
PVCCFA_EHV_FIVRA_CPU1    C442             1        Q_CAP_C0402-22UF,4V,20%,X6S,CHA
PVCCFA_EHV_FIVRA_CPU1    C449             1        Q_CAP_C0805-100UF,4V,20%,X6S,CA
PVCCFA_EHV_FIVRA_CPU1    C450             1        Q_CAP_C0805-100UF,4V,20%,X6S,CA
PVCCFA_EHV_FIVRA_CPU1    C453             1        Q_CAP_C0805-100UF,4V,20%,X6S,CA
PVCCFA_EHV_FIVRA_CPU1    C454             1        Q_CAP_C0805-100UF,4V,20%,X6S,CA
PVCCFA_EHV_FIVRA_CPU1    C457             1        Q_CAP_C0805-100UF,4V,20%,X6S,CA
PVCCFA_EHV_FIVRA_CPU1    C458             1        Q_CAP_C0805-100UF,4V,20%,X6S,CA
PVCCFA_EHV_FIVRA_CPU1    C461             1        Q_CAP_C0805-100UF,4V,20%,X6S,CA
PVCCFA_EHV_FIVRA_CPU1    C462             1        Q_CAP_C0805-100UF,4V,20%,X6S,CA
PVCCFA_EHV_FIVRA_CPU1    C465             1        Q_CAP_C0603-47UF,2.5V,20%,X6S,A
PVCCFA_EHV_FIVRA_CPU1    C466             1        Q_CAP_C0805-100UF,4V,20%,X6S,CA
PVCCFA_EHV_FIVRA_CPU1    C470             1        Q_CAP_C0805-100UF,4V,20%,X6S,CA
PVCCFA_EHV_FIVRA_CPU1    C473             1        Q_CAP_C0805-100UF,4V,20%,X6S,CA
PVCCFA_EHV_FIVRA_CPU1    C476             1        Q_CAP_C0805-100UF,4V,20%,X6S,CA
PVCCFA_EHV_FIVRA_CPU1    C477             1        Q_CAP_C0805-100UF,4V,20%,X6S,CA
PVCCFA_EHV_FIVRA_CPU1    C479             1        Q_CAP_C0805-100UF,4V,20%,X6S,CA
PVCCFA_EHV_FIVRA_CPU1    C482             1        Q_CAP_C0805-100UF,4V,20%,X6S,CA
PVCCFA_EHV_FIVRA_CPU1    C485             1        Q_CAP_C0805-100UF,4V,20%,X6S,CA
PVCCFA_EHV_FIVRA_CPU1    PC1201           1        Q_CAPP_THLF-560UF,2.5V,20%,OSCA
PVCCFA_EHV_FIVRA_CPU1    PC1203           1        Q_CAPP_THLF-560UF,2.5V,20%,OSCA
PVCCFA_EHV_FIVRA_CPU1    PC1203_P1_4      1        Q_CAP_C0402-100NF,50V,10%,X7R,A
PVCCFA_EHV_FIVRA_CPU1    PC1204_P1_3      1        Q_CAP_C0402-1UF,16V,10%,X6S,CHA
PVCCFA_EHV_FIVRA_CPU1    PC1206_P1_3      1        Q_CAP_0805-22UF,4V,20%,X6S,TMPA
PVCCFA_EHV_FIVRA_CPU1    PC1207_P1_4      1        Q_CAP_0805-22UF,4V,20%,X6S,TMPA
PVCCFA_EHV_FIVRA_CPU1    PC1208_P1_3      1        Q_CAP_0805-22UF,4V,20%,X6S,TMPA
PVCCFA_EHV_FIVRA_CPU1    PC1209_P1_4      1        Q_CAP_0805-22UF,4V,20%,X6S,TMPA
PVCCFA_EHV_FIVRA_CPU1    PC408_P1_2       1        Q_CAP_C0402-1UF,16V,10%,X6S,CHA
PVCCFA_EHV_FIVRA_CPU1    PC410_P1_1       1        Q_CAP_0805-22UF,4V,20%,X6S,TMPA
PVCCFA_EHV_FIVRA_CPU1    PC411_P1_2       1        Q_CAP_0805-22UF,4V,20%,X6S,TMPA
PVCCFA_EHV_FIVRA_CPU1    PC412_P1_1       1        Q_CAP_0805-22UF,4V,20%,X6S,TMPA
PVCCFA_EHV_FIVRA_CPU1    PC413_P1_2       1        Q_CAP_0805-22UF,4V,20%,X6S,TMPA
PVCCFA_EHV_FIVRA_CPU1    PC414            1        Q_CAPP_THLF-560UF,2.5V,20%,OSCA
PVCCFA_EHV_FIVRA_CPU1    PC415            1        Q_CAPP_THLF-560UF,2.5V,20%,OSCA
PVCCFA_EHV_FIVRA_CPU1    PC416            1        Q_CAPP_THLF-560UF,2.5V,20%,OSCA
PVCCFA_EHV_FIVRA_CPU1    PC418            1        Q_CAPP_SMLF-470UF,2.5V,20%,SPCA
PVCCFA_EHV_FIVRA_CPU1    PC1204           1        Q_CAPP_THLF-560UF,2.5V,20%,OSCA
PVCCFA_EHV_FIVRA_CPU1    PC1205           1        Q_CAPP_SMLF-470UF,2.5V,20%,EMPA
PVCCFA_EHV_FIVRA_CPU1    PC2171           1        Q_CAPP_SMLF-470UF,2.5V,20%,EMPA
PVCCFA_EHV_FIVRA_CPU1    PC2172           1        Q_CAPP_SMLF-470UF,2.5V,20%,SPCA
PVCCFA_EHV_FIVRA_CPU1    PC621_P1_1       1        Q_CAP_C0402-100NF,50V,10%,X7R,A
PVCCFA_EHV_FIVRA_CPU1    PL12             2        Q_INDUCTOR_SMLF-130NH/106A,INDA
PVCCFA_EHV_FIVRA_CPU1    PL18             2        Q_INDUCTOR_SMLF-130NH/106A,INDA
PVCCFA_EHV_FIVRA_CPU1    PL19             2        Q_INDUCTOR_SMLF-130NH/106A,INDA
PVCCFA_EHV_FIVRA_CPU1    PL113            2        Q_INDUCTOR_SMLF-130NH/106A,INDA
PVCCFA_EHV_FIVRA_CPU1    PR561            2        Q_RES_0402LF-100,1%,1/16W,CHIPA
PVCCFA_EHV_FIVRA_CPU1    PR1331           2        Q_RES_0402LF-0,5%,1/16W,CHIP,CA
PVCCFA_EHV_FIVRA_CPU1    PR1332           2        Q_RES_0402LF-0,5%,1/16W,CHIP,CA
PVCCFA_EHV_FIVRA_CPU1    PR1333           2        Q_RES_0402LF-0,5%,1/16W,CHIP,CA
PVCCFA_EHV_FIVRA_CPU1    PR1334           2        Q_RES_0402LF-0,5%,1/16W,CHIP,CA
PVCCFA_EHV_FIVRA_CPU1    U1               AA7      SOCKET4677_AZIFS054P001C01-SOCA
PVCCFA_EHV_FIVRA_CPU1    U1               AA11     SOCKET4677_AZIFS054P001C01-SOCA
PVCCFA_EHV_FIVRA_CPU1    U1               AA15     SOCKET4677_AZIFS054P001C01-SOCA
PVCCFA_EHV_FIVRA_CPU1    U1               AD85     SOCKET4677_AZIFS054P001C01-SOCA
PVCCFA_EHV_FIVRA_CPU1    U1               AD89     SOCKET4677_AZIFS054P001C01-SOCA
PVCCFA_EHV_FIVRA_CPU1    U1               AE7      SOCKET4677_AZIFS054P001C01-SOCA
PVCCFA_EHV_FIVRA_CPU1    U1               AE11     SOCKET4677_AZIFS054P001C01-SOCA
PVCCFA_EHV_FIVRA_CPU1    U1               AE15     SOCKET4677_AZIFS054P001C01-SOCA
PVCCFA_EHV_FIVRA_CPU1    U1               AF77     SOCKET4677_AZIFS054P001C01-SOCA
PVCCFA_EHV_FIVRA_CPU1    U1               AG78     SOCKET4677_AZIFS054P001C01-SOCA
PVCCFA_EHV_FIVRA_CPU1    U1               AH85     SOCKET4677_AZIFS054P001C01-SOCA
PVCCFA_EHV_FIVRA_CPU1    U1               AH89     SOCKET4677_AZIFS054P001C01-SOCA
PVCCFA_EHV_FIVRA_CPU1    U1               AJ7      SOCKET4677_AZIFS054P001C01-SOCA
PVCCFA_EHV_FIVRA_CPU1    U1               AJ11     SOCKET4677_AZIFS054P001C01-SOCA
PVCCFA_EHV_FIVRA_CPU1    U1               AJ15     SOCKET4677_AZIFS054P001C01-SOCA
PVCCFA_EHV_FIVRA_CPU1    U1               AM79     SOCKET4677_AZIFS054P001C01-SOCA
PVCCFA_EHV_FIVRA_CPU1    U1               AM85     SOCKET4677_AZIFS054P001C01-SOCA
PVCCFA_EHV_FIVRA_CPU1    U1               AM89     SOCKET4677_AZIFS054P001C01-SOCA
PVCCFA_EHV_FIVRA_CPU1    U1               AN7      SOCKET4677_AZIFS054P001C01-SOCA
PVCCFA_EHV_FIVRA_CPU1    U1               AN11     SOCKET4677_AZIFS054P001C01-SOCA
PVCCFA_EHV_FIVRA_CPU1    U1               AN15     SOCKET4677_AZIFS054P001C01-SOCA
PVCCFA_EHV_FIVRA_CPU1    U1               AN80     SOCKET4677_AZIFS054P001C01-SOCA
PVCCFA_EHV_FIVRA_CPU1    U1               AT73     SOCKET4677_AZIFS054P001C01-SOCA
PVCCFA_EHV_FIVRA_CPU1    U1               AT89     SOCKET4677_AZIFS054P001C01-SOCA
PVCCFA_EHV_FIVRA_CPU1    U1               AU15     SOCKET4677_AZIFS054P001C01-SOCA
PVCCFA_EHV_FIVRA_CPU1    U1               AW76     SOCKET4677_AZIFS054P001C01-SOCA
PVCCFA_EHV_FIVRA_CPU1    U1               AY89     SOCKET4677_AZIFS054P001C01-SOCA
PVCCFA_EHV_FIVRA_CPU1    U1               BE72     SOCKET4677_AZIFS054P001C01-SOCA
PVCCFA_EHV_FIVRA_CPU1    U1               BF77     SOCKET4677_AZIFS054P001C01-SOCA
PVCCFA_EHV_FIVRA_CPU1    U1               BH79     SOCKET4677_AZIFS054P001C01-SOCA
PVCCFA_EHV_FIVRA_CPU1    U1               BJ72     SOCKET4677_AZIFS054P001C01-SOCA
PVCCFA_EHV_FIVRA_CPU1    U1               BJ78     SOCKET4677_AZIFS054P001C01-SOCA
PVCCFA_EHV_FIVRA_CPU1    U1               C84      SOCKET4677_AZIFS054P001C01-SOCA
PVCCFA_EHV_FIVRA_CPU1    U1               C88      SOCKET4677_AZIFS054P001C01-SOCA
PVCCFA_EHV_FIVRA_CPU1    U1               CE74     SOCKET4677_AZIFS054P001C01-SOCA
PVCCFA_EHV_FIVRA_CPU1    U1               CK73     SOCKET4677_AZIFS054P001C01-SOCA
PVCCFA_EHV_FIVRA_CPU1    U1               CK79     SOCKET4677_AZIFS054P001C01-SOCA
PVCCFA_EHV_FIVRA_CPU1    U1               CM73     SOCKET4677_AZIFS054P001C01-SOCA
PVCCFA_EHV_FIVRA_CPU1    U1               CN78     SOCKET4677_AZIFS054P001C01-SOCA
PVCCFA_EHV_FIVRA_CPU1    U1               CP73     SOCKET4677_AZIFS054P001C01-SOCA
PVCCFA_EHV_FIVRA_CPU1    U1               CT77     SOCKET4677_AZIFS054P001C01-SOCA
PVCCFA_EHV_FIVRA_CPU1    U1               CT85     SOCKET4677_AZIFS054P001C01-SOCA
PVCCFA_EHV_FIVRA_CPU1    U1               CY75     SOCKET4677_AZIFS054P001C01-SOCA
PVCCFA_EHV_FIVRA_CPU1    U1               CY79     SOCKET4677_AZIFS054P001C01-SOCA
PVCCFA_EHV_FIVRA_CPU1    U1               CY85     SOCKET4677_AZIFS054P001C01-SOCA
PVCCFA_EHV_FIVRA_CPU1    U1               CY89     SOCKET4677_AZIFS054P001C01-SOCA
PVCCFA_EHV_FIVRA_CPU1    U1               DD77     SOCKET4677_AZIFS054P001C01-SOCA
PVCCFA_EHV_FIVRA_CPU1    U1               DD83     SOCKET4677_AZIFS054P001C01-SOCA
PVCCFA_EHV_FIVRA_CPU1    U1               DD85     SOCKET4677_AZIFS054P001C01-SOCA
PVCCFA_EHV_FIVRA_CPU1    U1               DD89     SOCKET4677_AZIFS054P001C01-SOCA
PVCCFA_EHV_FIVRA_CPU1    U1               DH89     SOCKET4677_AZIFS054P001C01-SOCA
PVCCFA_EHV_FIVRA_CPU1    U1               DM83     SOCKET4677_AZIFS054P001C01-SOCA
PVCCFA_EHV_FIVRA_CPU1    U1               DM85     SOCKET4677_AZIFS054P001C01-SOCA
PVCCFA_EHV_FIVRA_CPU1    U1               DM89     SOCKET4677_AZIFS054P001C01-SOCA
PVCCFA_EHV_FIVRA_CPU1    U1               DN3      SOCKET4677_AZIFS054P001C01-SOCA
PVCCFA_EHV_FIVRA_CPU1    U1               DN7      SOCKET4677_AZIFS054P001C01-SOCA
PVCCFA_EHV_FIVRA_CPU1    U1               DN11     SOCKET4677_AZIFS054P001C01-SOCA
PVCCFA_EHV_FIVRA_CPU1    U1               DN15     SOCKET4677_AZIFS054P001C01-SOCA
PVCCFA_EHV_FIVRA_CPU1    U1               DT79     SOCKET4677_AZIFS054P001C01-SOCA
PVCCFA_EHV_FIVRA_CPU1    U1               DT85     SOCKET4677_AZIFS054P001C01-SOCA
PVCCFA_EHV_FIVRA_CPU1    U1               DT89     SOCKET4677_AZIFS054P001C01-SOCA
PVCCFA_EHV_FIVRA_CPU1    U1               DU3      SOCKET4677_AZIFS054P001C01-SOCA
PVCCFA_EHV_FIVRA_CPU1    U1               DU7      SOCKET4677_AZIFS054P001C01-SOCA
PVCCFA_EHV_FIVRA_CPU1    U1               DU11     SOCKET4677_AZIFS054P001C01-SOCA
PVCCFA_EHV_FIVRA_CPU1    U1               DU15     SOCKET4677_AZIFS054P001C01-SOCA
PVCCFA_EHV_FIVRA_CPU1    U1               DY85     SOCKET4677_AZIFS054P001C01-SOCA
PVCCFA_EHV_FIVRA_CPU1    U1               DY89     SOCKET4677_AZIFS054P001C01-SOCA
PVCCFA_EHV_FIVRA_CPU1    U1               EA3      SOCKET4677_AZIFS054P001C01-SOCA
PVCCFA_EHV_FIVRA_CPU1    U1               EA7      SOCKET4677_AZIFS054P001C01-SOCA
PVCCFA_EHV_FIVRA_CPU1    U1               EA11     SOCKET4677_AZIFS054P001C01-SOCA
PVCCFA_EHV_FIVRA_CPU1    U1               EA15     SOCKET4677_AZIFS054P001C01-SOCA
PVCCFA_EHV_FIVRA_CPU1    U1               EC78     SOCKET4677_AZIFS054P001C01-SOCA
PVCCFA_EHV_FIVRA_CPU1    U1               ED79     SOCKET4677_AZIFS054P001C01-SOCA
PVCCFA_EHV_FIVRA_CPU1    U1               ED85     SOCKET4677_AZIFS054P001C01-SOCA
PVCCFA_EHV_FIVRA_CPU1    U1               ED89     SOCKET4677_AZIFS054P001C01-SOCA
PVCCFA_EHV_FIVRA_CPU1    U1               EE7      SOCKET4677_AZIFS054P001C01-SOCA
PVCCFA_EHV_FIVRA_CPU1    U1               EE11     SOCKET4677_AZIFS054P001C01-SOCA
PVCCFA_EHV_FIVRA_CPU1    U1               EE15     SOCKET4677_AZIFS054P001C01-SOCA
PVCCFA_EHV_FIVRA_CPU1    U1               EE84     SOCKET4677_AZIFS054P001C01-SOCA
PVCCFA_EHV_FIVRA_CPU1    U1               EF79     SOCKET4677_AZIFS054P001C01-SOCA
PVCCFA_EHV_FIVRA_CPU1    U1               EG80     SOCKET4677_AZIFS054P001C01-SOCA
PVCCFA_EHV_FIVRA_CPU1    U1               EJ15     SOCKET4677_AZIFS054P001C01-SOCA
PVCCFA_EHV_FIVRA_CPU1    U1               EJ84     SOCKET4677_AZIFS054P001C01-SOCA
PVCCFA_EHV_FIVRA_CPU1    U1               EN84     SOCKET4677_AZIFS054P001C01-SOCA
PVCCFA_EHV_FIVRA_CPU1    U1               H89      SOCKET4677_AZIFS054P001C01-SOCA
PVCCFA_EHV_FIVRA_CPU1    U1               J7       SOCKET4677_AZIFS054P001C01-SOCA
PVCCFA_EHV_FIVRA_CPU1    U1               J11      SOCKET4677_AZIFS054P001C01-SOCA
PVCCFA_EHV_FIVRA_CPU1    U1               J80      SOCKET4677_AZIFS054P001C01-SOCA
PVCCFA_EHV_FIVRA_CPU1    U1               K87      SOCKET4677_AZIFS054P001C01-SOCA
PVCCFA_EHV_FIVRA_CPU1    U1               L84      SOCKET4677_AZIFS054P001C01-SOCA
PVCCFA_EHV_FIVRA_CPU1    U1               M85      SOCKET4677_AZIFS054P001C01-SOCA
PVCCFA_EHV_FIVRA_CPU1    U1               M89      SOCKET4677_AZIFS054P001C01-SOCA
PVCCFA_EHV_FIVRA_CPU1    U1               N7       SOCKET4677_AZIFS054P001C01-SOCA
PVCCFA_EHV_FIVRA_CPU1    U1               N11      SOCKET4677_AZIFS054P001C01-SOCA
PVCCFA_EHV_FIVRA_CPU1    U1               P79      SOCKET4677_AZIFS054P001C01-SOCA
PVCCFA_EHV_FIVRA_CPU1    U1               R80      SOCKET4677_AZIFS054P001C01-SOCA
PVCCFA_EHV_FIVRA_CPU1    U1               T85      SOCKET4677_AZIFS054P001C01-SOCA
PVCCFA_EHV_FIVRA_CPU1    U1               T89      SOCKET4677_AZIFS054P001C01-SOCA
PVCCFA_EHV_FIVRA_CPU1    U1               U7       SOCKET4677_AZIFS054P001C01-SOCA
PVCCFA_EHV_FIVRA_CPU1    U1               U11      SOCKET4677_AZIFS054P001C01-SOCA
PVCCFA_EHV_FIVRA_CPU1    U1               U15      SOCKET4677_AZIFS054P001C01-SOCA
PVCCFA_EHV_FIVRA_CPU1    U1               W80      SOCKET4677_AZIFS054P001C01-SOCA
PVCCFA_EHV_FIVRA_CPU1    U1               Y79      SOCKET4677_AZIFS054P001C01-SOCA
PVCCFA_EHV_FIVRA_CPU1    U1               Y85      SOCKET4677_AZIFS054P001C01-SOCA
PVCCFA_EHV_FIVRA_CPU1    U1               Y89      SOCKET4677_AZIFS054P001C01-SOCA
PVCCFA_EHV_FIVRA_CPU1_EN_R PC420            1        Q_CAP_0402-1000PF,50V,5%,X7R,TA
PVCCFA_EHV_FIVRA_CPU1_EN_R PR234            2        Q_RES_0402LF-0,5%,1/16W,CHIP,CA
PVCCFA_EHV_FIVRA_CPU1_EN_R PU29             24       RAA229126GNPHA0-RAA229126GNP#HA
PVCCFA_EHV_FIVRA_CPU1_IMON1 PU29             38       RAA229126GNPHA0-RAA229126GNP#HA
PVCCFA_EHV_FIVRA_CPU1_IMON1 PU75_P1_1        38       ISL99390FRZTR5935-ISL99390FRZ-A
PVCCFA_EHV_FIVRA_CPU1_IMON2 PU29             37       RAA229126GNPHA0-RAA229126GNP#HA
PVCCFA_EHV_FIVRA_CPU1_IMON2 PU76_P1_2        38       ISL99390FRZTR5935-ISL99390FRZ-A
PVCCFA_EHV_FIVRA_CPU1_IMON3 PU29             36       RAA229126GNPHA0-RAA229126GNP#HA
PVCCFA_EHV_FIVRA_CPU1_IMON3 PU77_P1_3        38       ISL99390FRZTR5935-ISL99390FRZ-A
PVCCFA_EHV_FIVRA_CPU1_IMON4 PU29             35       RAA229126GNPHA0-RAA229126GNP#HA
PVCCFA_EHV_FIVRA_CPU1_IMON4 PU78_P1_4        38       ISL99390FRZTR5935-ISL99390FRZ-A
PVCCFA_EHV_FIVRA_CPU1_LSET1 PR225            1        Q_RES_0402LF-8.87K,1%,1/16W,EMA
PVCCFA_EHV_FIVRA_CPU1_LSET1 PU75_P1_1        37       ISL99390FRZTR5935-ISL99390FRZ-A
PVCCFA_EHV_FIVRA_CPU1_LSET2 PR224            1        Q_RES_0402LF-8.87K,1%,1/16W,EMA
PVCCFA_EHV_FIVRA_CPU1_LSET2 PU76_P1_2        37       ISL99390FRZTR5935-ISL99390FRZ-A
PVCCFA_EHV_FIVRA_CPU1_LSET3 PR1305           1        Q_RES_0402LF-8.87K,1%,1/16W,EMA
PVCCFA_EHV_FIVRA_CPU1_LSET3 PU77_P1_3        37       ISL99390FRZTR5935-ISL99390FRZ-A
PVCCFA_EHV_FIVRA_CPU1_LSET4 PR1304           1        Q_RES_0402LF-8.87K,1%,1/16W,EMA
PVCCFA_EHV_FIVRA_CPU1_LSET4 PU78_P1_4        37       ISL99390FRZTR5935-ISL99390FRZ-A
PVCCFA_EHV_FIVRA_CPU1_PVCC1 PC1242_P1_1      1        Q_CAP_C0402-2.2UF,10V,10%,X6S,A
PVCCFA_EHV_FIVRA_CPU1_PVCC1 PC1244_P1_3      1        Q_CAP_C0402-2.2UF,10V,10%,X6S,A
PVCCFA_EHV_FIVRA_CPU1_PVCC1 PR226            1        Q_RES_0402LF-2.2,1%,1/16W,CHIPA
PVCCFA_EHV_FIVRA_CPU1_PVCC1 PR701            2        Q_RES_0402LF-0,5%,1/16W,CHIP,CA
PVCCFA_EHV_FIVRA_CPU1_PVCC1 PR703            2        Q_RES_0402LF-0,5%,1/16W,EMPTY,A
PVCCFA_EHV_FIVRA_CPU1_PVCC1 PR1306           1        Q_RES_0402LF-2.2,1%,1/16W,CHIPA
PVCCFA_EHV_FIVRA_CPU1_PVCC1 PU75_P1_1        4        ISL99390FRZTR5935-ISL99390FRZ-A
PVCCFA_EHV_FIVRA_CPU1_PVCC1 PU77_P1_3        4        ISL99390FRZTR5935-ISL99390FRZ-A
PVCCFA_EHV_FIVRA_CPU1_PVCC2 PC1243_P1_2      1        Q_CAP_C0402-2.2UF,10V,10%,X6S,A
PVCCFA_EHV_FIVRA_CPU1_PVCC2 PC1245_P1_4      1        Q_CAP_C0402-2.2UF,10V,10%,X6S,A
PVCCFA_EHV_FIVRA_CPU1_PVCC2 PR227            1        Q_RES_0402LF-2.2,1%,1/16W,CHIPA
PVCCFA_EHV_FIVRA_CPU1_PVCC2 PR702            2        Q_RES_0402LF-0,5%,1/16W,CHIP,CA
PVCCFA_EHV_FIVRA_CPU1_PVCC2 PR704            2        Q_RES_0402LF-0,5%,1/16W,EMPTY,A
PVCCFA_EHV_FIVRA_CPU1_PVCC2 PR1307           1        Q_RES_0402LF-2.2,1%,1/16W,CHIPA
PVCCFA_EHV_FIVRA_CPU1_PVCC2 PU76_P1_2        4        ISL99390FRZTR5935-ISL99390FRZ-A
PVCCFA_EHV_FIVRA_CPU1_PVCC2 PU78_P1_4        4        ISL99390FRZTR5935-ISL99390FRZ-A
PVCCFA_EHV_FIVRA_CPU1_PWM1 PU29             1        RAA229126GNPHA0-RAA229126GNP#HA
PVCCFA_EHV_FIVRA_CPU1_PWM1 PU75_P1_1        34       ISL99390FRZTR5935-ISL99390FRZ-A
PVCCFA_EHV_FIVRA_CPU1_PWM2 PU29             2        RAA229126GNPHA0-RAA229126GNP#HA
PVCCFA_EHV_FIVRA_CPU1_PWM2 PU76_P1_2        34       ISL99390FRZTR5935-ISL99390FRZ-A
PVCCFA_EHV_FIVRA_CPU1_PWM3 PU29             3        RAA229126GNPHA0-RAA229126GNP#HA
PVCCFA_EHV_FIVRA_CPU1_PWM3 PU77_P1_3        34       ISL99390FRZTR5935-ISL99390FRZ-A
PVCCFA_EHV_FIVRA_CPU1_PWM4 PU29             4        RAA229126GNPHA0-RAA229126GNP#HA
PVCCFA_EHV_FIVRA_CPU1_PWM4 PU78_P1_4        34       ISL99390FRZTR5935-ISL99390FRZ-A
PVCCFA_EHV_FIVRA_CPU1_VDD1 PC395            1        Q_CAP_C0402-2.2UF,10V,10%,X6S,A
PVCCFA_EHV_FIVRA_CPU1_VDD1 PR226            2        Q_RES_0402LF-2.2,1%,1/16W,CHIPA
PVCCFA_EHV_FIVRA_CPU1_VDD1 PU75_P1_1        3        ISL99390FRZTR5935-ISL99390FRZ-A
PVCCFA_EHV_FIVRA_CPU1_VDD1 PU75_P1_1        35       ISL99390FRZTR5935-ISL99390FRZ-A
PVCCFA_EHV_FIVRA_CPU1_VDD2 PC396            1        Q_CAP_C0402-2.2UF,10V,10%,X6S,A
PVCCFA_EHV_FIVRA_CPU1_VDD2 PR227            2        Q_RES_0402LF-2.2,1%,1/16W,CHIPA
PVCCFA_EHV_FIVRA_CPU1_VDD2 PU76_P1_2        3        ISL99390FRZTR5935-ISL99390FRZ-A
PVCCFA_EHV_FIVRA_CPU1_VDD2 PU76_P1_2        35       ISL99390FRZTR5935-ISL99390FRZ-A
PVCCFA_EHV_FIVRA_CPU1_VDD3 PC1191           1        Q_CAP_C0402-2.2UF,10V,10%,X6S,A
PVCCFA_EHV_FIVRA_CPU1_VDD3 PR1306           2        Q_RES_0402LF-2.2,1%,1/16W,CHIPA
PVCCFA_EHV_FIVRA_CPU1_VDD3 PU77_P1_3        3        ISL99390FRZTR5935-ISL99390FRZ-A
PVCCFA_EHV_FIVRA_CPU1_VDD3 PU77_P1_3        35       ISL99390FRZTR5935-ISL99390FRZ-A
PVCCFA_EHV_FIVRA_CPU1_VDD4 PC1192           1        Q_CAP_C0402-2.2UF,10V,10%,X6S,A
PVCCFA_EHV_FIVRA_CPU1_VDD4 PR1307           2        Q_RES_0402LF-2.2,1%,1/16W,CHIPA
PVCCFA_EHV_FIVRA_CPU1_VDD4 PU78_P1_4        3        ISL99390FRZTR5935-ISL99390FRZ-A
PVCCFA_EHV_FIVRA_CPU1_VDD4 PU78_P1_4        35       ISL99390FRZTR5935-ISL99390FRZ-A
PVCCFA_EHV_FIVRA_CPU1_VOS1 PR1331           1        Q_RES_0402LF-0,5%,1/16W,CHIP,CA
PVCCFA_EHV_FIVRA_CPU1_VOS1 PU75_P1_1        1        ISL99390FRZTR5935-ISL99390FRZ-A
PVCCFA_EHV_FIVRA_CPU1_VOS2 PR1332           1        Q_RES_0402LF-0,5%,1/16W,CHIP,CA
PVCCFA_EHV_FIVRA_CPU1_VOS2 PU76_P1_2        1        ISL99390FRZTR5935-ISL99390FRZ-A
PVCCFA_EHV_FIVRA_CPU1_VOS3 PR1333           1        Q_RES_0402LF-0,5%,1/16W,CHIP,CA
PVCCFA_EHV_FIVRA_CPU1_VOS3 PU77_P1_3        1        ISL99390FRZTR5935-ISL99390FRZ-A
PVCCFA_EHV_FIVRA_CPU1_VOS4 PR1334           1        Q_RES_0402LF-0,5%,1/16W,CHIP,CA
PVCCFA_EHV_FIVRA_CPU1_VOS4 PU78_P1_4        1        ISL99390FRZTR5935-ISL99390FRZ-A
PVCCINFAON_CPU0          C408             1        Q_CAP_C0402-22UF,4V,20%,X6S,CHA
PVCCINFAON_CPU0          C410             1        Q_CAP_C0402-22UF,4V,20%,X6S,CHA
PVCCINFAON_CPU0          C412             1        Q_CAP_C0402-22UF,4V,20%,X6S,CHA
PVCCINFAON_CPU0          C414             1        Q_CAP_C0402-22UF,4V,20%,X6S,CHA
PVCCINFAON_CPU0          C416             1        Q_CAP_C0402-22UF,4V,20%,X6S,CHA
PVCCINFAON_CPU0          C522             1        Q_CAP_C0805-100UF,4V,20%,X6S,CA
PVCCINFAON_CPU0          C525             1        Q_CAP_C0805-100UF,4V,20%,X6S,CA
PVCCINFAON_CPU0          C528             1        Q_CAP_C0805-100UF,4V,20%,X6S,CA
PVCCINFAON_CPU0          C530             1        Q_CAP_C0805-100UF,4V,20%,X6S,CA
PVCCINFAON_CPU0          C531             1        Q_CAP_C0805-100UF,4V,20%,X6S,CA
PVCCINFAON_CPU0          C532             1        Q_CAP_C0603-47UF,2.5V,20%,X6S,A
PVCCINFAON_CPU0          C533             1        Q_CAP_C0603-47UF,2.5V,20%,X6S,A
PVCCINFAON_CPU0          C534             1        Q_CAP_C0402-22UF,4V,20%,X6S,CHA
PVCCINFAON_CPU0          PC1573           1        Q_CAPP_SMLF-330UF,2V,35%,SPCAPA
PVCCINFAON_CPU0          PC1574           1        Q_CAPP_THLF-560UF,2.5V,20%,OSCA
PVCCINFAON_CPU0          PC1575           1        Q_CAPP_SMLF-330UF,2V,35%,SPCAPA
PVCCINFAON_CPU0          PC1576           1        Q_CAPP_THLF-560UF,2.5V,20%,OSCA
PVCCINFAON_CPU0          PC1579           1        Q_CAPP_THLF-560UF,2.5V,20%,OSCA
PVCCINFAON_CPU0          PC199_P0_1       1        Q_CAP_C0402-100NF,50V,10%,X7R,A
PVCCINFAON_CPU0          PC202_P0_1       1        Q_CAP_0805-22UF,4V,20%,X6S,TMPA
PVCCINFAON_CPU0          PC203_P0_2       1        Q_CAP_0805-22UF,4V,20%,X6S,TMPA
PVCCINFAON_CPU0          PC204_P0_1       1        Q_CAP_0805-22UF,4V,20%,X6S,TMPA
PVCCINFAON_CPU0          PC205_P0_2       1        Q_CAP_0805-22UF,4V,20%,X6S,TMPA
PVCCINFAON_CPU0          PL4              2        Q_INDUCTOR_SMLF-120NH/94A,IND,A
PVCCINFAON_CPU0          PL5              2        Q_INDUCTOR_SMLF-120NH/94A,IND,A
PVCCINFAON_CPU0          PR521            2        Q_RES_0402LF-100,1%,1/16W,CHIPA
PVCCINFAON_CPU0          R323             1        Q_RES_1206LF-0,,1/2W,EMPTY,CS0A
PVCCINFAON_CPU0          U2               AY18     SOCKET4677_AZIFS054P001C01-SOCA
PVCCINFAON_CPU0          U2               BA15     SOCKET4677_AZIFS054P001C01-SOCA
PVCCINFAON_CPU0          U2               BC60     SOCKET4677_AZIFS054P001C01-SOCA
PVCCINFAON_CPU0          U2               BE15     SOCKET4677_AZIFS054P001C01-SOCA
PVCCINFAON_CPU0          U2               BE60     SOCKET4677_AZIFS054P001C01-SOCA
PVCCINFAON_CPU0          U2               BG60     SOCKET4677_AZIFS054P001C01-SOCA
PVCCINFAON_CPU0          U2               BJ15     SOCKET4677_AZIFS054P001C01-SOCA
PVCCINFAON_CPU0          U2               BJ60     SOCKET4677_AZIFS054P001C01-SOCA
PVCCINFAON_CPU0          U2               BK61     SOCKET4677_AZIFS054P001C01-SOCA
PVCCINFAON_CPU0          U2               BN15     SOCKET4677_AZIFS054P001C01-SOCA
PVCCINFAON_CPU0          U2               CA15     SOCKET4677_AZIFS054P001C01-SOCA
PVCCINFAON_CPU0          U2               CE15     SOCKET4677_AZIFS054P001C01-SOCA
PVCCINFAON_CPU0          U2               CE19     SOCKET4677_AZIFS054P001C01-SOCA
PVCCINFAON_CPU0          U2               CJ3      SOCKET4677_AZIFS054P001C01-SOCA
PVCCINFAON_CPU0          U2               CJ7      SOCKET4677_AZIFS054P001C01-SOCA
PVCCINFAON_CPU0          U2               CJ11     SOCKET4677_AZIFS054P001C01-SOCA
PVCCINFAON_CPU0          U2               CJ15     SOCKET4677_AZIFS054P001C01-SOCA
PVCCINFAON_CPU0          U2               CJ19     SOCKET4677_AZIFS054P001C01-SOCA
PVCCINFAON_CPU0          U2               CN3      SOCKET4677_AZIFS054P001C01-SOCA
PVCCINFAON_CPU0          U2               CN7      SOCKET4677_AZIFS054P001C01-SOCA
PVCCINFAON_CPU0          U2               CN11     SOCKET4677_AZIFS054P001C01-SOCA
PVCCINFAON_CPU0          U2               CN15     SOCKET4677_AZIFS054P001C01-SOCA
PVCCINFAON_CPU0          U2               CN19     SOCKET4677_AZIFS054P001C01-SOCA
PVCCINFAON_CPU0          U2               CN64     SOCKET4677_AZIFS054P001C01-SOCA
PVCCINFAON_CPU0          U2               CN66     SOCKET4677_AZIFS054P001C01-SOCA
PVCCINFAON_CPU0          U2               CP63     SOCKET4677_AZIFS054P001C01-SOCA
PVCCINFAON_CPU0          U2               CP65     SOCKET4677_AZIFS054P001C01-SOCA
PVCCINFAON_CPU0          U2               CP67     SOCKET4677_AZIFS054P001C01-SOCA
PVCCINFAON_CPU0          U2               CR66     SOCKET4677_AZIFS054P001C01-SOCA
PVCCINFAON_CPU0          U2               CT63     SOCKET4677_AZIFS054P001C01-SOCA
PVCCINFAON_CPU0          U2               CT65     SOCKET4677_AZIFS054P001C01-SOCA
PVCCINFAON_CPU0          U2               CT67     SOCKET4677_AZIFS054P001C01-SOCA
PVCCINFAON_CPU0          U2               CU3      SOCKET4677_AZIFS054P001C01-SOCA
PVCCINFAON_CPU0          U2               CU7      SOCKET4677_AZIFS054P001C01-SOCA
PVCCINFAON_CPU0          U2               CU11     SOCKET4677_AZIFS054P001C01-SOCA
PVCCINFAON_CPU0          U2               CU15     SOCKET4677_AZIFS054P001C01-SOCA
PVCCINFAON_CPU0          U2               CU64     SOCKET4677_AZIFS054P001C01-SOCA
PVCCINFAON_CPU0          U2               CV61     SOCKET4677_AZIFS054P001C01-SOCA
PVCCINFAON_CPU0          U2               CV63     SOCKET4677_AZIFS054P001C01-SOCA
PVCCINFAON_CPU0          U2               CV65     SOCKET4677_AZIFS054P001C01-SOCA
PVCCINFAON_CPU0          U2               CV67     SOCKET4677_AZIFS054P001C01-SOCA
PVCCINFAON_CPU0          U2               CW62     SOCKET4677_AZIFS054P001C01-SOCA
PVCCINFAON_CPU0          U2               CW64     SOCKET4677_AZIFS054P001C01-SOCA
PVCCINFAON_CPU0          U2               CW66     SOCKET4677_AZIFS054P001C01-SOCA
PVCCINFAON_CPU0          U2               CY65     SOCKET4677_AZIFS054P001C01-SOCA
PVCCINFAON_CPU0          U2               CY67     SOCKET4677_AZIFS054P001C01-SOCA
PVCCINFAON_CPU0          U2               DA3      SOCKET4677_AZIFS054P001C01-SOCA
PVCCINFAON_CPU0          U2               DA7      SOCKET4677_AZIFS054P001C01-SOCA
PVCCINFAON_CPU0          U2               DA11     SOCKET4677_AZIFS054P001C01-SOCA
PVCCINFAON_CPU0          U2               DA15     SOCKET4677_AZIFS054P001C01-SOCA
PVCCINFAON_CPU0          U2               DA21     SOCKET4677_AZIFS054P001C01-SOCA
PVCCINFAON_CPU0          U2               DA64     SOCKET4677_AZIFS054P001C01-SOCA
PVCCINFAON_CPU0          U2               DE3      SOCKET4677_AZIFS054P001C01-SOCA
PVCCINFAON_CPU0          U2               DE7      SOCKET4677_AZIFS054P001C01-SOCA
PVCCINFAON_CPU0          U2               DE11     SOCKET4677_AZIFS054P001C01-SOCA
PVCCINFAON_CPU0          U2               DE15     SOCKET4677_AZIFS054P001C01-SOCA
PVCCINFAON_CPU0          U2               DJ3      SOCKET4677_AZIFS054P001C01-SOCA
PVCCINFAON_CPU0          U2               DJ7      SOCKET4677_AZIFS054P001C01-SOCA
PVCCINFAON_CPU0          U2               DJ11     SOCKET4677_AZIFS054P001C01-SOCA
PVCCINFAON_CPU0          U2               DJ15     SOCKET4677_AZIFS054P001C01-SOCA
PVCCINFAON_CPU0_ACSP1    PU43_P0_1        25       RAA2213404GNPHB0-RAA2213404GNPA
PVCCINFAON_CPU0_ACSP1    PU5              23       ISL69260IRAZT-ISL69260IRAZ-T,SA
PVCCINFAON_CPU0_ACSP2    PU44_P0_2        25       RAA2213404GNPHB0-RAA2213404GNPA
PVCCINFAON_CPU0_ACSP2    PU5              24       ISL69260IRAZT-ISL69260IRAZ-T,SA
PVCCINFAON_CPU0_ADDR     PR105            2        Q_RES_0402LF-28K,1%,1/16W,EMPTA
PVCCINFAON_CPU0_ADDR     PR106            1        Q_RES_R0402LF-887,1%,1/16W,CHIA
PVCCINFAON_CPU0_ADDR     PU5              34       ISL69260IRAZT-ISL69260IRAZ-T,SA
PVCCINFAON_CPU0_APWM1    PU43_P0_1        21       RAA2213404GNPHB0-RAA2213404GNPA
PVCCINFAON_CPU0_APWM1    PU5              8        ISL69260IRAZT-ISL69260IRAZ-T,SA
PVCCINFAON_CPU0_APWM2    PU44_P0_2        21       RAA2213404GNPHB0-RAA2213404GNPA
PVCCINFAON_CPU0_APWM2    PU5              7        ISL69260IRAZT-ISL69260IRAZ-T,SA
PVCCINFAON_CPU0_ATSEN    PC222            1        Q_CAP_0402-470PF,50V,10%,X7R,TA
PVCCINFAON_CPU0_ATSEN    PR435            1        Q_RES_0402LF-10K,1%,1/16W,EMPTB
PVCCINFAON_CPU0_ATSEN    PU43_P0_1        1        RAA2213404GNPHB0-RAA2213404GNPA
PVCCINFAON_CPU0_ATSEN    PU44_P0_2        1        RAA2213404GNPHB0-RAA2213404GNPA
PVCCINFAON_CPU0_ATSEN    PU5              35       ISL69260IRAZT-ISL69260IRAZ-T,SA
PVCCINFAON_CPU0_CSPIN    PC214            1        Q_CAP_0402-0.1UF,25V,10%,EMPTYA
PVCCINFAON_CPU0_CSPIN    PR107            2        Q_RES_0402LF-0,5%,1/16W,EMPTY,A
PVCCINFAON_CPU0_CSPIN    PR122            1        Q_RES_0402LF-0,5%,1/16W,CHIP,CA
PVCCINFAON_CPU0_CSPIN    PU5              37       ISL69260IRAZT-ISL69260IRAZ-T,SA
PVCCINFAON_CPU0_EN_R     PC217            1        Q_CAP_0402-1000PF,50V,5%,X7R,TA
PVCCINFAON_CPU0_EN_R     PR111            2        Q_RES_0402LF-0,5%,1/16W,CHIP,CA
PVCCINFAON_CPU0_EN_R     PU5              13       ISL69260IRAZT-ISL69260IRAZ-T,SA
PVCCINFAON_CPU0_LSET1    PR1708           1        Q_RES_0402LF-8.87K,1%,1/16W,EMA
PVCCINFAON_CPU0_LSET1    PU43_P0_1        5        RAA2213404GNPHB0-RAA2213404GNPA
PVCCINFAON_CPU0_LSET2    PR1707           1        Q_RES_0402LF-8.87K,1%,1/16W,EMA
PVCCINFAON_CPU0_LSET2    PU44_P0_2        5        RAA2213404GNPHB0-RAA2213404GNPA
PVCCINFAON_CPU0_PH1_NC1  PR1776           1        Q_RES_0402LF-0,5%,1/16W,CHIP,CA
PVCCINFAON_CPU0_PH1_NC1  PU43_P0_1        3        RAA2213404GNPHB0-RAA2213404GNPA
PVCCINFAON_CPU0_PH2_NC1  PR1777           1        Q_RES_0402LF-0,5%,1/16W,CHIP,CA
PVCCINFAON_CPU0_PH2_NC1  PU44_P0_2        3        RAA2213404GNPHB0-RAA2213404GNPA
PVCCINFAON_CPU0_PIN_ALERT PR524            2        Q_RES_0402LF-1K,1%,1/16W,CHIP,A
PVCCINFAON_CPU0_PIN_ALERT PU5              15       ISL69260IRAZT-ISL69260IRAZ-T,SA
PVCCINFAON_CPU0_PVCC     PR101            1        Q_RES_0402LF-2.2,1%,1/16W,CHIPA
PVCCINFAON_CPU0_PVCC     PR102            1        Q_RES_0402LF-2.2,1%,1/16W,CHIPA
PVCCINFAON_CPU0_PVCC     PR437            2        Q_RES_0402LF-0,5%,1/16W,CHIP,CA
PVCCINFAON_CPU0_PVCC     PR441            2        Q_RES_0402LF-0,5%,1/16W,EMPTY,A
PVCCINFAON_CPU0_VCC      PC223            1        Q_CAP_C0402-100NF,50V,10%,EMPTA
PVCCINFAON_CPU0_VCC      PC225            1        Q_CAP_C0402-1UF,16V,10%,X6S,CHA
PVCCINFAON_CPU0_VCC      PR130            1        Q_RES_0402LF-1,1%,1/16W,CHIP,CA
PVCCINFAON_CPU0_VCC      PU5              39       ISL69260IRAZT-ISL69260IRAZ-T,SA
PVCCINFAON_CPU0_VDD1     PC187            1        Q_CAP_C0402-2.2UF,10V,10%,X6S,A
PVCCINFAON_CPU0_VDD1     PR101            2        Q_RES_0402LF-2.2,1%,1/16W,CHIPA
PVCCINFAON_CPU0_VDD1     PR1776           2        Q_RES_0402LF-0,5%,1/16W,CHIP,CA
PVCCINFAON_CPU0_VDD1     PU43_P0_1        4        RAA2213404GNPHB0-RAA2213404GNPA
PVCCINFAON_CPU0_VDD1     PU43_P0_1        22       RAA2213404GNPHB0-RAA2213404GNPA
PVCCINFAON_CPU0_VDD2     PC188            1        Q_CAP_C0402-2.2UF,10V,10%,X6S,A
PVCCINFAON_CPU0_VDD2     PR102            2        Q_RES_0402LF-2.2,1%,1/16W,CHIPA
PVCCINFAON_CPU0_VDD2     PR1777           2        Q_RES_0402LF-0,5%,1/16W,CHIP,CA
PVCCINFAON_CPU0_VDD2     PU44_P0_2        4        RAA2213404GNPHB0-RAA2213404GNPA
PVCCINFAON_CPU0_VDD2     PU44_P0_2        22       RAA2213404GNPHB0-RAA2213404GNPA
PVCCINFAON_CPU0_VIN_CSNIN PC221            1        Q_CAP_0402-0.1UF,25V,10%,X7R,CA
PVCCINFAON_CPU0_VIN_CSNIN PR108            2        Q_RES_0402LF-0,5%,1/16W,CHIP,CA
PVCCINFAON_CPU0_VIN_CSNIN PR123            1        Q_RES_0402LF-1K,1%,1/16W,EMPTYA
PVCCINFAON_CPU0_VIN_CSNIN PU5              38       ISL69260IRAZT-ISL69260IRAZ-T,SA
PVCCINFAON_CPU0_VREF     PC224            1        Q_CAP_0402-4.7UF,6.3V,20%,X6S,A
PVCCINFAON_CPU0_VREF     PC1346           2        Q_CAP_0402-0.1UF,25V,10%,X7R,CA
PVCCINFAON_CPU0_VREF     PC1347           2        Q_CAP_0402-0.1UF,25V,10%,X7R,CA
PVCCINFAON_CPU0_VREF     PC1348           2        Q_CAP_0402-0.1UF,25V,10%,X7R,CA
PVCCINFAON_CPU0_VREF     PC1372           1        Q_CAP_C0402-1UF,16V,10%,X6S,CHA
PVCCINFAON_CPU0_VREF     PR105            1        Q_RES_0402LF-28K,1%,1/16W,EMPTA
PVCCINFAON_CPU0_VREF     PU43_P0_1        24       RAA2213404GNPHB0-RAA2213404GNPA
PVCCINFAON_CPU0_VREF     PU44_P0_2        24       RAA2213404GNPHB0-RAA2213404GNPA
PVCCINFAON_CPU0_VREF     PU5              40       ISL69260IRAZT-ISL69260IRAZ-T,SA
PVCCINFAON_CPU0_VREF     PU42             24       RAA2213404GNPHB0-RAA2213404GNPA
PVCCINFAON_CPU0_VR_FAULT PR523            2        Q_RES_0402LF-1K,1%,1/16W,CHIP,A
PVCCINFAON_CPU0_VR_FAULT PU5              33       ISL69260IRAZT-ISL69260IRAZ-T,SA
PVCCINFAON_CPU1          C432             1        Q_CAP_C0402-22UF,4V,20%,X6S,CHA
PVCCINFAON_CPU1          C434             1        Q_CAP_C0402-22UF,4V,20%,X6S,CHA
PVCCINFAON_CPU1          C436             1        Q_CAP_C0402-22UF,4V,20%,X6S,CHA
PVCCINFAON_CPU1          C438             1        Q_CAP_C0402-22UF,4V,20%,X6S,CHA
PVCCINFAON_CPU1          C440             1        Q_CAP_C0402-22UF,4V,20%,X6S,CHA
PVCCINFAON_CPU1          C478             1        Q_CAP_C0805-100UF,4V,20%,X6S,CA
PVCCINFAON_CPU1          C481             1        Q_CAP_C0805-100UF,4V,20%,X6S,CA
PVCCINFAON_CPU1          C484             1        Q_CAP_C0805-100UF,4V,20%,X6S,CA
PVCCINFAON_CPU1          C486             1        Q_CAP_C0805-100UF,4V,20%,X6S,CA
PVCCINFAON_CPU1          C487             1        Q_CAP_C0805-100UF,4V,20%,X6S,CA
PVCCINFAON_CPU1          C488             1        Q_CAP_C0603-47UF,2.5V,20%,X6S,A
PVCCINFAON_CPU1          C489             1        Q_CAP_C0603-47UF,2.5V,20%,X6S,A
PVCCINFAON_CPU1          C490             1        Q_CAP_C0402-22UF,4V,20%,X6S,CHA
PVCCINFAON_CPU1          PC1588           1        Q_CAPP_SMLF-330UF,2V,35%,SPCAPA
PVCCINFAON_CPU1          PC1593           1        Q_CAPP_THLF-560UF,2.5V,20%,OSCA
PVCCINFAON_CPU1          PC1594           1        Q_CAPP_SMLF-330UF,2V,35%,SPCAPA
PVCCINFAON_CPU1          PC1595           1        Q_CAPP_THLF-560UF,2.5V,20%,OSCA
PVCCINFAON_CPU1          PC1596           1        Q_CAPP_THLF-560UF,2.5V,20%,OSCA
PVCCINFAON_CPU1          PC452_P1_1       1        Q_CAP_C0402-100NF,50V,10%,X7R,A
PVCCINFAON_CPU1          PC455_P1_1       1        Q_CAP_0805-22UF,4V,20%,X6S,TMPA
PVCCINFAON_CPU1          PC456_P1_2       1        Q_CAP_0805-22UF,4V,20%,X6S,TMPA
PVCCINFAON_CPU1          PC457_P1_1       1        Q_CAP_0805-22UF,4V,20%,X6S,TMPA
PVCCINFAON_CPU1          PC458_P1_2       1        Q_CAP_0805-22UF,4V,20%,X6S,TMPA
PVCCINFAON_CPU1          PL21             2        Q_INDUCTOR_SMLF-120NH/94A,IND,A
PVCCINFAON_CPU1          PL22             2        Q_INDUCTOR_SMLF-120NH/94A,IND,A
PVCCINFAON_CPU1          PR568            2        Q_RES_0402LF-100,1%,1/16W,CHIPA
PVCCINFAON_CPU1          R329             1        Q_RES_1206LF-0,,1/2W,EMPTY,CS0A
PVCCINFAON_CPU1          U1               AY18     SOCKET4677_AZIFS054P001C01-SOCA
PVCCINFAON_CPU1          U1               BA15     SOCKET4677_AZIFS054P001C01-SOCA
PVCCINFAON_CPU1          U1               BC60     SOCKET4677_AZIFS054P001C01-SOCA
PVCCINFAON_CPU1          U1               BE15     SOCKET4677_AZIFS054P001C01-SOCA
PVCCINFAON_CPU1          U1               BE60     SOCKET4677_AZIFS054P001C01-SOCA
PVCCINFAON_CPU1          U1               BG60     SOCKET4677_AZIFS054P001C01-SOCA
PVCCINFAON_CPU1          U1               BJ15     SOCKET4677_AZIFS054P001C01-SOCA
PVCCINFAON_CPU1          U1               BJ60     SOCKET4677_AZIFS054P001C01-SOCA
PVCCINFAON_CPU1          U1               BK61     SOCKET4677_AZIFS054P001C01-SOCA
PVCCINFAON_CPU1          U1               BN15     SOCKET4677_AZIFS054P001C01-SOCA
PVCCINFAON_CPU1          U1               CA15     SOCKET4677_AZIFS054P001C01-SOCA
PVCCINFAON_CPU1          U1               CE15     SOCKET4677_AZIFS054P001C01-SOCA
PVCCINFAON_CPU1          U1               CE19     SOCKET4677_AZIFS054P001C01-SOCA
PVCCINFAON_CPU1          U1               CJ3      SOCKET4677_AZIFS054P001C01-SOCA
PVCCINFAON_CPU1          U1               CJ7      SOCKET4677_AZIFS054P001C01-SOCA
PVCCINFAON_CPU1          U1               CJ11     SOCKET4677_AZIFS054P001C01-SOCA
PVCCINFAON_CPU1          U1               CJ15     SOCKET4677_AZIFS054P001C01-SOCA
PVCCINFAON_CPU1          U1               CJ19     SOCKET4677_AZIFS054P001C01-SOCA
PVCCINFAON_CPU1          U1               CN3      SOCKET4677_AZIFS054P001C01-SOCA
PVCCINFAON_CPU1          U1               CN7      SOCKET4677_AZIFS054P001C01-SOCA
PVCCINFAON_CPU1          U1               CN11     SOCKET4677_AZIFS054P001C01-SOCA
PVCCINFAON_CPU1          U1               CN15     SOCKET4677_AZIFS054P001C01-SOCA
PVCCINFAON_CPU1          U1               CN19     SOCKET4677_AZIFS054P001C01-SOCA
PVCCINFAON_CPU1          U1               CN64     SOCKET4677_AZIFS054P001C01-SOCA
PVCCINFAON_CPU1          U1               CN66     SOCKET4677_AZIFS054P001C01-SOCA
PVCCINFAON_CPU1          U1               CP63     SOCKET4677_AZIFS054P001C01-SOCA
PVCCINFAON_CPU1          U1               CP65     SOCKET4677_AZIFS054P001C01-SOCA
PVCCINFAON_CPU1          U1               CP67     SOCKET4677_AZIFS054P001C01-SOCA
PVCCINFAON_CPU1          U1               CR66     SOCKET4677_AZIFS054P001C01-SOCA
PVCCINFAON_CPU1          U1               CT63     SOCKET4677_AZIFS054P001C01-SOCA
PVCCINFAON_CPU1          U1               CT65     SOCKET4677_AZIFS054P001C01-SOCA
PVCCINFAON_CPU1          U1               CT67     SOCKET4677_AZIFS054P001C01-SOCA
PVCCINFAON_CPU1          U1               CU3      SOCKET4677_AZIFS054P001C01-SOCA
PVCCINFAON_CPU1          U1               CU7      SOCKET4677_AZIFS054P001C01-SOCA
PVCCINFAON_CPU1          U1               CU11     SOCKET4677_AZIFS054P001C01-SOCA
PVCCINFAON_CPU1          U1               CU15     SOCKET4677_AZIFS054P001C01-SOCA
PVCCINFAON_CPU1          U1               CU64     SOCKET4677_AZIFS054P001C01-SOCA
PVCCINFAON_CPU1          U1               CV61     SOCKET4677_AZIFS054P001C01-SOCA
PVCCINFAON_CPU1          U1               CV63     SOCKET4677_AZIFS054P001C01-SOCA
PVCCINFAON_CPU1          U1               CV65     SOCKET4677_AZIFS054P001C01-SOCA
PVCCINFAON_CPU1          U1               CV67     SOCKET4677_AZIFS054P001C01-SOCA
PVCCINFAON_CPU1          U1               CW62     SOCKET4677_AZIFS054P001C01-SOCA
PVCCINFAON_CPU1          U1               CW64     SOCKET4677_AZIFS054P001C01-SOCA
PVCCINFAON_CPU1          U1               CW66     SOCKET4677_AZIFS054P001C01-SOCA
PVCCINFAON_CPU1          U1               CY65     SOCKET4677_AZIFS054P001C01-SOCA
PVCCINFAON_CPU1          U1               CY67     SOCKET4677_AZIFS054P001C01-SOCA
PVCCINFAON_CPU1          U1               DA3      SOCKET4677_AZIFS054P001C01-SOCA
PVCCINFAON_CPU1          U1               DA7      SOCKET4677_AZIFS054P001C01-SOCA
PVCCINFAON_CPU1          U1               DA11     SOCKET4677_AZIFS054P001C01-SOCA
PVCCINFAON_CPU1          U1               DA15     SOCKET4677_AZIFS054P001C01-SOCA
PVCCINFAON_CPU1          U1               DA21     SOCKET4677_AZIFS054P001C01-SOCA
PVCCINFAON_CPU1          U1               DA64     SOCKET4677_AZIFS054P001C01-SOCA
PVCCINFAON_CPU1          U1               DE3      SOCKET4677_AZIFS054P001C01-SOCA
PVCCINFAON_CPU1          U1               DE7      SOCKET4677_AZIFS054P001C01-SOCA
PVCCINFAON_CPU1          U1               DE11     SOCKET4677_AZIFS054P001C01-SOCA
PVCCINFAON_CPU1          U1               DE15     SOCKET4677_AZIFS054P001C01-SOCA
PVCCINFAON_CPU1          U1               DJ3      SOCKET4677_AZIFS054P001C01-SOCA
PVCCINFAON_CPU1          U1               DJ7      SOCKET4677_AZIFS054P001C01-SOCA
PVCCINFAON_CPU1          U1               DJ11     SOCKET4677_AZIFS054P001C01-SOCA
PVCCINFAON_CPU1          U1               DJ15     SOCKET4677_AZIFS054P001C01-SOCA
PVCCINFAON_CPU1_ACSP1    PU22             23       ISL69260IRAZT-ISL69260IRAZ-T,SA
PVCCINFAON_CPU1_ACSP1    PU50_P1_1        25       RAA2213404GNPHB0-RAA2213404GNPA
PVCCINFAON_CPU1_ACSP2    PU22             24       ISL69260IRAZT-ISL69260IRAZ-T,SA
PVCCINFAON_CPU1_ACSP2    PU51_P1_2        25       RAA2213404GNPHB0-RAA2213404GNPA
PVCCINFAON_CPU1_ADDR     PR258            2        Q_RES_0402LF-28K,1%,1/16W,EMPTA
PVCCINFAON_CPU1_ADDR     PR259            1        Q_RES_0402LF -9.53K,1%,1/16W ,A
PVCCINFAON_CPU1_ADDR     PU22             34       ISL69260IRAZT-ISL69260IRAZ-T,SA
PVCCINFAON_CPU1_APWM1    PU22             8        ISL69260IRAZT-ISL69260IRAZ-T,SA
PVCCINFAON_CPU1_APWM1    PU50_P1_1        21       RAA2213404GNPHB0-RAA2213404GNPA
PVCCINFAON_CPU1_APWM2    PU22             7        ISL69260IRAZT-ISL69260IRAZ-T,SA
PVCCINFAON_CPU1_APWM2    PU51_P1_2        21       RAA2213404GNPHB0-RAA2213404GNPA
PVCCINFAON_CPU1_ATSEN    PC475            1        Q_CAP_0402-470PF,50V,10%,X7R,TA
PVCCINFAON_CPU1_ATSEN    PR665            1        Q_RES_0402LF-10K,1%,1/16W,EMPTB
PVCCINFAON_CPU1_ATSEN    PU22             35       ISL69260IRAZT-ISL69260IRAZ-T,SA
PVCCINFAON_CPU1_ATSEN    PU50_P1_1        1        RAA2213404GNPHB0-RAA2213404GNPA
PVCCINFAON_CPU1_ATSEN    PU51_P1_2        1        RAA2213404GNPHB0-RAA2213404GNPA
PVCCINFAON_CPU1_CSPIN    PC467            1        Q_CAP_0402-0.1UF,25V,10%,EMPTYA
PVCCINFAON_CPU1_CSPIN    PR260            2        Q_RES_0402LF-0,5%,1/16W,EMPTY,A
PVCCINFAON_CPU1_CSPIN    PR275            1        Q_RES_0402LF-0,5%,1/16W,CHIP,CA
PVCCINFAON_CPU1_CSPIN    PU22             37       ISL69260IRAZT-ISL69260IRAZ-T,SA
PVCCINFAON_CPU1_EN_R     PC470            1        Q_CAP_0402-1000PF,50V,5%,X7R,TA
PVCCINFAON_CPU1_EN_R     PR264            2        Q_RES_0402LF-0,5%,1/16W,CHIP,CA
PVCCINFAON_CPU1_EN_R     PU22             13       ISL69260IRAZT-ISL69260IRAZ-T,SA
PVCCINFAON_CPU1_LSET1    PR1726           1        Q_RES_0402LF-8.87K,1%,1/16W,EMA
PVCCINFAON_CPU1_LSET1    PU50_P1_1        5        RAA2213404GNPHB0-RAA2213404GNPA
PVCCINFAON_CPU1_LSET2    PR1727           1        Q_RES_0402LF-8.87K,1%,1/16W,EMA
PVCCINFAON_CPU1_LSET2    PU51_P1_2        5        RAA2213404GNPHB0-RAA2213404GNPA
PVCCINFAON_CPU1_PH1_NC1  PR1796           1        Q_RES_0402LF-0,5%,1/16W,CHIP,CA
PVCCINFAON_CPU1_PH1_NC1  PU50_P1_1        3        RAA2213404GNPHB0-RAA2213404GNPA
PVCCINFAON_CPU1_PH2_NC1  PR1797           1        Q_RES_0402LF-0,5%,1/16W,CHIP,CA
PVCCINFAON_CPU1_PH2_NC1  PU51_P1_2        3        RAA2213404GNPHB0-RAA2213404GNPA
PVCCINFAON_CPU1_PIN_ALERT PR571            2        Q_RES_0402LF-1K,1%,1/16W,CHIP,A
PVCCINFAON_CPU1_PIN_ALERT PU22             15       ISL69260IRAZT-ISL69260IRAZ-T,SA
PVCCINFAON_CPU1_PVCC     PR254            1        Q_RES_0402LF-2.2,1%,1/16W,CHIPA
PVCCINFAON_CPU1_PVCC     PR255            1        Q_RES_0402LF-2.2,1%,1/16W,CHIPA
PVCCINFAON_CPU1_PVCC     PR668            2        Q_RES_0402LF-0,5%,1/16W,CHIP,CA
PVCCINFAON_CPU1_PVCC     PR677            2        Q_RES_0402LF-0,5%,1/16W,EMPTY,A
PVCCINFAON_CPU1_VCC      PC476            1        Q_CAP_C0402-100NF,50V,10%,EMPTA
PVCCINFAON_CPU1_VCC      PC478            1        Q_CAP_C0402-1UF,16V,10%,X6S,CHA
PVCCINFAON_CPU1_VCC      PR283            1        Q_RES_0402LF-1,1%,1/16W,CHIP,CA
PVCCINFAON_CPU1_VCC      PU22             39       ISL69260IRAZT-ISL69260IRAZ-T,SA
PVCCINFAON_CPU1_VDD1     PC440            1        Q_CAP_C0402-2.2UF,10V,10%,X6S,A
PVCCINFAON_CPU1_VDD1     PR254            2        Q_RES_0402LF-2.2,1%,1/16W,CHIPA
PVCCINFAON_CPU1_VDD1     PR1796           2        Q_RES_0402LF-0,5%,1/16W,CHIP,CA
PVCCINFAON_CPU1_VDD1     PU50_P1_1        4        RAA2213404GNPHB0-RAA2213404GNPA
PVCCINFAON_CPU1_VDD1     PU50_P1_1        22       RAA2213404GNPHB0-RAA2213404GNPA
PVCCINFAON_CPU1_VDD2     PC441            1        Q_CAP_C0402-2.2UF,10V,10%,X6S,A
PVCCINFAON_CPU1_VDD2     PR255            2        Q_RES_0402LF-2.2,1%,1/16W,CHIPA
PVCCINFAON_CPU1_VDD2     PR1797           2        Q_RES_0402LF-0,5%,1/16W,CHIP,CA
PVCCINFAON_CPU1_VDD2     PU51_P1_2        4        RAA2213404GNPHB0-RAA2213404GNPA
PVCCINFAON_CPU1_VDD2     PU51_P1_2        22       RAA2213404GNPHB0-RAA2213404GNPA
PVCCINFAON_CPU1_VIN_CSNIN PC474            1        Q_CAP_0402-0.1UF,25V,10%,X7R,CA
PVCCINFAON_CPU1_VIN_CSNIN PR261            2        Q_RES_0402LF-0,5%,1/16W,CHIP,CA
PVCCINFAON_CPU1_VIN_CSNIN PR276            1        Q_RES_0402LF-1K,1%,1/16W,EMPTYA
PVCCINFAON_CPU1_VIN_CSNIN PU22             38       ISL69260IRAZT-ISL69260IRAZ-T,SA
PVCCINFAON_CPU1_VREF     PC477            1        Q_CAP_0402-4.7UF,6.3V,20%,X6S,A
PVCCINFAON_CPU1_VREF     PC1193           1        Q_CAP_C0402-1UF,16V,10%,X6S,CHA
PVCCINFAON_CPU1_VREF     PC1364           2        Q_CAP_0402-0.1UF,25V,10%,X7R,CA
PVCCINFAON_CPU1_VREF     PC1365           2        Q_CAP_0402-0.1UF,25V,10%,X7R,CA
PVCCINFAON_CPU1_VREF     PC1366           2        Q_CAP_0402-0.1UF,25V,10%,X7R,CA
PVCCINFAON_CPU1_VREF     PR258            1        Q_RES_0402LF-28K,1%,1/16W,EMPTA
PVCCINFAON_CPU1_VREF     PU22             40       ISL69260IRAZT-ISL69260IRAZ-T,SA
PVCCINFAON_CPU1_VREF     PU49             24       RAA2213404GNPHB0-RAA2213404GNPA
PVCCINFAON_CPU1_VREF     PU50_P1_1        24       RAA2213404GNPHB0-RAA2213404GNPA
PVCCINFAON_CPU1_VREF     PU51_P1_2        24       RAA2213404GNPHB0-RAA2213404GNPA
PVCCINFAON_CPU1_VR_FAULT PR570            2        Q_RES_0402LF-1K,1%,1/16W,CHIP,A
PVCCINFAON_CPU1_VR_FAULT PU22             33       ISL69260IRAZT-ISL69260IRAZ-T,SA
PVCCIN_CPU0              C101             1        Q_CAP_0805-47UF,4V,20%,X6S,CH6A
PVCCIN_CPU0              C212             1        Q_CAP_0805-47UF,4V,20%,X6S,CH6A
PVCCIN_CPU0              C213             1        Q_CAP_0805-47UF,4V,20%,X6S,CH6A
PVCCIN_CPU0              C214             1        Q_CAP_0805-47UF,4V,20%,X6S,CH6A
PVCCIN_CPU0              C215             1        Q_CAP_0805-47UF,4V,20%,X6S,CH6A
PVCCIN_CPU0              C216             1        Q_CAP_0805-47UF,4V,20%,X6S,CH6A
PVCCIN_CPU0              C217             1        Q_CAP_0805-47UF,4V,20%,X6S,CH6A
PVCCIN_CPU0              C218             1        Q_CAP_0805-47UF,4V,20%,X6S,CH6A
PVCCIN_CPU0              C219             1        Q_CAP_0805-47UF,4V,20%,X6S,CH6A
PVCCIN_CPU0              C220             1        Q_CAP_0805-47UF,4V,20%,X6S,CH6A
PVCCIN_CPU0              C355             1        Q_CAP_C0805-100UF,4V,20%,X6S,CA
PVCCIN_CPU0              C356             1        Q_CAP_C0805-100UF,4V,20%,X6S,CA
PVCCIN_CPU0              C357             1        Q_CAP_C0805-100UF,4V,20%,X6S,CA
PVCCIN_CPU0              C358             1        Q_CAP_C0805-100UF,4V,20%,X6S,CA
PVCCIN_CPU0              C359             1        Q_CAP_C0805-100UF,4V,20%,X6S,CA
PVCCIN_CPU0              C360             1        Q_CAP_C0805-100UF,4V,20%,X6S,CA
PVCCIN_CPU0              C361             1        Q_CAP_C0805-100UF,4V,20%,X6S,CA
PVCCIN_CPU0              C362             1        Q_CAP_C0805-100UF,4V,20%,X6S,CA
PVCCIN_CPU0              C363             1        Q_CAP_C0805-100UF,4V,20%,X6S,CA
PVCCIN_CPU0              C364             1        Q_CAP_C0805-100UF,4V,20%,X6S,CA
PVCCIN_CPU0              C365             1        Q_CAP_C0805-100UF,4V,20%,X6S,CA
PVCCIN_CPU0              C366             1        Q_CAP_C0805-100UF,4V,20%,X6S,CA
PVCCIN_CPU0              C367             1        Q_CAP_C0805-100UF,4V,20%,X6S,CA
PVCCIN_CPU0              C368             1        Q_CAP_C0805-100UF,4V,20%,X6S,CA
PVCCIN_CPU0              C369             1        Q_CAP_C0805-100UF,4V,20%,X6S,CA
PVCCIN_CPU0              C370             1        Q_CAP_C0805-100UF,4V,20%,X6S,CA
PVCCIN_CPU0              C371             1        Q_CAP_C0805-100UF,4V,20%,X6S,CA
PVCCIN_CPU0              C372             1        Q_CAP_C0805-100UF,4V,20%,X6S,CA
PVCCIN_CPU0              C373             1        Q_CAP_C0805-100UF,4V,20%,X6S,CA
PVCCIN_CPU0              C374             1        Q_CAP_C0805-100UF,4V,20%,X6S,CA
PVCCIN_CPU0              C376             1        Q_CAP_C0805-100UF,4V,20%,X6S,CA
PVCCIN_CPU0              C377             1        Q_CAP_C0805-100UF,4V,20%,X6S,CA
PVCCIN_CPU0              C379             1        Q_CAP_C0805-100UF,4V,20%,X6S,CA
PVCCIN_CPU0              C380             1        Q_CAP_C0805-100UF,4V,20%,X6S,CA
PVCCIN_CPU0              C381             1        Q_CAP_C0603-47UF,2.5V,20%,X6S,A
PVCCIN_CPU0              C382             1        Q_CAP_C0805-100UF,4V,20%,X6S,CA
PVCCIN_CPU0              C383             1        Q_CAP_C0805-100UF,4V,20%,X6S,CA
PVCCIN_CPU0              C384             1        Q_CAP_C0603-47UF,2.5V,20%,X6S,A
PVCCIN_CPU0              C385             1        Q_CAP_C0805-100UF,4V,20%,X6S,CA
PVCCIN_CPU0              C386             1        Q_CAP_C0805-100UF,4V,20%,X6S,CA
PVCCIN_CPU0              C387             1        Q_CAP_C0805-100UF,4V,20%,X6S,CA
PVCCIN_CPU0              C388             1        Q_CAP_C0805-100UF,4V,20%,X6S,CA
PVCCIN_CPU0              C389             1        Q_CAP_C0805-100UF,4V,20%,X6S,CA
PVCCIN_CPU0              C390             1        Q_CAP_C0805-100UF,4V,20%,X6S,CA
PVCCIN_CPU0              C391             1        Q_CAP_C0805-100UF,4V,20%,X6S,CA
PVCCIN_CPU0              C392             1        Q_CAP_C0805-100UF,4V,20%,X6S,CA
PVCCIN_CPU0              C393             1        Q_CAP_C0805-100UF,4V,20%,X6S,CA
PVCCIN_CPU0              C394             1        Q_CAP_C0805-100UF,4V,20%,X6S,CA
PVCCIN_CPU0              C396             1        Q_CAP_C0805-100UF,4V,20%,X6S,CA
PVCCIN_CPU0              C397             1        Q_CAP_C0805-100UF,4V,20%,X6S,CA
PVCCIN_CPU0              C398             1        Q_CAP_C0805-100UF,4V,20%,X6S,CA
PVCCIN_CPU0              C524             1        Q_CAP_C0603-47UF,2.5V,20%,X6S,A
PVCCIN_CPU0              C527             1        Q_CAP_C0603-47UF,2.5V,20%,X6S,A
PVCCIN_CPU0              C966             1        Q_CAP_C0402-22UF,4V,20%,X6S,CHA
PVCCIN_CPU0              C967             1        Q_CAP_C0402-22UF,4V,20%,X6S,CHA
PVCCIN_CPU0              C968             1        Q_CAP_C0402-22UF,4V,20%,X6S,CHA
PVCCIN_CPU0              C969             1        Q_CAP_C0402-22UF,4V,20%,X6S,CHA
PVCCIN_CPU0              C970             1        Q_CAP_C0402-22UF,4V,20%,X6S,CHA
PVCCIN_CPU0              C971             1        Q_CAP_C0402-22UF,4V,20%,X6S,CHA
PVCCIN_CPU0              C972             1        Q_CAP_C0402-22UF,4V,20%,X6S,CHA
PVCCIN_CPU0              C973             1        Q_CAP_C0402-22UF,4V,20%,X6S,CHA
PVCCIN_CPU0              C974             1        Q_CAP_C0402-22UF,4V,20%,X6S,CHA
PVCCIN_CPU0              C975             1        Q_CAP_C0402-22UF,4V,20%,X6S,CHA
PVCCIN_CPU0              C976             1        Q_CAP_C0402-22UF,4V,20%,X6S,CHA
PVCCIN_CPU0              C977             1        Q_CAP_C0402-22UF,4V,20%,X6S,CHA
PVCCIN_CPU0              C978             1        Q_CAP_C0402-22UF,4V,20%,X6S,CHA
PVCCIN_CPU0              C979             1        Q_CAP_C0402-22UF,4V,20%,X6S,CHA
PVCCIN_CPU0              C980             1        Q_CAP_C0402-22UF,4V,20%,X6S,CHA
PVCCIN_CPU0              C981             1        Q_CAP_C0402-22UF,4V,20%,X6S,CHA
PVCCIN_CPU0              C982             1        Q_CAP_C0402-22UF,4V,20%,X6S,CHA
PVCCIN_CPU0              C983             1        Q_CAP_C0402-22UF,4V,20%,X6S,CHA
PVCCIN_CPU0              C984             1        Q_CAP_C0402-22UF,4V,20%,X6S,CHA
PVCCIN_CPU0              C985             1        Q_CAP_C0402-22UF,4V,20%,X6S,CHA
PVCCIN_CPU0              C986             1        Q_CAP_C0402-22UF,4V,20%,X6S,CHA
PVCCIN_CPU0              C987             1        Q_CAP_C0402-22UF,4V,20%,X6S,CHA
PVCCIN_CPU0              C988             1        Q_CAP_C0402-22UF,4V,20%,X6S,CHA
PVCCIN_CPU0              C989             1        Q_CAP_C0402-22UF,4V,20%,X6S,CHA
PVCCIN_CPU0              C990             1        Q_CAP_C0402-22UF,4V,20%,X6S,CHA
PVCCIN_CPU0              C991             1        Q_CAP_C0402-22UF,4V,20%,X6S,CHA
PVCCIN_CPU0              C992             1        Q_CAP_C0402-22UF,4V,20%,X6S,CHA
PVCCIN_CPU0              C993             1        Q_CAP_C0402-22UF,4V,20%,X6S,CHA
PVCCIN_CPU0              C994             1        Q_CAP_C0402-22UF,4V,20%,X6S,CHA
PVCCIN_CPU0              C995             1        Q_CAP_C0402-22UF,4V,20%,X6S,CHA
PVCCIN_CPU0              C996             1        Q_CAP_C0402-22UF,4V,20%,X6S,CHA
PVCCIN_CPU0              C997             1        Q_CAP_C0402-22UF,4V,20%,X6S,CHA
PVCCIN_CPU0              C998             1        Q_CAP_C0402-22UF,4V,20%,X6S,CHA
PVCCIN_CPU0              C999             1        Q_CAP_C0402-22UF,4V,20%,X6S,CHA
PVCCIN_CPU0              C1000            1        Q_CAP_C0402-22UF,4V,20%,X6S,CHA
PVCCIN_CPU0              C1001            1        Q_CAP_C0402-22UF,4V,20%,X6S,CHA
PVCCIN_CPU0              C1002            1        Q_CAP_C0402-22UF,4V,20%,X6S,CHA
PVCCIN_CPU0              C1003            1        Q_CAP_C0402-22UF,4V,20%,X6S,CHA
PVCCIN_CPU0              C1004            1        Q_CAP_C0402-22UF,4V,20%,X6S,CHA
PVCCIN_CPU0              C1005            1        Q_CAP_C0402-22UF,4V,20%,X6S,CHA
PVCCIN_CPU0              C1006            1        Q_CAP_C0402-22UF,4V,20%,X6S,CHA
PVCCIN_CPU0              C1007            1        Q_CAP_C0402-22UF,4V,20%,X6S,CHA
PVCCIN_CPU0              C1008            1        Q_CAP_C0402-22UF,4V,20%,X6S,CHA
PVCCIN_CPU0              C1009            1        Q_CAP_C0402-22UF,4V,20%,X6S,CHA
PVCCIN_CPU0              C1010            1        Q_CAP_C0402-22UF,4V,20%,X6S,CHA
PVCCIN_CPU0              C1011            1        Q_CAP_C0402-22UF,4V,20%,X6S,CHA
PVCCIN_CPU0              C1012            1        Q_CAP_C0402-22UF,4V,20%,X6S,CHA
PVCCIN_CPU0              C1013            1        Q_CAP_C0402-22UF,4V,20%,X6S,CHA
PVCCIN_CPU0              C1014            1        Q_CAP_C0402-22UF,4V,20%,X6S,CHA
PVCCIN_CPU0              C1015            1        Q_CAP_C0402-22UF,4V,20%,X6S,CHA
PVCCIN_CPU0              C1016            1        Q_CAP_C0402-22UF,4V,20%,X6S,CHA
PVCCIN_CPU0              C1017            1        Q_CAP_C0402-22UF,4V,20%,X6S,CHA
PVCCIN_CPU0              C1018            1        Q_CAP_C0402-22UF,4V,20%,X6S,CHA
PVCCIN_CPU0              C1019            1        Q_CAP_C0402-22UF,4V,20%,X6S,CHA
PVCCIN_CPU0              C1020            1        Q_CAP_C0402-22UF,4V,20%,X6S,CHA
PVCCIN_CPU0              C1021            1        Q_CAP_C0402-22UF,4V,20%,X6S,CHA
PVCCIN_CPU0              C1022            1        Q_CAP_C0402-22UF,4V,20%,X6S,CHA
PVCCIN_CPU0              C1023            1        Q_CAP_C0402-22UF,4V,20%,X6S,CHA
PVCCIN_CPU0              C1024            1        Q_CAP_C0402-22UF,4V,20%,X6S,CHA
PVCCIN_CPU0              C1025            1        Q_CAP_C0402-22UF,4V,20%,X6S,CHA
PVCCIN_CPU0              C1026            1        Q_CAP_C0402-22UF,4V,20%,X6S,CHA
PVCCIN_CPU0              C1027            1        Q_CAP_C0402-22UF,4V,20%,X6S,CHA
PVCCIN_CPU0              C1028            1        Q_CAP_C0402-22UF,4V,20%,X6S,CHA
PVCCIN_CPU0              C1029            1        Q_CAP_C0402-22UF,4V,20%,X6S,CHA
PVCCIN_CPU0              C1030            1        Q_CAP_C0402-22UF,4V,20%,X6S,CHA
PVCCIN_CPU0              C1031            1        Q_CAP_C0402-22UF,4V,20%,X6S,CHA
PVCCIN_CPU0              C1032            1        Q_CAP_C0402-22UF,4V,20%,X6S,CHA
PVCCIN_CPU0              C1033            1        Q_CAP_C0402-22UF,4V,20%,X6S,CHA
PVCCIN_CPU0              C1034            1        Q_CAP_C0402-22UF,4V,20%,X6S,CHA
PVCCIN_CPU0              C1035            1        Q_CAP_C0402-22UF,4V,20%,X6S,CHA
PVCCIN_CPU0              C1036            1        Q_CAP_C0402-22UF,4V,20%,X6S,CHA
PVCCIN_CPU0              C1037            1        Q_CAP_C0402-22UF,4V,20%,X6S,CHA
PVCCIN_CPU0              C1038            1        Q_CAP_C0402-22UF,4V,20%,X6S,CHA
PVCCIN_CPU0              C1039            1        Q_CAP_C0402-22UF,4V,20%,X6S,CHA
PVCCIN_CPU0              C1040            1        Q_CAP_C0402-22UF,4V,20%,X6S,CHA
PVCCIN_CPU0              C1041            1        Q_CAP_C0402-22UF,4V,20%,X6S,CHA
PVCCIN_CPU0              C1043            1        Q_CAP_C0402-22UF,4V,20%,X6S,CHA
PVCCIN_CPU0              C1044            1        Q_CAP_C0402-22UF,4V,20%,X6S,CHA
PVCCIN_CPU0              C1045            1        Q_CAP_C0402-22UF,4V,20%,X6S,CHA
PVCCIN_CPU0              PC16             1        Q_CAPP_THLF-560UF,2.5V,20%,OSCA
PVCCIN_CPU0              PC1920           1        Q_CAPP_SMLF-470UF,2.5V,20%,EMPA
PVCCIN_CPU0              PC2336           1        Q_CAPP_SMLF-470UF,2.5V,20%,EMPA
PVCCIN_CPU0              PC242_P0_8       1        Q_CAP_C0402-1UF,16V,10%,X6S,CHA
PVCCIN_CPU0              PC243_P0_7       1        Q_CAP_C0402-1UF,16V,10%,X6S,CHA
PVCCIN_CPU0              PC244_P0_8       1        Q_CAP_0805-22UF,4V,20%,X6S,TMPA
PVCCIN_CPU0              PC245_P0_7       1        Q_CAP_0805-22UF,4V,20%,X6S,TMPA
PVCCIN_CPU0              PC246_P0_8       1        Q_CAP_0805-22UF,4V,20%,X6S,TMPA
PVCCIN_CPU0              PC247_P0_7       1        Q_CAP_0805-22UF,4V,20%,X6S,TMPA
PVCCIN_CPU0              PC266_P0_6       1        Q_CAP_0805-22UF,4V,20%,X6S,TMPA
PVCCIN_CPU0              PC267_P0_5       1        Q_CAP_0805-22UF,4V,20%,X6S,TMPA
PVCCIN_CPU0              PC268_P0_6       1        Q_CAP_0805-22UF,4V,20%,X6S,TMPA
PVCCIN_CPU0              PC269_P0_5       1        Q_CAP_0805-22UF,4V,20%,X6S,TMPA
PVCCIN_CPU0              PC288_P0_4       1        Q_CAP_0805-22UF,4V,20%,X6S,TMPA
PVCCIN_CPU0              PC289_P0_3       1        Q_CAP_0805-22UF,4V,20%,X6S,TMPA
PVCCIN_CPU0              PC290_P0_4       1        Q_CAP_0805-22UF,4V,20%,X6S,TMPA
PVCCIN_CPU0              PC291_P0_3       1        Q_CAP_0805-22UF,4V,20%,X6S,TMPA
PVCCIN_CPU0              PC308_P0_1       1        Q_CAP_C0402-100NF,50V,10%,X7R,A
PVCCIN_CPU0              PC310_P0_1       1        Q_CAP_C0402-1UF,16V,10%,X6S,CHA
PVCCIN_CPU0              PC311_P0_2       1        Q_CAP_0805-22UF,4V,20%,X6S,TMPA
PVCCIN_CPU0              PC312_P0_1       1        Q_CAP_0805-22UF,4V,20%,X6S,TMPA
PVCCIN_CPU0              PC313_P0_2       1        Q_CAP_0805-22UF,4V,20%,X6S,TMPA
PVCCIN_CPU0              PC314_P0_1       1        Q_CAP_0805-22UF,4V,20%,X6S,TMPA
PVCCIN_CPU0              PC316            1        Q_CAPP_THLF-560UF,2.5V,20%,OSCA
PVCCIN_CPU0              PC319            1        Q_CAPP_THLF-560UF,2.5V,20%,OSCA
PVCCIN_CPU0              PC322            1        Q_CAPP_THLF-560UF,2.5V,20%,OSCA
PVCCIN_CPU0              PC323            1        Q_CAPP_SMLF-470UF,2.5V,20%,EMPA
PVCCIN_CPU0              PC325            1        Q_CAPP_THLF-560UF,2.5V,20%,OSCA
PVCCIN_CPU0              PC326            1        Q_CAPP_SMLF-470UF,2.5V,20%,EMPA
PVCCIN_CPU0              PL7              4        Q_INDUCTOR4P_14-150NH,SMLF,INDA
PVCCIN_CPU0              PL8              4        Q_INDUCTOR4P_14-150NH,SMLF,INDA
PVCCIN_CPU0              PL9              4        Q_INDUCTOR4P_14-150NH,SMLF,INDA
PVCCIN_CPU0              PL10             4        Q_INDUCTOR4P_14-150NH,SMLF,INDA
PVCCIN_CPU0              PL11             4        Q_INDUCTOR4P_14-150NH,SMLF,INDA
PVCCIN_CPU0              PL13             4        Q_INDUCTOR4P_14-150NH,SMLF,INDA
PVCCIN_CPU0              PL112            4        Q_INDUCTOR4P_14-150NH,SMLF,INDA
PVCCIN_CPU0              PL114            4        Q_INDUCTOR4P_14-150NH,SMLF,INDA
PVCCIN_CPU0              PR136            2        Q_RES_0402LF-0,5%,1/16W,CHIP,CA
PVCCIN_CPU0              PR137            2        Q_RES_0402LF-0,5%,1/16W,CHIP,CA
PVCCIN_CPU0              PR142            2        Q_RES_0402LF-0,5%,1/16W,CHIP,CA
PVCCIN_CPU0              PR143            2        Q_RES_0402LF-0,5%,1/16W,CHIP,CA
PVCCIN_CPU0              PR148            2        Q_RES_0402LF-0,5%,1/16W,CHIP,CA
PVCCIN_CPU0              PR149            2        Q_RES_0402LF-0,5%,1/16W,CHIP,CA
PVCCIN_CPU0              PR154            2        Q_RES_0402LF-0,5%,1/16W,CHIP,CA
PVCCIN_CPU0              PR155            2        Q_RES_0402LF-0,5%,1/16W,CHIP,CA
PVCCIN_CPU0              PR531            2        Q_RES_0402LF-100,1%,1/16W,CHIPA
PVCCIN_CPU0              U2               BD91     SOCKET4677_AZIFS054P001C01-SOCA
PVCCIN_CPU0              U2               BE86     SOCKET4677_AZIFS054P001C01-SOCA
PVCCIN_CPU0              U2               BE88     SOCKET4677_AZIFS054P001C01-SOCA
PVCCIN_CPU0              U2               BE90     SOCKET4677_AZIFS054P001C01-SOCA
PVCCIN_CPU0              U2               BF85     SOCKET4677_AZIFS054P001C01-SOCA
PVCCIN_CPU0              U2               BF87     SOCKET4677_AZIFS054P001C01-SOCA
PVCCIN_CPU0              U2               BF89     SOCKET4677_AZIFS054P001C01-SOCA
PVCCIN_CPU0              U2               BF91     SOCKET4677_AZIFS054P001C01-SOCA
PVCCIN_CPU0              U2               BG84     SOCKET4677_AZIFS054P001C01-SOCA
PVCCIN_CPU0              U2               BG86     SOCKET4677_AZIFS054P001C01-SOCA
PVCCIN_CPU0              U2               BG88     SOCKET4677_AZIFS054P001C01-SOCA
PVCCIN_CPU0              U2               BG90     SOCKET4677_AZIFS054P001C01-SOCA
PVCCIN_CPU0              U2               BH85     SOCKET4677_AZIFS054P001C01-SOCA
PVCCIN_CPU0              U2               BH87     SOCKET4677_AZIFS054P001C01-SOCA
PVCCIN_CPU0              U2               BH89     SOCKET4677_AZIFS054P001C01-SOCA
PVCCIN_CPU0              U2               BH91     SOCKET4677_AZIFS054P001C01-SOCA
PVCCIN_CPU0              U2               BK81     SOCKET4677_AZIFS054P001C01-SOCA
PVCCIN_CPU0              U2               BK83     SOCKET4677_AZIFS054P001C01-SOCA
PVCCIN_CPU0              U2               BK85     SOCKET4677_AZIFS054P001C01-SOCA
PVCCIN_CPU0              U2               BK87     SOCKET4677_AZIFS054P001C01-SOCA
PVCCIN_CPU0              U2               BK89     SOCKET4677_AZIFS054P001C01-SOCA
PVCCIN_CPU0              U2               BK91     SOCKET4677_AZIFS054P001C01-SOCA
PVCCIN_CPU0              U2               BL80     SOCKET4677_AZIFS054P001C01-SOCA
PVCCIN_CPU0              U2               BL82     SOCKET4677_AZIFS054P001C01-SOCA
PVCCIN_CPU0              U2               BL84     SOCKET4677_AZIFS054P001C01-SOCA
PVCCIN_CPU0              U2               BL86     SOCKET4677_AZIFS054P001C01-SOCA
PVCCIN_CPU0              U2               BL88     SOCKET4677_AZIFS054P001C01-SOCA
PVCCIN_CPU0              U2               BL90     SOCKET4677_AZIFS054P001C01-SOCA
PVCCIN_CPU0              U2               BM79     SOCKET4677_AZIFS054P001C01-SOCA
PVCCIN_CPU0              U2               BM81     SOCKET4677_AZIFS054P001C01-SOCA
PVCCIN_CPU0              U2               BM83     SOCKET4677_AZIFS054P001C01-SOCA
PVCCIN_CPU0              U2               BM85     SOCKET4677_AZIFS054P001C01-SOCA
PVCCIN_CPU0              U2               BM87     SOCKET4677_AZIFS054P001C01-SOCA
PVCCIN_CPU0              U2               BM89     SOCKET4677_AZIFS054P001C01-SOCA
PVCCIN_CPU0              U2               BM91     SOCKET4677_AZIFS054P001C01-SOCA
PVCCIN_CPU0              U2               BN33     SOCKET4677_AZIFS054P001C01-SOCA
PVCCIN_CPU0              U2               BN35     SOCKET4677_AZIFS054P001C01-SOCA
PVCCIN_CPU0              U2               BN37     SOCKET4677_AZIFS054P001C01-SOCA
PVCCIN_CPU0              U2               BN39     SOCKET4677_AZIFS054P001C01-SOCA
PVCCIN_CPU0              U2               BN41     SOCKET4677_AZIFS054P001C01-SOCA
PVCCIN_CPU0              U2               BN43     SOCKET4677_AZIFS054P001C01-SOCA
PVCCIN_CPU0              U2               BN45     SOCKET4677_AZIFS054P001C01-SOCA
PVCCIN_CPU0              U2               BN48     SOCKET4677_AZIFS054P001C01-SOCA
PVCCIN_CPU0              U2               BN50     SOCKET4677_AZIFS054P001C01-SOCA
PVCCIN_CPU0              U2               BN52     SOCKET4677_AZIFS054P001C01-SOCA
PVCCIN_CPU0              U2               BN54     SOCKET4677_AZIFS054P001C01-SOCA
PVCCIN_CPU0              U2               BN56     SOCKET4677_AZIFS054P001C01-SOCA
PVCCIN_CPU0              U2               BN58     SOCKET4677_AZIFS054P001C01-SOCA
PVCCIN_CPU0              U2               BN60     SOCKET4677_AZIFS054P001C01-SOCA
PVCCIN_CPU0              U2               BN78     SOCKET4677_AZIFS054P001C01-SOCA
PVCCIN_CPU0              U2               BN80     SOCKET4677_AZIFS054P001C01-SOCA
PVCCIN_CPU0              U2               BN82     SOCKET4677_AZIFS054P001C01-SOCA
PVCCIN_CPU0              U2               BN84     SOCKET4677_AZIFS054P001C01-SOCA
PVCCIN_CPU0              U2               BN86     SOCKET4677_AZIFS054P001C01-SOCA
PVCCIN_CPU0              U2               BN88     SOCKET4677_AZIFS054P001C01-SOCA
PVCCIN_CPU0              U2               BN90     SOCKET4677_AZIFS054P001C01-SOCA
PVCCIN_CPU0              U2               BP32     SOCKET4677_AZIFS054P001C01-SOCA
PVCCIN_CPU0              U2               BP34     SOCKET4677_AZIFS054P001C01-SOCA
PVCCIN_CPU0              U2               BP36     SOCKET4677_AZIFS054P001C01-SOCA
PVCCIN_CPU0              U2               BP38     SOCKET4677_AZIFS054P001C01-SOCA
PVCCIN_CPU0              U2               BP40     SOCKET4677_AZIFS054P001C01-SOCA
PVCCIN_CPU0              U2               BP42     SOCKET4677_AZIFS054P001C01-SOCA
PVCCIN_CPU0              U2               BP44     SOCKET4677_AZIFS054P001C01-SOCA
PVCCIN_CPU0              U2               BP47     SOCKET4677_AZIFS054P001C01-SOCA
PVCCIN_CPU0              U2               BP49     SOCKET4677_AZIFS054P001C01-SOCA
PVCCIN_CPU0              U2               BP51     SOCKET4677_AZIFS054P001C01-SOCA
PVCCIN_CPU0              U2               BP53     SOCKET4677_AZIFS054P001C01-SOCA
PVCCIN_CPU0              U2               BP55     SOCKET4677_AZIFS054P001C01-SOCA
PVCCIN_CPU0              U2               BP57     SOCKET4677_AZIFS054P001C01-SOCA
PVCCIN_CPU0              U2               BP59     SOCKET4677_AZIFS054P001C01-SOCA
PVCCIN_CPU0              U2               BP61     SOCKET4677_AZIFS054P001C01-SOCA
PVCCIN_CPU0              U2               BP79     SOCKET4677_AZIFS054P001C01-SOCA
PVCCIN_CPU0              U2               BP81     SOCKET4677_AZIFS054P001C01-SOCA
PVCCIN_CPU0              U2               BP83     SOCKET4677_AZIFS054P001C01-SOCA
PVCCIN_CPU0              U2               BP85     SOCKET4677_AZIFS054P001C01-SOCA
PVCCIN_CPU0              U2               BP87     SOCKET4677_AZIFS054P001C01-SOCA
PVCCIN_CPU0              U2               BP89     SOCKET4677_AZIFS054P001C01-SOCA
PVCCIN_CPU0              U2               BR60     SOCKET4677_AZIFS054P001C01-SOCA
PVCCIN_CPU0              U2               BR62     SOCKET4677_AZIFS054P001C01-SOCA
PVCCIN_CPU0              U2               BR78     SOCKET4677_AZIFS054P001C01-SOCA
PVCCIN_CPU0              U2               BT32     SOCKET4677_AZIFS054P001C01-SOCA
PVCCIN_CPU0              U2               BT34     SOCKET4677_AZIFS054P001C01-SOCA
PVCCIN_CPU0              U2               BT36     SOCKET4677_AZIFS054P001C01-SOCA
PVCCIN_CPU0              U2               BT38     SOCKET4677_AZIFS054P001C01-SOCA
PVCCIN_CPU0              U2               BT40     SOCKET4677_AZIFS054P001C01-SOCA
PVCCIN_CPU0              U2               BT42     SOCKET4677_AZIFS054P001C01-SOCA
PVCCIN_CPU0              U2               BT44     SOCKET4677_AZIFS054P001C01-SOCA
PVCCIN_CPU0              U2               BT47     SOCKET4677_AZIFS054P001C01-SOCA
PVCCIN_CPU0              U2               BT49     SOCKET4677_AZIFS054P001C01-SOCA
PVCCIN_CPU0              U2               BT51     SOCKET4677_AZIFS054P001C01-SOCA
PVCCIN_CPU0              U2               BT53     SOCKET4677_AZIFS054P001C01-SOCA
PVCCIN_CPU0              U2               BT55     SOCKET4677_AZIFS054P001C01-SOCA
PVCCIN_CPU0              U2               BT57     SOCKET4677_AZIFS054P001C01-SOCA
PVCCIN_CPU0              U2               BT59     SOCKET4677_AZIFS054P001C01-SOCA
PVCCIN_CPU0              U2               BT61     SOCKET4677_AZIFS054P001C01-SOCA
PVCCIN_CPU0              U2               BT63     SOCKET4677_AZIFS054P001C01-SOCA
PVCCIN_CPU0              U2               BT65     SOCKET4677_AZIFS054P001C01-SOCA
PVCCIN_CPU0              U2               BT67     SOCKET4677_AZIFS054P001C01-SOCA
PVCCIN_CPU0              U2               BT69     SOCKET4677_AZIFS054P001C01-SOCA
PVCCIN_CPU0              U2               BT71     SOCKET4677_AZIFS054P001C01-SOCA
PVCCIN_CPU0              U2               BT73     SOCKET4677_AZIFS054P001C01-SOCA
PVCCIN_CPU0              U2               BT75     SOCKET4677_AZIFS054P001C01-SOCA
PVCCIN_CPU0              U2               BT77     SOCKET4677_AZIFS054P001C01-SOCA
PVCCIN_CPU0              U2               BT79     SOCKET4677_AZIFS054P001C01-SOCA
PVCCIN_CPU0              U2               BT81     SOCKET4677_AZIFS054P001C01-SOCA
PVCCIN_CPU0              U2               BT83     SOCKET4677_AZIFS054P001C01-SOCA
PVCCIN_CPU0              U2               BT85     SOCKET4677_AZIFS054P001C01-SOCA
PVCCIN_CPU0              U2               BT87     SOCKET4677_AZIFS054P001C01-SOCA
PVCCIN_CPU0              U2               BT89     SOCKET4677_AZIFS054P001C01-SOCA
PVCCIN_CPU0              U2               BU33     SOCKET4677_AZIFS054P001C01-SOCA
PVCCIN_CPU0              U2               BU35     SOCKET4677_AZIFS054P001C01-SOCA
PVCCIN_CPU0              U2               BU37     SOCKET4677_AZIFS054P001C01-SOCA
PVCCIN_CPU0              U2               BU39     SOCKET4677_AZIFS054P001C01-SOCA
PVCCIN_CPU0              U2               BU41     SOCKET4677_AZIFS054P001C01-SOCA
PVCCIN_CPU0              U2               BU43     SOCKET4677_AZIFS054P001C01-SOCA
PVCCIN_CPU0              U2               BU45     SOCKET4677_AZIFS054P001C01-SOCA
PVCCIN_CPU0              U2               BU48     SOCKET4677_AZIFS054P001C01-SOCA
PVCCIN_CPU0              U2               BU50     SOCKET4677_AZIFS054P001C01-SOCA
PVCCIN_CPU0              U2               BU52     SOCKET4677_AZIFS054P001C01-SOCA
PVCCIN_CPU0              U2               BU54     SOCKET4677_AZIFS054P001C01-SOCA
PVCCIN_CPU0              U2               BU56     SOCKET4677_AZIFS054P001C01-SOCA
PVCCIN_CPU0              U2               BU58     SOCKET4677_AZIFS054P001C01-SOCA
PVCCIN_CPU0              U2               BU60     SOCKET4677_AZIFS054P001C01-SOCA
PVCCIN_CPU0              U2               BU62     SOCKET4677_AZIFS054P001C01-SOCA
PVCCIN_CPU0              U2               BU64     SOCKET4677_AZIFS054P001C01-SOCA
PVCCIN_CPU0              U2               BU66     SOCKET4677_AZIFS054P001C01-SOCA
PVCCIN_CPU0              U2               BU68     SOCKET4677_AZIFS054P001C01-SOCA
PVCCIN_CPU0              U2               BU70     SOCKET4677_AZIFS054P001C01-SOCA
PVCCIN_CPU0              U2               BU72     SOCKET4677_AZIFS054P001C01-SOCA
PVCCIN_CPU0              U2               BU74     SOCKET4677_AZIFS054P001C01-SOCA
PVCCIN_CPU0              U2               BU76     SOCKET4677_AZIFS054P001C01-SOCA
PVCCIN_CPU0              U2               BU78     SOCKET4677_AZIFS054P001C01-SOCA
PVCCIN_CPU0              U2               BU80     SOCKET4677_AZIFS054P001C01-SOCA
PVCCIN_CPU0              U2               BU82     SOCKET4677_AZIFS054P001C01-SOCA
PVCCIN_CPU0              U2               BU84     SOCKET4677_AZIFS054P001C01-SOCA
PVCCIN_CPU0              U2               BU86     SOCKET4677_AZIFS054P001C01-SOCA
PVCCIN_CPU0              U2               BU88     SOCKET4677_AZIFS054P001C01-SOCA
PVCCIN_CPU0              U2               BU90     SOCKET4677_AZIFS054P001C01-SOCA
PVCCIN_CPU0              U2               BV32     SOCKET4677_AZIFS054P001C01-SOCA
PVCCIN_CPU0              U2               BV34     SOCKET4677_AZIFS054P001C01-SOCA
PVCCIN_CPU0              U2               BV36     SOCKET4677_AZIFS054P001C01-SOCA
PVCCIN_CPU0              U2               BV38     SOCKET4677_AZIFS054P001C01-SOCA
PVCCIN_CPU0              U2               BV40     SOCKET4677_AZIFS054P001C01-SOCA
PVCCIN_CPU0              U2               BV42     SOCKET4677_AZIFS054P001C01-SOCA
PVCCIN_CPU0              U2               BV44     SOCKET4677_AZIFS054P001C01-SOCA
PVCCIN_CPU0              U2               BV47     SOCKET4677_AZIFS054P001C01-SOCA
PVCCIN_CPU0              U2               BV49     SOCKET4677_AZIFS054P001C01-SOCA
PVCCIN_CPU0              U2               BV51     SOCKET4677_AZIFS054P001C01-SOCA
PVCCIN_CPU0              U2               BV53     SOCKET4677_AZIFS054P001C01-SOCA
PVCCIN_CPU0              U2               BV55     SOCKET4677_AZIFS054P001C01-SOCA
PVCCIN_CPU0              U2               BV57     SOCKET4677_AZIFS054P001C01-SOCA
PVCCIN_CPU0              U2               BV59     SOCKET4677_AZIFS054P001C01-SOCA
PVCCIN_CPU0              U2               BV61     SOCKET4677_AZIFS054P001C01-SOCA
PVCCIN_CPU0              U2               BV63     SOCKET4677_AZIFS054P001C01-SOCA
PVCCIN_CPU0              U2               BV65     SOCKET4677_AZIFS054P001C01-SOCA
PVCCIN_CPU0              U2               BV67     SOCKET4677_AZIFS054P001C01-SOCA
PVCCIN_CPU0              U2               BV69     SOCKET4677_AZIFS054P001C01-SOCA
PVCCIN_CPU0              U2               BV71     SOCKET4677_AZIFS054P001C01-SOCA
PVCCIN_CPU0              U2               BV73     SOCKET4677_AZIFS054P001C01-SOCA
PVCCIN_CPU0              U2               BV75     SOCKET4677_AZIFS054P001C01-SOCA
PVCCIN_CPU0              U2               BV77     SOCKET4677_AZIFS054P001C01-SOCA
PVCCIN_CPU0              U2               BV79     SOCKET4677_AZIFS054P001C01-SOCA
PVCCIN_CPU0              U2               BV81     SOCKET4677_AZIFS054P001C01-SOCA
PVCCIN_CPU0              U2               BV83     SOCKET4677_AZIFS054P001C01-SOCA
PVCCIN_CPU0              U2               BV85     SOCKET4677_AZIFS054P001C01-SOCA
PVCCIN_CPU0              U2               BV87     SOCKET4677_AZIFS054P001C01-SOCA
PVCCIN_CPU0              U2               BV89     SOCKET4677_AZIFS054P001C01-SOCA
PVCCIN_CPU0              U2               BW33     SOCKET4677_AZIFS054P001C01-SOCA
PVCCIN_CPU0              U2               BW35     SOCKET4677_AZIFS054P001C01-SOCA
PVCCIN_CPU0              U2               BW37     SOCKET4677_AZIFS054P001C01-SOCA
PVCCIN_CPU0              U2               BW39     SOCKET4677_AZIFS054P001C01-SOCA
PVCCIN_CPU0              U2               BW41     SOCKET4677_AZIFS054P001C01-SOCA
PVCCIN_CPU0              U2               BW43     SOCKET4677_AZIFS054P001C01-SOCA
PVCCIN_CPU0              U2               BW45     SOCKET4677_AZIFS054P001C01-SOCA
PVCCIN_CPU0              U2               BW48     SOCKET4677_AZIFS054P001C01-SOCA
PVCCIN_CPU0              U2               BW50     SOCKET4677_AZIFS054P001C01-SOCA
PVCCIN_CPU0              U2               BW52     SOCKET4677_AZIFS054P001C01-SOCA
PVCCIN_CPU0              U2               BW54     SOCKET4677_AZIFS054P001C01-SOCA
PVCCIN_CPU0              U2               BW56     SOCKET4677_AZIFS054P001C01-SOCA
PVCCIN_CPU0              U2               BW58     SOCKET4677_AZIFS054P001C01-SOCA
PVCCIN_CPU0              U2               BW60     SOCKET4677_AZIFS054P001C01-SOCA
PVCCIN_CPU0              U2               BW62     SOCKET4677_AZIFS054P001C01-SOCA
PVCCIN_CPU0              U2               BW64     SOCKET4677_AZIFS054P001C01-SOCA
PVCCIN_CPU0              U2               BW66     SOCKET4677_AZIFS054P001C01-SOCA
PVCCIN_CPU0              U2               BW68     SOCKET4677_AZIFS054P001C01-SOCA
PVCCIN_CPU0              U2               BW70     SOCKET4677_AZIFS054P001C01-SOCA
PVCCIN_CPU0              U2               BW72     SOCKET4677_AZIFS054P001C01-SOCA
PVCCIN_CPU0              U2               BW74     SOCKET4677_AZIFS054P001C01-SOCA
PVCCIN_CPU0              U2               BW76     SOCKET4677_AZIFS054P001C01-SOCA
PVCCIN_CPU0              U2               BW78     SOCKET4677_AZIFS054P001C01-SOCA
PVCCIN_CPU0              U2               BW80     SOCKET4677_AZIFS054P001C01-SOCA
PVCCIN_CPU0              U2               BW82     SOCKET4677_AZIFS054P001C01-SOCA
PVCCIN_CPU0              U2               BW84     SOCKET4677_AZIFS054P001C01-SOCA
PVCCIN_CPU0              U2               BW86     SOCKET4677_AZIFS054P001C01-SOCA
PVCCIN_CPU0              U2               BW88     SOCKET4677_AZIFS054P001C01-SOCA
PVCCIN_CPU0              U2               BW90     SOCKET4677_AZIFS054P001C01-SOCA
PVCCIN_CPU0              U2               BY32     SOCKET4677_AZIFS054P001C01-SOCA
PVCCIN_CPU0              U2               BY34     SOCKET4677_AZIFS054P001C01-SOCA
PVCCIN_CPU0              U2               BY36     SOCKET4677_AZIFS054P001C01-SOCA
PVCCIN_CPU0              U2               BY38     SOCKET4677_AZIFS054P001C01-SOCA
PVCCIN_CPU0              U2               BY40     SOCKET4677_AZIFS054P001C01-SOCA
PVCCIN_CPU0              U2               BY42     SOCKET4677_AZIFS054P001C01-SOCA
PVCCIN_CPU0              U2               BY44     SOCKET4677_AZIFS054P001C01-SOCA
PVCCIN_CPU0              U2               BY47     SOCKET4677_AZIFS054P001C01-SOCA
PVCCIN_CPU0              U2               BY49     SOCKET4677_AZIFS054P001C01-SOCA
PVCCIN_CPU0              U2               BY51     SOCKET4677_AZIFS054P001C01-SOCA
PVCCIN_CPU0              U2               BY53     SOCKET4677_AZIFS054P001C01-SOCA
PVCCIN_CPU0              U2               BY55     SOCKET4677_AZIFS054P001C01-SOCA
PVCCIN_CPU0              U2               BY57     SOCKET4677_AZIFS054P001C01-SOCA
PVCCIN_CPU0              U2               BY59     SOCKET4677_AZIFS054P001C01-SOCA
PVCCIN_CPU0              U2               BY61     SOCKET4677_AZIFS054P001C01-SOCA
PVCCIN_CPU0              U2               BY63     SOCKET4677_AZIFS054P001C01-SOCA
PVCCIN_CPU0              U2               BY65     SOCKET4677_AZIFS054P001C01-SOCA
PVCCIN_CPU0              U2               BY67     SOCKET4677_AZIFS054P001C01-SOCA
PVCCIN_CPU0              U2               BY69     SOCKET4677_AZIFS054P001C01-SOCA
PVCCIN_CPU0              U2               BY71     SOCKET4677_AZIFS054P001C01-SOCA
PVCCIN_CPU0              U2               BY73     SOCKET4677_AZIFS054P001C01-SOCA
PVCCIN_CPU0              U2               BY75     SOCKET4677_AZIFS054P001C01-SOCA
PVCCIN_CPU0              U2               BY77     SOCKET4677_AZIFS054P001C01-SOCA
PVCCIN_CPU0              U2               BY79     SOCKET4677_AZIFS054P001C01-SOCA
PVCCIN_CPU0              U2               BY81     SOCKET4677_AZIFS054P001C01-SOCA
PVCCIN_CPU0              U2               BY83     SOCKET4677_AZIFS054P001C01-SOCA
PVCCIN_CPU0              U2               BY85     SOCKET4677_AZIFS054P001C01-SOCA
PVCCIN_CPU0              U2               BY87     SOCKET4677_AZIFS054P001C01-SOCA
PVCCIN_CPU0              U2               BY89     SOCKET4677_AZIFS054P001C01-SOCA
PVCCIN_CPU0              U2               CA33     SOCKET4677_AZIFS054P001C01-SOCA
PVCCIN_CPU0              U2               CA35     SOCKET4677_AZIFS054P001C01-SOCA
PVCCIN_CPU0              U2               CA37     SOCKET4677_AZIFS054P001C01-SOCA
PVCCIN_CPU0              U2               CA39     SOCKET4677_AZIFS054P001C01-SOCA
PVCCIN_CPU0              U2               CA41     SOCKET4677_AZIFS054P001C01-SOCA
PVCCIN_CPU0              U2               CA43     SOCKET4677_AZIFS054P001C01-SOCA
PVCCIN_CPU0              U2               CA45     SOCKET4677_AZIFS054P001C01-SOCA
PVCCIN_CPU0              U2               CA48     SOCKET4677_AZIFS054P001C01-SOCA
PVCCIN_CPU0              U2               CA50     SOCKET4677_AZIFS054P001C01-SOCA
PVCCIN_CPU0              U2               CA52     SOCKET4677_AZIFS054P001C01-SOCA
PVCCIN_CPU0              U2               CA54     SOCKET4677_AZIFS054P001C01-SOCA
PVCCIN_CPU0              U2               CA56     SOCKET4677_AZIFS054P001C01-SOCA
PVCCIN_CPU0              U2               CA58     SOCKET4677_AZIFS054P001C01-SOCA
PVCCIN_CPU0              U2               CA60     SOCKET4677_AZIFS054P001C01-SOCA
PVCCIN_CPU0              U2               CA62     SOCKET4677_AZIFS054P001C01-SOCA
PVCCIN_CPU0              U2               CA64     SOCKET4677_AZIFS054P001C01-SOCA
PVCCIN_CPU0              U2               CA66     SOCKET4677_AZIFS054P001C01-SOCA
PVCCIN_CPU0              U2               CA68     SOCKET4677_AZIFS054P001C01-SOCA
PVCCIN_CPU0              U2               CA70     SOCKET4677_AZIFS054P001C01-SOCA
PVCCIN_CPU0              U2               CA72     SOCKET4677_AZIFS054P001C01-SOCA
PVCCIN_CPU0              U2               CA74     SOCKET4677_AZIFS054P001C01-SOCA
PVCCIN_CPU0              U2               CA76     SOCKET4677_AZIFS054P001C01-SOCA
PVCCIN_CPU0              U2               CA78     SOCKET4677_AZIFS054P001C01-SOCA
PVCCIN_CPU0              U2               CA80     SOCKET4677_AZIFS054P001C01-SOCA
PVCCIN_CPU0              U2               CA82     SOCKET4677_AZIFS054P001C01-SOCA
PVCCIN_CPU0              U2               CA84     SOCKET4677_AZIFS054P001C01-SOCA
PVCCIN_CPU0              U2               CA86     SOCKET4677_AZIFS054P001C01-SOCA
PVCCIN_CPU0              U2               CA88     SOCKET4677_AZIFS054P001C01-SOCA
PVCCIN_CPU0              U2               CA90     SOCKET4677_AZIFS054P001C01-SOCA
PVCCIN_CPU0              U2               CB61     SOCKET4677_AZIFS054P001C01-SOCA
PVCCIN_CPU0              U2               CB75     SOCKET4677_AZIFS054P001C01-SOCA
PVCCIN_CPU0              U2               CB77     SOCKET4677_AZIFS054P001C01-SOCA
PVCCIN_CPU0              U2               CC33     SOCKET4677_AZIFS054P001C01-SOCA
PVCCIN_CPU0              U2               CC35     SOCKET4677_AZIFS054P001C01-SOCA
PVCCIN_CPU0              U2               CC37     SOCKET4677_AZIFS054P001C01-SOCA
PVCCIN_CPU0              U2               CC39     SOCKET4677_AZIFS054P001C01-SOCA
PVCCIN_CPU0              U2               CC41     SOCKET4677_AZIFS054P001C01-SOCA
PVCCIN_CPU0              U2               CC43     SOCKET4677_AZIFS054P001C01-SOCA
PVCCIN_CPU0              U2               CC45     SOCKET4677_AZIFS054P001C01-SOCA
PVCCIN_CPU0              U2               CC48     SOCKET4677_AZIFS054P001C01-SOCA
PVCCIN_CPU0              U2               CC50     SOCKET4677_AZIFS054P001C01-SOCA
PVCCIN_CPU0              U2               CC52     SOCKET4677_AZIFS054P001C01-SOCA
PVCCIN_CPU0              U2               CC54     SOCKET4677_AZIFS054P001C01-SOCA
PVCCIN_CPU0              U2               CC56     SOCKET4677_AZIFS054P001C01-SOCA
PVCCIN_CPU0              U2               CC58     SOCKET4677_AZIFS054P001C01-SOCA
PVCCIN_CPU0              U2               CC60     SOCKET4677_AZIFS054P001C01-SOCA
PVCCIN_CPU0              U2               CC76     SOCKET4677_AZIFS054P001C01-SOCA
PVCCIN_CPU0              U2               CC78     SOCKET4677_AZIFS054P001C01-SOCA
PVCCIN_CPU0              U2               CC80     SOCKET4677_AZIFS054P001C01-SOCA
PVCCIN_CPU0              U2               CC82     SOCKET4677_AZIFS054P001C01-SOCA
PVCCIN_CPU0              U2               CC84     SOCKET4677_AZIFS054P001C01-SOCA
PVCCIN_CPU0              U2               CC86     SOCKET4677_AZIFS054P001C01-SOCA
PVCCIN_CPU0              U2               CC88     SOCKET4677_AZIFS054P001C01-SOCA
PVCCIN_CPU0              U2               CC90     SOCKET4677_AZIFS054P001C01-SOCA
PVCCIN_CPU0              U2               CD32     SOCKET4677_AZIFS054P001C01-SOCA
PVCCIN_CPU0              U2               CD34     SOCKET4677_AZIFS054P001C01-SOCA
PVCCIN_CPU0              U2               CD36     SOCKET4677_AZIFS054P001C01-SOCA
PVCCIN_CPU0              U2               CD38     SOCKET4677_AZIFS054P001C01-SOCA
PVCCIN_CPU0              U2               CD40     SOCKET4677_AZIFS054P001C01-SOCA
PVCCIN_CPU0              U2               CD42     SOCKET4677_AZIFS054P001C01-SOCA
PVCCIN_CPU0              U2               CD44     SOCKET4677_AZIFS054P001C01-SOCA
PVCCIN_CPU0              U2               CD47     SOCKET4677_AZIFS054P001C01-SOCA
PVCCIN_CPU0              U2               CD49     SOCKET4677_AZIFS054P001C01-SOCA
PVCCIN_CPU0              U2               CD51     SOCKET4677_AZIFS054P001C01-SOCA
PVCCIN_CPU0              U2               CD53     SOCKET4677_AZIFS054P001C01-SOCA
PVCCIN_CPU0              U2               CD55     SOCKET4677_AZIFS054P001C01-SOCA
PVCCIN_CPU0              U2               CD57     SOCKET4677_AZIFS054P001C01-SOCA
PVCCIN_CPU0              U2               CD59     SOCKET4677_AZIFS054P001C01-SOCA
PVCCIN_CPU0              U2               CD79     SOCKET4677_AZIFS054P001C01-SOCA
PVCCIN_CPU0              U2               CD81     SOCKET4677_AZIFS054P001C01-SOCA
PVCCIN_CPU0              U2               CD83     SOCKET4677_AZIFS054P001C01-SOCA
PVCCIN_CPU0              U2               CD85     SOCKET4677_AZIFS054P001C01-SOCA
PVCCIN_CPU0              U2               CD87     SOCKET4677_AZIFS054P001C01-SOCA
PVCCIN_CPU0              U2               CD89     SOCKET4677_AZIFS054P001C01-SOCA
PVCCIN_CPU0              U2               CE80     SOCKET4677_AZIFS054P001C01-SOCA
PVCCIN_CPU0              U2               CE82     SOCKET4677_AZIFS054P001C01-SOCA
PVCCIN_CPU0              U2               CE84     SOCKET4677_AZIFS054P001C01-SOCA
PVCCIN_CPU0              U2               CE86     SOCKET4677_AZIFS054P001C01-SOCA
PVCCIN_CPU0              U2               CE88     SOCKET4677_AZIFS054P001C01-SOCA
PVCCIN_CPU0              U2               CE90     SOCKET4677_AZIFS054P001C01-SOCA
PVCCIN_CPU0              U2               CF79     SOCKET4677_AZIFS054P001C01-SOCA
PVCCIN_CPU0              U2               CF81     SOCKET4677_AZIFS054P001C01-SOCA
PVCCIN_CPU0              U2               CF83     SOCKET4677_AZIFS054P001C01-SOCA
PVCCIN_CPU0              U2               CF85     SOCKET4677_AZIFS054P001C01-SOCA
PVCCIN_CPU0              U2               CF87     SOCKET4677_AZIFS054P001C01-SOCA
PVCCIN_CPU0              U2               CF89     SOCKET4677_AZIFS054P001C01-SOCA
PVCCIN_CPU0              U2               CF91     SOCKET4677_AZIFS054P001C01-SOCA
PVCCIN_CPU0              U2               CG80     SOCKET4677_AZIFS054P001C01-SOCA
PVCCIN_CPU0              U2               CG82     SOCKET4677_AZIFS054P001C01-SOCA
PVCCIN_CPU0              U2               CG84     SOCKET4677_AZIFS054P001C01-SOCA
PVCCIN_CPU0              U2               CG86     SOCKET4677_AZIFS054P001C01-SOCA
PVCCIN_CPU0              U2               CG88     SOCKET4677_AZIFS054P001C01-SOCA
PVCCIN_CPU0              U2               CG90     SOCKET4677_AZIFS054P001C01-SOCA
PVCCIN_CPU0              U2               CH81     SOCKET4677_AZIFS054P001C01-SOCA
PVCCIN_CPU0              U2               CH91     SOCKET4677_AZIFS054P001C01-SOCA
PVCCIN_CPU0              U2               CJ82     SOCKET4677_AZIFS054P001C01-SOCA
PVCCIN_CPU0              U2               CJ84     SOCKET4677_AZIFS054P001C01-SOCA
PVCCIN_CPU0              U2               CJ86     SOCKET4677_AZIFS054P001C01-SOCA
PVCCIN_CPU0              U2               CJ88     SOCKET4677_AZIFS054P001C01-SOCA
PVCCIN_CPU0              U2               CJ90     SOCKET4677_AZIFS054P001C01-SOCA
PVCCIN_CPU0              U2               CK83     SOCKET4677_AZIFS054P001C01-SOCA
PVCCIN_CPU0              U2               CK85     SOCKET4677_AZIFS054P001C01-SOCA
PVCCIN_CPU0              U2               CK87     SOCKET4677_AZIFS054P001C01-SOCA
PVCCIN_CPU0              U2               CK89     SOCKET4677_AZIFS054P001C01-SOCA
PVCCIN_CPU0              U2               CK91     SOCKET4677_AZIFS054P001C01-SOCA
PVCCIN_CPU0              U2               CL84     SOCKET4677_AZIFS054P001C01-SOCA
PVCCIN_CPU0              U2               CL86     SOCKET4677_AZIFS054P001C01-SOCA
PVCCIN_CPU0              U2               CL88     SOCKET4677_AZIFS054P001C01-SOCA
PVCCIN_CPU0              U2               CL90     SOCKET4677_AZIFS054P001C01-SOCA
PVCCIN_CPU0              U2               CM87     SOCKET4677_AZIFS054P001C01-SOCA
PVCCIN_CPU0              U2               CM89     SOCKET4677_AZIFS054P001C01-SOCA
PVCCIN_CPU0              U2               CM91     SOCKET4677_AZIFS054P001C01-SOCA
PVCCIN_CPU0              U2               CN88     SOCKET4677_AZIFS054P001C01-SOCA
PVCCIN_CPU0              U2               CN90     SOCKET4677_AZIFS054P001C01-SOCA
PVCCIN_CPU0              U2               CP89     SOCKET4677_AZIFS054P001C01-SOCA
PVCCIN_CPU0_ADDR         PR159            2        Q_RES_0402LF-28K,1%,1/16W,EMPTA
PVCCIN_CPU0_ADDR         PR171            1        Q_RES_0402LF-0,5%,1/16W,CHIP,CA
PVCCIN_CPU0_ADDR         PU14             42       RAA229126GNPHA0-RAA229126GNP#HA
PVCCIN_CPU0_ATSEN        PC336            1        Q_CAP_0402-470PF,50V,10%,X7R,TA
PVCCIN_CPU0_ATSEN        PR400            1        Q_RES_0402LF-10K,1%,1/16W,EMPTB
PVCCIN_CPU0_ATSEN        PU10_P0_4        36       ISL99390FRZTR5935-ISL99390FRZ-A
PVCCIN_CPU0_ATSEN        PU11_P0_3        36       ISL99390FRZTR5935-ISL99390FRZ-A
PVCCIN_CPU0_ATSEN        PU12_P0_2        36       ISL99390FRZTR5935-ISL99390FRZ-A
PVCCIN_CPU0_ATSEN        PU13_P0_1        36       ISL99390FRZTR5935-ISL99390FRZ-A
PVCCIN_CPU0_ATSEN        PU14             43       RAA229126GNPHA0-RAA229126GNP#HA
PVCCIN_CPU0_ATSEN        PU69_P0_1        36       ISL99390FRZTR5935-ISL99390FRZ-A
PVCCIN_CPU0_ATSEN        PU6_P0_8         36       ISL99390FRZTR5935-ISL99390FRZ-A
PVCCIN_CPU0_ATSEN        PU70_P0_2        36       ISL99390FRZTR5935-ISL99390FRZ-A
PVCCIN_CPU0_ATSEN        PU71_P0_3        36       ISL99390FRZTR5935-ISL99390FRZ-B
PVCCIN_CPU0_ATSEN        PU72_P0_4        36       ISL99390FRZTR5935-ISL99390FRZ-B
PVCCIN_CPU0_ATSEN        PU7_P0_7         36       ISL99390FRZTR5935-ISL99390FRZ-A
PVCCIN_CPU0_ATSEN        PU8_P0_6         36       ISL99390FRZTR5935-ISL99390FRZ-A
PVCCIN_CPU0_ATSEN        PU9_P0_5         36       ISL99390FRZTR5935-ISL99390FRZ-A
PVCCIN_CPU0_CSPIN        PC329            1        Q_CAP_0402-0.1UF,25V,10%,EMPTYA
PVCCIN_CPU0_CSPIN        PR157            2        Q_RES_0402LF-0,5%,1/16W,EMPTY,A
PVCCIN_CPU0_CSPIN        PR158            1        Q_RES_0402LF-0,5%,1/16W,CHIP,CA
PVCCIN_CPU0_CSPIN        PU14             45       RAA229126GNPHA0-RAA229126GNP#HA
PVCCIN_CPU0_EN_R         PC332            1        Q_CAP_0402-1000PF,50V,5%,X7R,TA
PVCCIN_CPU0_EN_R         PR162            2        Q_RES_0402LF-0,5%,1/16W,CHIP,CA
PVCCIN_CPU0_EN_R         PU14             17       RAA229126GNPHA0-RAA229126GNP#HA
PVCCIN_CPU0_IMON1        PU13_P0_1        38       ISL99390FRZTR5935-ISL99390FRZ-A
PVCCIN_CPU0_IMON1        PU14             27       RAA229126GNPHA0-RAA229126GNP#HA
PVCCIN_CPU0_IMON2        PU12_P0_2        38       ISL99390FRZTR5935-ISL99390FRZ-A
PVCCIN_CPU0_IMON2        PU14             28       RAA229126GNPHA0-RAA229126GNP#HA
PVCCIN_CPU0_IMON3        PU11_P0_3        38       ISL99390FRZTR5935-ISL99390FRZ-A
PVCCIN_CPU0_IMON3        PU14             29       RAA229126GNPHA0-RAA229126GNP#HA
PVCCIN_CPU0_IMON4        PU10_P0_4        38       ISL99390FRZTR5935-ISL99390FRZ-A
PVCCIN_CPU0_IMON4        PU14             30       RAA229126GNPHA0-RAA229126GNP#HA
PVCCIN_CPU0_IMON5        PU14             31       RAA229126GNPHA0-RAA229126GNP#HA
PVCCIN_CPU0_IMON5        PU9_P0_5         38       ISL99390FRZTR5935-ISL99390FRZ-A
PVCCIN_CPU0_IMON6        PU14             32       RAA229126GNPHA0-RAA229126GNP#HA
PVCCIN_CPU0_IMON6        PU8_P0_6         38       ISL99390FRZTR5935-ISL99390FRZ-A
PVCCIN_CPU0_IMON7        PU14             33       RAA229126GNPHA0-RAA229126GNP#HA
PVCCIN_CPU0_IMON7        PU7_P0_7         38       ISL99390FRZTR5935-ISL99390FRZ-A
PVCCIN_CPU0_IMON8        PU14             34       RAA229126GNPHA0-RAA229126GNP#HA
PVCCIN_CPU0_IMON8        PU6_P0_8         38       ISL99390FRZTR5935-ISL99390FRZ-A
PVCCIN_CPU0_ISYS_R       PR450            1        Q_RES_0402LF-0,5%,1/16W,EMPTY,A
PVCCIN_CPU0_ISYS_R       PR451            1        Q_RES_0402LF-0,5%,1/16W,CHIP,CA
PVCCIN_CPU0_ISYS_R       PU14             44       RAA229126GNPHA0-RAA229126GNP#HA
PVCCIN_CPU0_LSET1        PR151            1        Q_RES_0402LF-8.87K,1%,1/16W,EMA
PVCCIN_CPU0_LSET1        PU13_P0_1        37       ISL99390FRZTR5935-ISL99390FRZ-A
PVCCIN_CPU0_LSET2        PR150            1        Q_RES_0402LF-8.87K,1%,1/16W,EMA
PVCCIN_CPU0_LSET2        PU12_P0_2        37       ISL99390FRZTR5935-ISL99390FRZ-A
PVCCIN_CPU0_LSET3        PR145            1        Q_RES_0402LF-8.87K,1%,1/16W,EMA
PVCCIN_CPU0_LSET3        PU11_P0_3        37       ISL99390FRZTR5935-ISL99390FRZ-A
PVCCIN_CPU0_LSET4        PR144            1        Q_RES_0402LF-8.87K,1%,1/16W,EMA
PVCCIN_CPU0_LSET4        PU10_P0_4        37       ISL99390FRZTR5935-ISL99390FRZ-A
PVCCIN_CPU0_LSET5        PR139            1        Q_RES_0402LF-8.87K,1%,1/16W,EMA
PVCCIN_CPU0_LSET5        PU9_P0_5         37       ISL99390FRZTR5935-ISL99390FRZ-A
PVCCIN_CPU0_LSET6        PR138            1        Q_RES_0402LF-8.87K,1%,1/16W,EMA
PVCCIN_CPU0_LSET6        PU8_P0_6         37       ISL99390FRZTR5935-ISL99390FRZ-A
PVCCIN_CPU0_LSET7        PR133            1        Q_RES_0402LF-8.87K,1%,1/16W,EMA
PVCCIN_CPU0_LSET7        PU7_P0_7         37       ISL99390FRZTR5935-ISL99390FRZ-A
PVCCIN_CPU0_LSET8        PR132            1        Q_RES_0402LF-8.87K,1%,1/16W,EMA
PVCCIN_CPU0_LSET8        PU6_P0_8         37       ISL99390FRZTR5935-ISL99390FRZ-A
PVCCIN_CPU0_PIN_ALERT    PR169            2        Q_RES_0402LF-1K,1%,1/16W,CHIP,A
PVCCIN_CPU0_PIN_ALERT    PU14             19       RAA229126GNPHA0-RAA229126GNP#HA
PVCCIN_CPU0_PIN_ALERT    R541             2        Q_RES_0402LF-0,5%,1/16W,CHIP,CA
PVCCIN_CPU0_PVCC         PC228_P0_8       1        Q_CAP_C0402-2.2UF,10V,10%,X6S,A
PVCCIN_CPU0_PVCC         PC229_P0_7       1        Q_CAP_C0402-2.2UF,10V,10%,X6S,A
PVCCIN_CPU0_PVCC         PC250_P0_6       1        Q_CAP_C0402-2.2UF,10V,10%,X6S,A
PVCCIN_CPU0_PVCC         PC251_P0_5       1        Q_CAP_C0402-2.2UF,10V,10%,X6S,A
PVCCIN_CPU0_PVCC         PC272_P0_4       1        Q_CAP_C0402-2.2UF,10V,10%,X6S,A
PVCCIN_CPU0_PVCC         PC273_P0_3       1        Q_CAP_C0402-2.2UF,10V,10%,X6S,A
PVCCIN_CPU0_PVCC         PC294_P0_2       1        Q_CAP_C0402-2.2UF,10V,10%,X6S,A
PVCCIN_CPU0_PVCC         PC295_P0_1       1        Q_CAP_C0402-2.2UF,10V,10%,X6S,A
PVCCIN_CPU0_PVCC         PR134            1        Q_RES_0402LF-2.2,1%,1/16W,CHIPA
PVCCIN_CPU0_PVCC         PR135            1        Q_RES_0402LF-2.2,1%,1/16W,CHIPA
PVCCIN_CPU0_PVCC         PR140            1        Q_RES_0402LF-2.2,1%,1/16W,CHIPA
PVCCIN_CPU0_PVCC         PR141            1        Q_RES_0402LF-2.2,1%,1/16W,CHIPA
PVCCIN_CPU0_PVCC         PR146            1        Q_RES_0402LF-2.2,1%,1/16W,CHIPA
PVCCIN_CPU0_PVCC         PR147            1        Q_RES_0402LF-2.2,1%,1/16W,CHIPA
PVCCIN_CPU0_PVCC         PR152            1        Q_RES_0402LF-2.2,1%,1/16W,CHIPA
PVCCIN_CPU0_PVCC         PR153            1        Q_RES_0402LF-2.2,1%,1/16W,CHIPA
PVCCIN_CPU0_PVCC         PR402            2        Q_RES_0402LF-0,5%,1/16W,CHIP,CA
PVCCIN_CPU0_PVCC         PR403            2        Q_RES_0402LF-0,5%,1/16W,EMPTY,A
PVCCIN_CPU0_PVCC         PU10_P0_4        4        ISL99390FRZTR5935-ISL99390FRZ-A
PVCCIN_CPU0_PVCC         PU11_P0_3        4        ISL99390FRZTR5935-ISL99390FRZ-A
PVCCIN_CPU0_PVCC         PU12_P0_2        4        ISL99390FRZTR5935-ISL99390FRZ-A
PVCCIN_CPU0_PVCC         PU13_P0_1        4        ISL99390FRZTR5935-ISL99390FRZ-A
PVCCIN_CPU0_PVCC         PU6_P0_8         4        ISL99390FRZTR5935-ISL99390FRZ-A
PVCCIN_CPU0_PVCC         PU7_P0_7         4        ISL99390FRZTR5935-ISL99390FRZ-A
PVCCIN_CPU0_PVCC         PU8_P0_6         4        ISL99390FRZTR5935-ISL99390FRZ-A
PVCCIN_CPU0_PVCC         PU9_P0_5         4        ISL99390FRZTR5935-ISL99390FRZ-A
PVCCIN_CPU0_PWM1         PU13_P0_1        34       ISL99390FRZTR5935-ISL99390FRZ-A
PVCCIN_CPU0_PWM1         PU14             12       RAA229126GNPHA0-RAA229126GNP#HA
PVCCIN_CPU0_PWM2         PU12_P0_2        34       ISL99390FRZTR5935-ISL99390FRZ-A
PVCCIN_CPU0_PWM2         PU14             11       RAA229126GNPHA0-RAA229126GNP#HA
PVCCIN_CPU0_PWM3         PU11_P0_3        34       ISL99390FRZTR5935-ISL99390FRZ-A
PVCCIN_CPU0_PWM3         PU14             10       RAA229126GNPHA0-RAA229126GNP#HA
PVCCIN_CPU0_PWM4         PU10_P0_4        34       ISL99390FRZTR5935-ISL99390FRZ-A
PVCCIN_CPU0_PWM4         PU14             9        RAA229126GNPHA0-RAA229126GNP#HA
PVCCIN_CPU0_PWM5         PU14             8        RAA229126GNPHA0-RAA229126GNP#HA
PVCCIN_CPU0_PWM5         PU9_P0_5         34       ISL99390FRZTR5935-ISL99390FRZ-A
PVCCIN_CPU0_PWM6         PU14             7        RAA229126GNPHA0-RAA229126GNP#HA
PVCCIN_CPU0_PWM6         PU8_P0_6         34       ISL99390FRZTR5935-ISL99390FRZ-A
PVCCIN_CPU0_PWM7         PU14             6        RAA229126GNPHA0-RAA229126GNP#HA
PVCCIN_CPU0_PWM7         PU7_P0_7         34       ISL99390FRZTR5935-ISL99390FRZ-A
PVCCIN_CPU0_PWM8         PU14             5        RAA229126GNPHA0-RAA229126GNP#HA
PVCCIN_CPU0_PWM8         PU6_P0_8         34       ISL99390FRZTR5935-ISL99390FRZ-A
PVCCIN_CPU0_VCC          PC334            1        Q_CAP_C0402-100NF,50V,10%,EMPTA
PVCCIN_CPU0_VCC          PC337            1        Q_CAP_C0402-1UF,16V,10%,X6S,CHA
PVCCIN_CPU0_VCC          PR176            1        Q_RES_0402LF-1,1%,1/16W,CHIP,CA
PVCCIN_CPU0_VCC          PU14             47       RAA229126GNPHA0-RAA229126GNP#HA
PVCCIN_CPU0_VDD1         PC293            1        Q_CAP_C0402-2.2UF,10V,10%,X6S,A
PVCCIN_CPU0_VDD1         PR153            2        Q_RES_0402LF-2.2,1%,1/16W,CHIPA
PVCCIN_CPU0_VDD1         PU13_P0_1        3        ISL99390FRZTR5935-ISL99390FRZ-A
PVCCIN_CPU0_VDD1         PU13_P0_1        35       ISL99390FRZTR5935-ISL99390FRZ-A
PVCCIN_CPU0_VDD2         PC292            1        Q_CAP_C0402-2.2UF,10V,10%,X6S,A
PVCCIN_CPU0_VDD2         PR152            2        Q_RES_0402LF-2.2,1%,1/16W,CHIPA
PVCCIN_CPU0_VDD2         PU12_P0_2        3        ISL99390FRZTR5935-ISL99390FRZ-A
PVCCIN_CPU0_VDD2         PU12_P0_2        35       ISL99390FRZTR5935-ISL99390FRZ-A
PVCCIN_CPU0_VDD3         PC271            1        Q_CAP_C0402-2.2UF,10V,10%,X6S,A
PVCCIN_CPU0_VDD3         PR147            2        Q_RES_0402LF-2.2,1%,1/16W,CHIPA
PVCCIN_CPU0_VDD3         PU11_P0_3        3        ISL99390FRZTR5935-ISL99390FRZ-A
PVCCIN_CPU0_VDD3         PU11_P0_3        35       ISL99390FRZTR5935-ISL99390FRZ-A
PVCCIN_CPU0_VDD4         PC270            1        Q_CAP_C0402-2.2UF,10V,10%,X6S,A
PVCCIN_CPU0_VDD4         PR146            2        Q_RES_0402LF-2.2,1%,1/16W,CHIPA
PVCCIN_CPU0_VDD4         PU10_P0_4        3        ISL99390FRZTR5935-ISL99390FRZ-A
PVCCIN_CPU0_VDD4         PU10_P0_4        35       ISL99390FRZTR5935-ISL99390FRZ-A
PVCCIN_CPU0_VDD5         PC249            1        Q_CAP_C0402-2.2UF,10V,10%,X6S,A
PVCCIN_CPU0_VDD5         PR141            2        Q_RES_0402LF-2.2,1%,1/16W,CHIPA
PVCCIN_CPU0_VDD5         PU9_P0_5         3        ISL99390FRZTR5935-ISL99390FRZ-A
PVCCIN_CPU0_VDD5         PU9_P0_5         35       ISL99390FRZTR5935-ISL99390FRZ-A
PVCCIN_CPU0_VDD6         PC248            1        Q_CAP_C0402-2.2UF,10V,10%,X6S,A
PVCCIN_CPU0_VDD6         PR140            2        Q_RES_0402LF-2.2,1%,1/16W,CHIPA
PVCCIN_CPU0_VDD6         PU8_P0_6         3        ISL99390FRZTR5935-ISL99390FRZ-A
PVCCIN_CPU0_VDD6         PU8_P0_6         35       ISL99390FRZTR5935-ISL99390FRZ-A
PVCCIN_CPU0_VDD7         PC227            1        Q_CAP_C0402-2.2UF,10V,10%,X6S,A
PVCCIN_CPU0_VDD7         PR135            2        Q_RES_0402LF-2.2,1%,1/16W,CHIPA
PVCCIN_CPU0_VDD7         PU7_P0_7         3        ISL99390FRZTR5935-ISL99390FRZ-A
PVCCIN_CPU0_VDD7         PU7_P0_7         35       ISL99390FRZTR5935-ISL99390FRZ-A
PVCCIN_CPU0_VDD8         PC226            1        Q_CAP_C0402-2.2UF,10V,10%,X6S,A
PVCCIN_CPU0_VDD8         PR134            2        Q_RES_0402LF-2.2,1%,1/16W,CHIPA
PVCCIN_CPU0_VDD8         PU6_P0_8         3        ISL99390FRZTR5935-ISL99390FRZ-A
PVCCIN_CPU0_VDD8         PU6_P0_8         35       ISL99390FRZTR5935-ISL99390FRZ-A
PVCCIN_CPU0_VIN_CSNIN    PC330            1        Q_CAP_0402-0.1UF,25V,10%,X7R,CA
PVCCIN_CPU0_VIN_CSNIN    PR156            2        Q_RES_0402LF-0,5%,1/16W,CHIP,CA
PVCCIN_CPU0_VIN_CSNIN    PR166            1        Q_RES_0402LF-1K,1%,1/16W,EMPTYA
PVCCIN_CPU0_VIN_CSNIN    PU14             46       RAA229126GNPHA0-RAA229126GNP#HA
PVCCIN_CPU0_VOS1         PR155            1        Q_RES_0402LF-0,5%,1/16W,CHIP,CA
PVCCIN_CPU0_VOS1         PU13_P0_1        1        ISL99390FRZTR5935-ISL99390FRZ-A
PVCCIN_CPU0_VOS2         PR154            1        Q_RES_0402LF-0,5%,1/16W,CHIP,CA
PVCCIN_CPU0_VOS2         PU12_P0_2        1        ISL99390FRZTR5935-ISL99390FRZ-A
PVCCIN_CPU0_VOS3         PR149            1        Q_RES_0402LF-0,5%,1/16W,CHIP,CA
PVCCIN_CPU0_VOS3         PU11_P0_3        1        ISL99390FRZTR5935-ISL99390FRZ-A
PVCCIN_CPU0_VOS4         PR148            1        Q_RES_0402LF-0,5%,1/16W,CHIP,CA
PVCCIN_CPU0_VOS4         PU10_P0_4        1        ISL99390FRZTR5935-ISL99390FRZ-A
PVCCIN_CPU0_VOS5         PR143            1        Q_RES_0402LF-0,5%,1/16W,CHIP,CA
PVCCIN_CPU0_VOS5         PU9_P0_5         1        ISL99390FRZTR5935-ISL99390FRZ-A
PVCCIN_CPU0_VOS6         PR142            1        Q_RES_0402LF-0,5%,1/16W,CHIP,CA
PVCCIN_CPU0_VOS6         PU8_P0_6         1        ISL99390FRZTR5935-ISL99390FRZ-A
PVCCIN_CPU0_VOS7         PR137            1        Q_RES_0402LF-0,5%,1/16W,CHIP,CA
PVCCIN_CPU0_VOS7         PU7_P0_7         1        ISL99390FRZTR5935-ISL99390FRZ-A
PVCCIN_CPU0_VOS8         PR136            1        Q_RES_0402LF-0,5%,1/16W,CHIP,CA
PVCCIN_CPU0_VOS8         PU6_P0_8         1        ISL99390FRZTR5935-ISL99390FRZ-A
PVCCIN_CPU0_VREF         PC335            1        Q_CAP_0402-4.7UF,6.3V,20%,X6S,A
PVCCIN_CPU0_VREF         PC1173           1        Q_CAP_C0402-1UF,16V,10%,X6S,CHA
PVCCIN_CPU0_VREF         PC1340           2        Q_CAP_0402-0.1UF,25V,10%,X7R,CA
PVCCIN_CPU0_VREF         PC1341           2        Q_CAP_0402-0.1UF,25V,10%,X7R,CA
PVCCIN_CPU0_VREF         PC1342           2        Q_CAP_0402-0.1UF,25V,10%,X7R,CA
PVCCIN_CPU0_VREF         PC1343           2        Q_CAP_0402-0.1UF,25V,10%,X7R,CA
PVCCIN_CPU0_VREF         PC1344           2        Q_CAP_0402-0.1UF,25V,10%,X7R,CA
PVCCIN_CPU0_VREF         PC1345           2        Q_CAP_0402-0.1UF,25V,10%,X7R,CA
PVCCIN_CPU0_VREF         PC1349           2        Q_CAP_0402-0.1UF,25V,10%,X7R,CA
PVCCIN_CPU0_VREF         PC1350           2        Q_CAP_0402-0.1UF,25V,10%,X7R,CA
PVCCIN_CPU0_VREF         PC1351           2        Q_CAP_0402-0.1UF,25V,10%,EMPTYA
PVCCIN_CPU0_VREF         PC1352           2        Q_CAP_0402-0.1UF,25V,10%,EMPTYA
PVCCIN_CPU0_VREF         PC1355           2        Q_CAP_0402-0.1UF,25V,10%,X7R,CA
PVCCIN_CPU0_VREF         PC1356           2        Q_CAP_0402-0.1UF,25V,10%,X7R,CA
PVCCIN_CPU0_VREF         PR159            1        Q_RES_0402LF-28K,1%,1/16W,EMPTA
PVCCIN_CPU0_VREF         PU10_P0_4        39       ISL99390FRZTR5935-ISL99390FRZ-A
PVCCIN_CPU0_VREF         PU11_P0_3        39       ISL99390FRZTR5935-ISL99390FRZ-A
PVCCIN_CPU0_VREF         PU12_P0_2        39       ISL99390FRZTR5935-ISL99390FRZ-A
PVCCIN_CPU0_VREF         PU13_P0_1        39       ISL99390FRZTR5935-ISL99390FRZ-A
PVCCIN_CPU0_VREF         PU14             48       RAA229126GNPHA0-RAA229126GNP#HA
PVCCIN_CPU0_VREF         PU69_P0_1        39       ISL99390FRZTR5935-ISL99390FRZ-A
PVCCIN_CPU0_VREF         PU6_P0_8         39       ISL99390FRZTR5935-ISL99390FRZ-A
PVCCIN_CPU0_VREF         PU70_P0_2        39       ISL99390FRZTR5935-ISL99390FRZ-A
PVCCIN_CPU0_VREF         PU71_P0_3        39       ISL99390FRZTR5935-ISL99390FRZ-B
PVCCIN_CPU0_VREF         PU72_P0_4        39       ISL99390FRZTR5935-ISL99390FRZ-B
PVCCIN_CPU0_VREF         PU7_P0_7         39       ISL99390FRZTR5935-ISL99390FRZ-A
PVCCIN_CPU0_VREF         PU8_P0_6         39       ISL99390FRZTR5935-ISL99390FRZ-A
PVCCIN_CPU0_VREF         PU9_P0_5         39       ISL99390FRZTR5935-ISL99390FRZ-A
PVCCIN_CPU0_VR_FAULT     PR172            2        Q_RES_0402LF-1K,1%,1/16W,CHIP,A
PVCCIN_CPU0_VR_FAULT     PU14             41       RAA229126GNPHA0-RAA229126GNP#HA
PVCCIN_CPU1              C221             1        Q_CAP_C0402-22UF,4V,20%,X6S,CHA
PVCCIN_CPU1              C222             1        Q_CAP_C0402-22UF,4V,20%,X6S,CHA
PVCCIN_CPU1              C223             1        Q_CAP_C0402-22UF,4V,20%,X6S,CHA
PVCCIN_CPU1              C224             1        Q_CAP_C0402-22UF,4V,20%,X6S,CHA
PVCCIN_CPU1              C225             1        Q_CAP_0805-47UF,4V,20%,X6S,CH6A
PVCCIN_CPU1              C226             1        Q_CAP_C0402-22UF,4V,20%,X6S,CHA
PVCCIN_CPU1              C227             1        Q_CAP_C0402-22UF,4V,20%,X6S,CHA
PVCCIN_CPU1              C228             1        Q_CAP_C0402-22UF,4V,20%,X6S,CHA
PVCCIN_CPU1              C229             1        Q_CAP_C0402-22UF,4V,20%,X6S,CHA
PVCCIN_CPU1              C230             1        Q_CAP_0805-47UF,4V,20%,X6S,CH6A
PVCCIN_CPU1              C231             1        Q_CAP_C0402-22UF,4V,20%,X6S,CHA
PVCCIN_CPU1              C232             1        Q_CAP_C0402-22UF,4V,20%,X6S,CHA
PVCCIN_CPU1              C233             1        Q_CAP_C0402-22UF,4V,20%,X6S,CHA
PVCCIN_CPU1              C234             1        Q_CAP_C0402-22UF,4V,20%,X6S,CHA
PVCCIN_CPU1              C235             1        Q_CAP_0805-47UF,4V,20%,X6S,CH6A
PVCCIN_CPU1              C236             1        Q_CAP_C0402-22UF,4V,20%,X6S,CHA
PVCCIN_CPU1              C237             1        Q_CAP_C0402-22UF,4V,20%,X6S,CHA
PVCCIN_CPU1              C238             1        Q_CAP_C0402-22UF,4V,20%,X6S,CHA
PVCCIN_CPU1              C239             1        Q_CAP_C0402-22UF,4V,20%,X6S,CHA
PVCCIN_CPU1              C240             1        Q_CAP_0805-47UF,4V,20%,X6S,CH6A
PVCCIN_CPU1              C241             1        Q_CAP_C0402-22UF,4V,20%,X6S,CHA
PVCCIN_CPU1              C242             1        Q_CAP_C0402-22UF,4V,20%,X6S,CHA
PVCCIN_CPU1              C243             1        Q_CAP_C0402-22UF,4V,20%,X6S,CHA
PVCCIN_CPU1              C244             1        Q_CAP_C0402-22UF,4V,20%,X6S,CHA
PVCCIN_CPU1              C245             1        Q_CAP_0805-47UF,4V,20%,X6S,CH6A
PVCCIN_CPU1              C246             1        Q_CAP_C0402-22UF,4V,20%,X6S,CHA
PVCCIN_CPU1              C247             1        Q_CAP_C0402-22UF,4V,20%,X6S,CHA
PVCCIN_CPU1              C248             1        Q_CAP_C0402-22UF,4V,20%,X6S,CHA
PVCCIN_CPU1              C249             1        Q_CAP_C0402-22UF,4V,20%,X6S,CHA
PVCCIN_CPU1              C250             1        Q_CAP_0805-47UF,4V,20%,X6S,CH6A
PVCCIN_CPU1              C251             1        Q_CAP_C0402-22UF,4V,20%,X6S,CHA
PVCCIN_CPU1              C252             1        Q_CAP_C0402-22UF,4V,20%,X6S,CHA
PVCCIN_CPU1              C253             1        Q_CAP_C0402-22UF,4V,20%,X6S,CHA
PVCCIN_CPU1              C254             1        Q_CAP_C0402-22UF,4V,20%,X6S,CHA
PVCCIN_CPU1              C255             1        Q_CAP_0805-47UF,4V,20%,X6S,CH6A
PVCCIN_CPU1              C256             1        Q_CAP_C0402-22UF,4V,20%,X6S,CHA
PVCCIN_CPU1              C257             1        Q_CAP_C0402-22UF,4V,20%,X6S,CHA
PVCCIN_CPU1              C258             1        Q_CAP_C0402-22UF,4V,20%,X6S,CHA
PVCCIN_CPU1              C259             1        Q_CAP_C0402-22UF,4V,20%,X6S,CHA
PVCCIN_CPU1              C260             1        Q_CAP_0805-47UF,4V,20%,X6S,CH6A
PVCCIN_CPU1              C261             1        Q_CAP_C0402-22UF,4V,20%,X6S,CHA
PVCCIN_CPU1              C262             1        Q_CAP_C0402-22UF,4V,20%,X6S,CHA
PVCCIN_CPU1              C263             1        Q_CAP_C0402-22UF,4V,20%,X6S,CHA
PVCCIN_CPU1              C264             1        Q_CAP_C0402-22UF,4V,20%,X6S,CHA
PVCCIN_CPU1              C265             1        Q_CAP_0805-47UF,4V,20%,X6S,CH6A
PVCCIN_CPU1              C266             1        Q_CAP_C0402-22UF,4V,20%,X6S,CHA
PVCCIN_CPU1              C267             1        Q_CAP_C0402-22UF,4V,20%,X6S,CHA
PVCCIN_CPU1              C268             1        Q_CAP_C0402-22UF,4V,20%,X6S,CHA
PVCCIN_CPU1              C269             1        Q_CAP_C0402-22UF,4V,20%,X6S,CHA
PVCCIN_CPU1              C270             1        Q_CAP_0805-47UF,4V,20%,X6S,CH6A
PVCCIN_CPU1              C271             1        Q_CAP_C0402-22UF,4V,20%,X6S,CHA
PVCCIN_CPU1              C272             1        Q_CAP_C0402-22UF,4V,20%,X6S,CHA
PVCCIN_CPU1              C273             1        Q_CAP_C0402-22UF,4V,20%,X6S,CHA
PVCCIN_CPU1              C274             1        Q_CAP_C0402-22UF,4V,20%,X6S,CHA
PVCCIN_CPU1              C275             1        Q_CAP_C0402-22UF,4V,20%,X6S,CHA
PVCCIN_CPU1              C276             1        Q_CAP_C0402-22UF,4V,20%,X6S,CHA
PVCCIN_CPU1              C277             1        Q_CAP_C0402-22UF,4V,20%,X6S,CHA
PVCCIN_CPU1              C278             1        Q_CAP_C0402-22UF,4V,20%,X6S,CHA
PVCCIN_CPU1              C279             1        Q_CAP_C0402-22UF,4V,20%,X6S,CHA
PVCCIN_CPU1              C280             1        Q_CAP_C0402-22UF,4V,20%,X6S,CHA
PVCCIN_CPU1              C281             1        Q_CAP_C0402-22UF,4V,20%,X6S,CHA
PVCCIN_CPU1              C282             1        Q_CAP_C0402-22UF,4V,20%,X6S,CHA
PVCCIN_CPU1              C283             1        Q_CAP_C0402-22UF,4V,20%,X6S,CHA
PVCCIN_CPU1              C284             1        Q_CAP_C0402-22UF,4V,20%,X6S,CHA
PVCCIN_CPU1              C285             1        Q_CAP_C0402-22UF,4V,20%,X6S,CHA
PVCCIN_CPU1              C286             1        Q_CAP_C0402-22UF,4V,20%,X6S,CHA
PVCCIN_CPU1              C287             1        Q_CAP_C0402-22UF,4V,20%,X6S,CHA
PVCCIN_CPU1              C288             1        Q_CAP_C0402-22UF,4V,20%,X6S,CHA
PVCCIN_CPU1              C289             1        Q_CAP_C0402-22UF,4V,20%,X6S,CHA
PVCCIN_CPU1              C290             1        Q_CAP_C0402-22UF,4V,20%,X6S,CHA
PVCCIN_CPU1              C291             1        Q_CAP_C0402-22UF,4V,20%,X6S,CHA
PVCCIN_CPU1              C292             1        Q_CAP_C0402-22UF,4V,20%,X6S,CHA
PVCCIN_CPU1              C293             1        Q_CAP_C0402-22UF,4V,20%,X6S,CHA
PVCCIN_CPU1              C294             1        Q_CAP_C0402-22UF,4V,20%,X6S,CHA
PVCCIN_CPU1              C295             1        Q_CAP_C0402-22UF,4V,20%,X6S,CHA
PVCCIN_CPU1              C296             1        Q_CAP_C0402-22UF,4V,20%,X6S,CHA
PVCCIN_CPU1              C297             1        Q_CAP_C0402-22UF,4V,20%,X6S,CHA
PVCCIN_CPU1              C298             1        Q_CAP_C0402-22UF,4V,20%,X6S,CHA
PVCCIN_CPU1              C299             1        Q_CAP_C0402-22UF,4V,20%,X6S,CHA
PVCCIN_CPU1              C300             1        Q_CAP_C0402-22UF,4V,20%,X6S,CHA
PVCCIN_CPU1              C301             1        Q_CAP_C0402-22UF,4V,20%,X6S,CHA
PVCCIN_CPU1              C302             1        Q_CAP_C0402-22UF,4V,20%,X6S,CHA
PVCCIN_CPU1              C303             1        Q_CAP_C0402-22UF,4V,20%,X6S,CHA
PVCCIN_CPU1              C304             1        Q_CAP_C0402-22UF,4V,20%,X6S,CHA
PVCCIN_CPU1              C305             1        Q_CAP_C0402-22UF,4V,20%,X6S,CHA
PVCCIN_CPU1              C306             1        Q_CAP_C0402-22UF,4V,20%,X6S,CHA
PVCCIN_CPU1              C307             1        Q_CAP_C0402-22UF,4V,20%,X6S,CHA
PVCCIN_CPU1              C308             1        Q_CAP_C0402-22UF,4V,20%,X6S,CHA
PVCCIN_CPU1              C309             1        Q_CAP_C0402-22UF,4V,20%,X6S,CHA
PVCCIN_CPU1              C311             1        Q_CAP_C0805-100UF,4V,20%,X6S,CA
PVCCIN_CPU1              C312             1        Q_CAP_C0805-100UF,4V,20%,X6S,CA
PVCCIN_CPU1              C313             1        Q_CAP_C0805-100UF,4V,20%,X6S,CA
PVCCIN_CPU1              C314             1        Q_CAP_C0805-100UF,4V,20%,X6S,CA
PVCCIN_CPU1              C315             1        Q_CAP_C0805-100UF,4V,20%,X6S,CA
PVCCIN_CPU1              C316             1        Q_CAP_C0805-100UF,4V,20%,X6S,CA
PVCCIN_CPU1              C317             1        Q_CAP_C0805-100UF,4V,20%,X6S,CA
PVCCIN_CPU1              C318             1        Q_CAP_C0805-100UF,4V,20%,X6S,CA
PVCCIN_CPU1              C320             1        Q_CAP_C0805-100UF,4V,20%,X6S,CA
PVCCIN_CPU1              C321             1        Q_CAP_C0805-100UF,4V,20%,X6S,CA
PVCCIN_CPU1              C322             1        Q_CAP_C0805-100UF,4V,20%,X6S,CA
PVCCIN_CPU1              C323             1        Q_CAP_C0805-100UF,4V,20%,X6S,CA
PVCCIN_CPU1              C324             1        Q_CAP_C0805-100UF,4V,20%,X6S,CA
PVCCIN_CPU1              C325             1        Q_CAP_C0805-100UF,4V,20%,X6S,CA
PVCCIN_CPU1              C326             1        Q_CAP_C0805-100UF,4V,20%,X6S,CA
PVCCIN_CPU1              C327             1        Q_CAP_C0805-100UF,4V,20%,X6S,CA
PVCCIN_CPU1              C328             1        Q_CAP_C0805-100UF,4V,20%,X6S,CA
PVCCIN_CPU1              C329             1        Q_CAP_C0805-100UF,4V,20%,X6S,CA
PVCCIN_CPU1              C330             1        Q_CAP_C0805-100UF,4V,20%,X6S,CA
PVCCIN_CPU1              C332             1        Q_CAP_C0805-100UF,4V,20%,X6S,CA
PVCCIN_CPU1              C333             1        Q_CAP_C0805-100UF,4V,20%,X6S,CA
PVCCIN_CPU1              C335             1        Q_CAP_C0805-100UF,4V,20%,X6S,CA
PVCCIN_CPU1              C336             1        Q_CAP_C0805-100UF,4V,20%,X6S,CA
PVCCIN_CPU1              C337             1        Q_CAP_C0603-47UF,2.5V,20%,X6S,A
PVCCIN_CPU1              C338             1        Q_CAP_C0805-100UF,4V,20%,X6S,CA
PVCCIN_CPU1              C339             1        Q_CAP_C0805-100UF,4V,20%,X6S,CA
PVCCIN_CPU1              C340             1        Q_CAP_C0603-47UF,2.5V,20%,X6S,A
PVCCIN_CPU1              C341             1        Q_CAP_C0805-100UF,4V,20%,X6S,CA
PVCCIN_CPU1              C342             1        Q_CAP_C0805-100UF,4V,20%,X6S,CA
PVCCIN_CPU1              C343             1        Q_CAP_C0805-100UF,4V,20%,X6S,CA
PVCCIN_CPU1              C344             1        Q_CAP_C0805-100UF,4V,20%,X6S,CA
PVCCIN_CPU1              C345             1        Q_CAP_C0805-100UF,4V,20%,X6S,CA
PVCCIN_CPU1              C346             1        Q_CAP_C0805-100UF,4V,20%,X6S,CA
PVCCIN_CPU1              C347             1        Q_CAP_C0805-100UF,4V,20%,X6S,CA
PVCCIN_CPU1              C348             1        Q_CAP_C0805-100UF,4V,20%,X6S,CA
PVCCIN_CPU1              C349             1        Q_CAP_C0805-100UF,4V,20%,X6S,CA
PVCCIN_CPU1              C350             1        Q_CAP_C0805-100UF,4V,20%,X6S,CA
PVCCIN_CPU1              C351             1        Q_CAP_C0805-100UF,4V,20%,X6S,CA
PVCCIN_CPU1              C352             1        Q_CAP_C0805-100UF,4V,20%,X6S,CA
PVCCIN_CPU1              C353             1        Q_CAP_C0805-100UF,4V,20%,X6S,CA
PVCCIN_CPU1              C354             1        Q_CAP_C0805-100UF,4V,20%,X6S,CA
PVCCIN_CPU1              C480             1        Q_CAP_C0603-47UF,2.5V,20%,X6S,A
PVCCIN_CPU1              C483             1        Q_CAP_C0603-47UF,2.5V,20%,X6S,A
PVCCIN_CPU1              PC189            1        Q_CAPP_SMLF-470UF,2.5V,20%,EMPA
PVCCIN_CPU1              PC1990           1        Q_CAPP_SMLF-470UF,2.5V,20%,EMPA
PVCCIN_CPU1              PC495_P1_8       1        Q_CAP_C0402-1UF,16V,10%,X6S,CHA
PVCCIN_CPU1              PC496_P1_7       1        Q_CAP_C0402-1UF,16V,10%,X6S,CHA
PVCCIN_CPU1              PC497_P1_8       1        Q_CAP_0805-22UF,4V,20%,X6S,TMPA
PVCCIN_CPU1              PC498_P1_7       1        Q_CAP_0805-22UF,4V,20%,X6S,TMPA
PVCCIN_CPU1              PC499_P1_8       1        Q_CAP_0805-22UF,4V,20%,X6S,TMPA
PVCCIN_CPU1              PC500_P1_7       1        Q_CAP_0805-22UF,4V,20%,X6S,TMPA
PVCCIN_CPU1              PC519_P1_6       1        Q_CAP_0805-22UF,4V,20%,X6S,TMPA
PVCCIN_CPU1              PC520_P1_5       1        Q_CAP_0805-22UF,4V,20%,X6S,TMPA
PVCCIN_CPU1              PC521_P1_6       1        Q_CAP_0805-22UF,4V,20%,X6S,TMPA
PVCCIN_CPU1              PC522_P1_5       1        Q_CAP_0805-22UF,4V,20%,X6S,TMPA
PVCCIN_CPU1              PC541_P1_4       1        Q_CAP_0805-22UF,4V,20%,X6S,TMPA
PVCCIN_CPU1              PC542_P1_3       1        Q_CAP_0805-22UF,4V,20%,X6S,TMPA
PVCCIN_CPU1              PC543_P1_4       1        Q_CAP_0805-22UF,4V,20%,X6S,TMPA
PVCCIN_CPU1              PC544_P1_3       1        Q_CAP_0805-22UF,4V,20%,X6S,TMPA
PVCCIN_CPU1              PC572_P1_1       1        Q_CAP_C0402-100NF,50V,10%,X7R,A
PVCCIN_CPU1              PC574_P1_1       1        Q_CAP_C0402-1UF,16V,10%,X6S,CHA
PVCCIN_CPU1              PC575_P1_2       1        Q_CAP_0805-22UF,4V,20%,X6S,TMPA
PVCCIN_CPU1              PC576_P1_1       1        Q_CAP_0805-22UF,4V,20%,X6S,TMPA
PVCCIN_CPU1              PC577_P1_2       1        Q_CAP_0805-22UF,4V,20%,X6S,TMPA
PVCCIN_CPU1              PC578_P1_1       1        Q_CAP_0805-22UF,4V,20%,X6S,TMPA
PVCCIN_CPU1              PC83             1        Q_CAPP_THLF-560UF,2.5V,20%,OSCA
PVCCIN_CPU1              PC580            1        Q_CAPP_THLF-560UF,2.5V,20%,OSCA
PVCCIN_CPU1              PC583            1        Q_CAPP_THLF-560UF,2.5V,20%,OSCA
PVCCIN_CPU1              PC586            1        Q_CAPP_THLF-560UF,2.5V,20%,OSCA
PVCCIN_CPU1              PC587            1        Q_CAPP_SMLF-470UF,2.5V,20%,EMPA
PVCCIN_CPU1              PC589            1        Q_CAPP_THLF-560UF,2.5V,20%,OSCA
PVCCIN_CPU1              PC590            1        Q_CAPP_SMLF-470UF,2.5V,20%,EMPA
PVCCIN_CPU1              PL24             4        Q_INDUCTOR4P_14-150NH,SMLF,INDA
PVCCIN_CPU1              PL25             4        Q_INDUCTOR4P_14-150NH,SMLF,INDA
PVCCIN_CPU1              PL26             4        Q_INDUCTOR4P_14-150NH,SMLF,INDA
PVCCIN_CPU1              PL27             4        Q_INDUCTOR4P_14-150NH,SMLF,INDA
PVCCIN_CPU1              PL28             4        Q_INDUCTOR4P_14-150NH,SMLF,INDA
PVCCIN_CPU1              PL29             4        Q_INDUCTOR4P_14-150NH,SMLF,INDA
PVCCIN_CPU1              PL30             4        Q_INDUCTOR4P_14-150NH,SMLF,INDA
PVCCIN_CPU1              PL31             4        Q_INDUCTOR4P_14-150NH,SMLF,INDA
PVCCIN_CPU1              PR289            2        Q_RES_0402LF-0,5%,1/16W,CHIP,CA
PVCCIN_CPU1              PR290            2        Q_RES_0402LF-0,5%,1/16W,CHIP,CA
PVCCIN_CPU1              PR295            2        Q_RES_0402LF-0,5%,1/16W,CHIP,CA
PVCCIN_CPU1              PR296            2        Q_RES_0402LF-0,5%,1/16W,CHIP,CA
PVCCIN_CPU1              PR301            2        Q_RES_0402LF-0,5%,1/16W,CHIP,CA
PVCCIN_CPU1              PR302            2        Q_RES_0402LF-0,5%,1/16W,CHIP,CA
PVCCIN_CPU1              PR329            2        Q_RES_0402LF-0,5%,1/16W,CHIP,CA
PVCCIN_CPU1              PR330            2        Q_RES_0402LF-0,5%,1/16W,CHIP,CA
PVCCIN_CPU1              PR578            2        Q_RES_0402LF-100,1%,1/16W,CHIPA
PVCCIN_CPU1              U1               BD91     SOCKET4677_AZIFS054P001C01-SOCA
PVCCIN_CPU1              U1               BE86     SOCKET4677_AZIFS054P001C01-SOCA
PVCCIN_CPU1              U1               BE88     SOCKET4677_AZIFS054P001C01-SOCA
PVCCIN_CPU1              U1               BE90     SOCKET4677_AZIFS054P001C01-SOCA
PVCCIN_CPU1              U1               BF85     SOCKET4677_AZIFS054P001C01-SOCA
PVCCIN_CPU1              U1               BF87     SOCKET4677_AZIFS054P001C01-SOCA
PVCCIN_CPU1              U1               BF89     SOCKET4677_AZIFS054P001C01-SOCA
PVCCIN_CPU1              U1               BF91     SOCKET4677_AZIFS054P001C01-SOCA
PVCCIN_CPU1              U1               BG84     SOCKET4677_AZIFS054P001C01-SOCA
PVCCIN_CPU1              U1               BG86     SOCKET4677_AZIFS054P001C01-SOCA
PVCCIN_CPU1              U1               BG88     SOCKET4677_AZIFS054P001C01-SOCA
PVCCIN_CPU1              U1               BG90     SOCKET4677_AZIFS054P001C01-SOCA
PVCCIN_CPU1              U1               BH85     SOCKET4677_AZIFS054P001C01-SOCA
PVCCIN_CPU1              U1               BH87     SOCKET4677_AZIFS054P001C01-SOCA
PVCCIN_CPU1              U1               BH89     SOCKET4677_AZIFS054P001C01-SOCA
PVCCIN_CPU1              U1               BH91     SOCKET4677_AZIFS054P001C01-SOCA
PVCCIN_CPU1              U1               BK81     SOCKET4677_AZIFS054P001C01-SOCA
PVCCIN_CPU1              U1               BK83     SOCKET4677_AZIFS054P001C01-SOCA
PVCCIN_CPU1              U1               BK85     SOCKET4677_AZIFS054P001C01-SOCA
PVCCIN_CPU1              U1               BK87     SOCKET4677_AZIFS054P001C01-SOCA
PVCCIN_CPU1              U1               BK89     SOCKET4677_AZIFS054P001C01-SOCA
PVCCIN_CPU1              U1               BK91     SOCKET4677_AZIFS054P001C01-SOCA
PVCCIN_CPU1              U1               BL80     SOCKET4677_AZIFS054P001C01-SOCA
PVCCIN_CPU1              U1               BL82     SOCKET4677_AZIFS054P001C01-SOCA
PVCCIN_CPU1              U1               BL84     SOCKET4677_AZIFS054P001C01-SOCA
PVCCIN_CPU1              U1               BL86     SOCKET4677_AZIFS054P001C01-SOCA
PVCCIN_CPU1              U1               BL88     SOCKET4677_AZIFS054P001C01-SOCA
PVCCIN_CPU1              U1               BL90     SOCKET4677_AZIFS054P001C01-SOCA
PVCCIN_CPU1              U1               BM79     SOCKET4677_AZIFS054P001C01-SOCA
PVCCIN_CPU1              U1               BM81     SOCKET4677_AZIFS054P001C01-SOCA
PVCCIN_CPU1              U1               BM83     SOCKET4677_AZIFS054P001C01-SOCA
PVCCIN_CPU1              U1               BM85     SOCKET4677_AZIFS054P001C01-SOCA
PVCCIN_CPU1              U1               BM87     SOCKET4677_AZIFS054P001C01-SOCA
PVCCIN_CPU1              U1               BM89     SOCKET4677_AZIFS054P001C01-SOCA
PVCCIN_CPU1              U1               BM91     SOCKET4677_AZIFS054P001C01-SOCA
PVCCIN_CPU1              U1               BN33     SOCKET4677_AZIFS054P001C01-SOCA
PVCCIN_CPU1              U1               BN35     SOCKET4677_AZIFS054P001C01-SOCA
PVCCIN_CPU1              U1               BN37     SOCKET4677_AZIFS054P001C01-SOCA
PVCCIN_CPU1              U1               BN39     SOCKET4677_AZIFS054P001C01-SOCA
PVCCIN_CPU1              U1               BN41     SOCKET4677_AZIFS054P001C01-SOCA
PVCCIN_CPU1              U1               BN43     SOCKET4677_AZIFS054P001C01-SOCA
PVCCIN_CPU1              U1               BN45     SOCKET4677_AZIFS054P001C01-SOCA
PVCCIN_CPU1              U1               BN48     SOCKET4677_AZIFS054P001C01-SOCA
PVCCIN_CPU1              U1               BN50     SOCKET4677_AZIFS054P001C01-SOCA
PVCCIN_CPU1              U1               BN52     SOCKET4677_AZIFS054P001C01-SOCA
PVCCIN_CPU1              U1               BN54     SOCKET4677_AZIFS054P001C01-SOCA
PVCCIN_CPU1              U1               BN56     SOCKET4677_AZIFS054P001C01-SOCA
PVCCIN_CPU1              U1               BN58     SOCKET4677_AZIFS054P001C01-SOCA
PVCCIN_CPU1              U1               BN60     SOCKET4677_AZIFS054P001C01-SOCA
PVCCIN_CPU1              U1               BN78     SOCKET4677_AZIFS054P001C01-SOCA
PVCCIN_CPU1              U1               BN80     SOCKET4677_AZIFS054P001C01-SOCA
PVCCIN_CPU1              U1               BN82     SOCKET4677_AZIFS054P001C01-SOCA
PVCCIN_CPU1              U1               BN84     SOCKET4677_AZIFS054P001C01-SOCA
PVCCIN_CPU1              U1               BN86     SOCKET4677_AZIFS054P001C01-SOCA
PVCCIN_CPU1              U1               BN88     SOCKET4677_AZIFS054P001C01-SOCA
PVCCIN_CPU1              U1               BN90     SOCKET4677_AZIFS054P001C01-SOCA
PVCCIN_CPU1              U1               BP32     SOCKET4677_AZIFS054P001C01-SOCA
PVCCIN_CPU1              U1               BP34     SOCKET4677_AZIFS054P001C01-SOCA
PVCCIN_CPU1              U1               BP36     SOCKET4677_AZIFS054P001C01-SOCA
PVCCIN_CPU1              U1               BP38     SOCKET4677_AZIFS054P001C01-SOCA
PVCCIN_CPU1              U1               BP40     SOCKET4677_AZIFS054P001C01-SOCA
PVCCIN_CPU1              U1               BP42     SOCKET4677_AZIFS054P001C01-SOCA
PVCCIN_CPU1              U1               BP44     SOCKET4677_AZIFS054P001C01-SOCA
PVCCIN_CPU1              U1               BP47     SOCKET4677_AZIFS054P001C01-SOCA
PVCCIN_CPU1              U1               BP49     SOCKET4677_AZIFS054P001C01-SOCA
PVCCIN_CPU1              U1               BP51     SOCKET4677_AZIFS054P001C01-SOCA
PVCCIN_CPU1              U1               BP53     SOCKET4677_AZIFS054P001C01-SOCA
PVCCIN_CPU1              U1               BP55     SOCKET4677_AZIFS054P001C01-SOCA
PVCCIN_CPU1              U1               BP57     SOCKET4677_AZIFS054P001C01-SOCA
PVCCIN_CPU1              U1               BP59     SOCKET4677_AZIFS054P001C01-SOCA
PVCCIN_CPU1              U1               BP61     SOCKET4677_AZIFS054P001C01-SOCA
PVCCIN_CPU1              U1               BP79     SOCKET4677_AZIFS054P001C01-SOCA
PVCCIN_CPU1              U1               BP81     SOCKET4677_AZIFS054P001C01-SOCA
PVCCIN_CPU1              U1               BP83     SOCKET4677_AZIFS054P001C01-SOCA
PVCCIN_CPU1              U1               BP85     SOCKET4677_AZIFS054P001C01-SOCA
PVCCIN_CPU1              U1               BP87     SOCKET4677_AZIFS054P001C01-SOCA
PVCCIN_CPU1              U1               BP89     SOCKET4677_AZIFS054P001C01-SOCA
PVCCIN_CPU1              U1               BR60     SOCKET4677_AZIFS054P001C01-SOCA
PVCCIN_CPU1              U1               BR62     SOCKET4677_AZIFS054P001C01-SOCA
PVCCIN_CPU1              U1               BR78     SOCKET4677_AZIFS054P001C01-SOCA
PVCCIN_CPU1              U1               BT32     SOCKET4677_AZIFS054P001C01-SOCA
PVCCIN_CPU1              U1               BT34     SOCKET4677_AZIFS054P001C01-SOCA
PVCCIN_CPU1              U1               BT36     SOCKET4677_AZIFS054P001C01-SOCA
PVCCIN_CPU1              U1               BT38     SOCKET4677_AZIFS054P001C01-SOCA
PVCCIN_CPU1              U1               BT40     SOCKET4677_AZIFS054P001C01-SOCA
PVCCIN_CPU1              U1               BT42     SOCKET4677_AZIFS054P001C01-SOCA
PVCCIN_CPU1              U1               BT44     SOCKET4677_AZIFS054P001C01-SOCA
PVCCIN_CPU1              U1               BT47     SOCKET4677_AZIFS054P001C01-SOCA
PVCCIN_CPU1              U1               BT49     SOCKET4677_AZIFS054P001C01-SOCA
PVCCIN_CPU1              U1               BT51     SOCKET4677_AZIFS054P001C01-SOCA
PVCCIN_CPU1              U1               BT53     SOCKET4677_AZIFS054P001C01-SOCA
PVCCIN_CPU1              U1               BT55     SOCKET4677_AZIFS054P001C01-SOCA
PVCCIN_CPU1              U1               BT57     SOCKET4677_AZIFS054P001C01-SOCA
PVCCIN_CPU1              U1               BT59     SOCKET4677_AZIFS054P001C01-SOCA
PVCCIN_CPU1              U1               BT61     SOCKET4677_AZIFS054P001C01-SOCA
PVCCIN_CPU1              U1               BT63     SOCKET4677_AZIFS054P001C01-SOCA
PVCCIN_CPU1              U1               BT65     SOCKET4677_AZIFS054P001C01-SOCA
PVCCIN_CPU1              U1               BT67     SOCKET4677_AZIFS054P001C01-SOCA
PVCCIN_CPU1              U1               BT69     SOCKET4677_AZIFS054P001C01-SOCA
PVCCIN_CPU1              U1               BT71     SOCKET4677_AZIFS054P001C01-SOCA
PVCCIN_CPU1              U1               BT73     SOCKET4677_AZIFS054P001C01-SOCA
PVCCIN_CPU1              U1               BT75     SOCKET4677_AZIFS054P001C01-SOCA
PVCCIN_CPU1              U1               BT77     SOCKET4677_AZIFS054P001C01-SOCA
PVCCIN_CPU1              U1               BT79     SOCKET4677_AZIFS054P001C01-SOCA
PVCCIN_CPU1              U1               BT81     SOCKET4677_AZIFS054P001C01-SOCA
PVCCIN_CPU1              U1               BT83     SOCKET4677_AZIFS054P001C01-SOCA
PVCCIN_CPU1              U1               BT85     SOCKET4677_AZIFS054P001C01-SOCA
PVCCIN_CPU1              U1               BT87     SOCKET4677_AZIFS054P001C01-SOCA
PVCCIN_CPU1              U1               BT89     SOCKET4677_AZIFS054P001C01-SOCA
PVCCIN_CPU1              U1               BU33     SOCKET4677_AZIFS054P001C01-SOCA
PVCCIN_CPU1              U1               BU35     SOCKET4677_AZIFS054P001C01-SOCA
PVCCIN_CPU1              U1               BU37     SOCKET4677_AZIFS054P001C01-SOCA
PVCCIN_CPU1              U1               BU39     SOCKET4677_AZIFS054P001C01-SOCA
PVCCIN_CPU1              U1               BU41     SOCKET4677_AZIFS054P001C01-SOCA
PVCCIN_CPU1              U1               BU43     SOCKET4677_AZIFS054P001C01-SOCA
PVCCIN_CPU1              U1               BU45     SOCKET4677_AZIFS054P001C01-SOCA
PVCCIN_CPU1              U1               BU48     SOCKET4677_AZIFS054P001C01-SOCA
PVCCIN_CPU1              U1               BU50     SOCKET4677_AZIFS054P001C01-SOCA
PVCCIN_CPU1              U1               BU52     SOCKET4677_AZIFS054P001C01-SOCA
PVCCIN_CPU1              U1               BU54     SOCKET4677_AZIFS054P001C01-SOCA
PVCCIN_CPU1              U1               BU56     SOCKET4677_AZIFS054P001C01-SOCA
PVCCIN_CPU1              U1               BU58     SOCKET4677_AZIFS054P001C01-SOCA
PVCCIN_CPU1              U1               BU60     SOCKET4677_AZIFS054P001C01-SOCA
PVCCIN_CPU1              U1               BU62     SOCKET4677_AZIFS054P001C01-SOCA
PVCCIN_CPU1              U1               BU64     SOCKET4677_AZIFS054P001C01-SOCA
PVCCIN_CPU1              U1               BU66     SOCKET4677_AZIFS054P001C01-SOCA
PVCCIN_CPU1              U1               BU68     SOCKET4677_AZIFS054P001C01-SOCA
PVCCIN_CPU1              U1               BU70     SOCKET4677_AZIFS054P001C01-SOCA
PVCCIN_CPU1              U1               BU72     SOCKET4677_AZIFS054P001C01-SOCA
PVCCIN_CPU1              U1               BU74     SOCKET4677_AZIFS054P001C01-SOCA
PVCCIN_CPU1              U1               BU76     SOCKET4677_AZIFS054P001C01-SOCA
PVCCIN_CPU1              U1               BU78     SOCKET4677_AZIFS054P001C01-SOCA
PVCCIN_CPU1              U1               BU80     SOCKET4677_AZIFS054P001C01-SOCA
PVCCIN_CPU1              U1               BU82     SOCKET4677_AZIFS054P001C01-SOCA
PVCCIN_CPU1              U1               BU84     SOCKET4677_AZIFS054P001C01-SOCA
PVCCIN_CPU1              U1               BU86     SOCKET4677_AZIFS054P001C01-SOCA
PVCCIN_CPU1              U1               BU88     SOCKET4677_AZIFS054P001C01-SOCA
PVCCIN_CPU1              U1               BU90     SOCKET4677_AZIFS054P001C01-SOCA
PVCCIN_CPU1              U1               BV32     SOCKET4677_AZIFS054P001C01-SOCA
PVCCIN_CPU1              U1               BV34     SOCKET4677_AZIFS054P001C01-SOCA
PVCCIN_CPU1              U1               BV36     SOCKET4677_AZIFS054P001C01-SOCA
PVCCIN_CPU1              U1               BV38     SOCKET4677_AZIFS054P001C01-SOCA
PVCCIN_CPU1              U1               BV40     SOCKET4677_AZIFS054P001C01-SOCA
PVCCIN_CPU1              U1               BV42     SOCKET4677_AZIFS054P001C01-SOCA
PVCCIN_CPU1              U1               BV44     SOCKET4677_AZIFS054P001C01-SOCA
PVCCIN_CPU1              U1               BV47     SOCKET4677_AZIFS054P001C01-SOCA
PVCCIN_CPU1              U1               BV49     SOCKET4677_AZIFS054P001C01-SOCA
PVCCIN_CPU1              U1               BV51     SOCKET4677_AZIFS054P001C01-SOCA
PVCCIN_CPU1              U1               BV53     SOCKET4677_AZIFS054P001C01-SOCA
PVCCIN_CPU1              U1               BV55     SOCKET4677_AZIFS054P001C01-SOCA
PVCCIN_CPU1              U1               BV57     SOCKET4677_AZIFS054P001C01-SOCA
PVCCIN_CPU1              U1               BV59     SOCKET4677_AZIFS054P001C01-SOCA
PVCCIN_CPU1              U1               BV61     SOCKET4677_AZIFS054P001C01-SOCA
PVCCIN_CPU1              U1               BV63     SOCKET4677_AZIFS054P001C01-SOCA
PVCCIN_CPU1              U1               BV65     SOCKET4677_AZIFS054P001C01-SOCA
PVCCIN_CPU1              U1               BV67     SOCKET4677_AZIFS054P001C01-SOCA
PVCCIN_CPU1              U1               BV69     SOCKET4677_AZIFS054P001C01-SOCA
PVCCIN_CPU1              U1               BV71     SOCKET4677_AZIFS054P001C01-SOCA
PVCCIN_CPU1              U1               BV73     SOCKET4677_AZIFS054P001C01-SOCA
PVCCIN_CPU1              U1               BV75     SOCKET4677_AZIFS054P001C01-SOCA
PVCCIN_CPU1              U1               BV77     SOCKET4677_AZIFS054P001C01-SOCA
PVCCIN_CPU1              U1               BV79     SOCKET4677_AZIFS054P001C01-SOCA
PVCCIN_CPU1              U1               BV81     SOCKET4677_AZIFS054P001C01-SOCA
PVCCIN_CPU1              U1               BV83     SOCKET4677_AZIFS054P001C01-SOCA
PVCCIN_CPU1              U1               BV85     SOCKET4677_AZIFS054P001C01-SOCA
PVCCIN_CPU1              U1               BV87     SOCKET4677_AZIFS054P001C01-SOCA
PVCCIN_CPU1              U1               BV89     SOCKET4677_AZIFS054P001C01-SOCA
PVCCIN_CPU1              U1               BW33     SOCKET4677_AZIFS054P001C01-SOCA
PVCCIN_CPU1              U1               BW35     SOCKET4677_AZIFS054P001C01-SOCA
PVCCIN_CPU1              U1               BW37     SOCKET4677_AZIFS054P001C01-SOCA
PVCCIN_CPU1              U1               BW39     SOCKET4677_AZIFS054P001C01-SOCA
PVCCIN_CPU1              U1               BW41     SOCKET4677_AZIFS054P001C01-SOCA
PVCCIN_CPU1              U1               BW43     SOCKET4677_AZIFS054P001C01-SOCA
PVCCIN_CPU1              U1               BW45     SOCKET4677_AZIFS054P001C01-SOCA
PVCCIN_CPU1              U1               BW48     SOCKET4677_AZIFS054P001C01-SOCA
PVCCIN_CPU1              U1               BW50     SOCKET4677_AZIFS054P001C01-SOCA
PVCCIN_CPU1              U1               BW52     SOCKET4677_AZIFS054P001C01-SOCA
PVCCIN_CPU1              U1               BW54     SOCKET4677_AZIFS054P001C01-SOCA
PVCCIN_CPU1              U1               BW56     SOCKET4677_AZIFS054P001C01-SOCA
PVCCIN_CPU1              U1               BW58     SOCKET4677_AZIFS054P001C01-SOCA
PVCCIN_CPU1              U1               BW60     SOCKET4677_AZIFS054P001C01-SOCA
PVCCIN_CPU1              U1               BW62     SOCKET4677_AZIFS054P001C01-SOCA
PVCCIN_CPU1              U1               BW64     SOCKET4677_AZIFS054P001C01-SOCA
PVCCIN_CPU1              U1               BW66     SOCKET4677_AZIFS054P001C01-SOCA
PVCCIN_CPU1              U1               BW68     SOCKET4677_AZIFS054P001C01-SOCA
PVCCIN_CPU1              U1               BW70     SOCKET4677_AZIFS054P001C01-SOCA
PVCCIN_CPU1              U1               BW72     SOCKET4677_AZIFS054P001C01-SOCA
PVCCIN_CPU1              U1               BW74     SOCKET4677_AZIFS054P001C01-SOCA
PVCCIN_CPU1              U1               BW76     SOCKET4677_AZIFS054P001C01-SOCA
PVCCIN_CPU1              U1               BW78     SOCKET4677_AZIFS054P001C01-SOCA
PVCCIN_CPU1              U1               BW80     SOCKET4677_AZIFS054P001C01-SOCA
PVCCIN_CPU1              U1               BW82     SOCKET4677_AZIFS054P001C01-SOCA
PVCCIN_CPU1              U1               BW84     SOCKET4677_AZIFS054P001C01-SOCA
PVCCIN_CPU1              U1               BW86     SOCKET4677_AZIFS054P001C01-SOCA
PVCCIN_CPU1              U1               BW88     SOCKET4677_AZIFS054P001C01-SOCA
PVCCIN_CPU1              U1               BW90     SOCKET4677_AZIFS054P001C01-SOCA
PVCCIN_CPU1              U1               BY32     SOCKET4677_AZIFS054P001C01-SOCA
PVCCIN_CPU1              U1               BY34     SOCKET4677_AZIFS054P001C01-SOCA
PVCCIN_CPU1              U1               BY36     SOCKET4677_AZIFS054P001C01-SOCA
PVCCIN_CPU1              U1               BY38     SOCKET4677_AZIFS054P001C01-SOCA
PVCCIN_CPU1              U1               BY40     SOCKET4677_AZIFS054P001C01-SOCA
PVCCIN_CPU1              U1               BY42     SOCKET4677_AZIFS054P001C01-SOCA
PVCCIN_CPU1              U1               BY44     SOCKET4677_AZIFS054P001C01-SOCA
PVCCIN_CPU1              U1               BY47     SOCKET4677_AZIFS054P001C01-SOCA
PVCCIN_CPU1              U1               BY49     SOCKET4677_AZIFS054P001C01-SOCA
PVCCIN_CPU1              U1               BY51     SOCKET4677_AZIFS054P001C01-SOCA
PVCCIN_CPU1              U1               BY53     SOCKET4677_AZIFS054P001C01-SOCA
PVCCIN_CPU1              U1               BY55     SOCKET4677_AZIFS054P001C01-SOCA
PVCCIN_CPU1              U1               BY57     SOCKET4677_AZIFS054P001C01-SOCA
PVCCIN_CPU1              U1               BY59     SOCKET4677_AZIFS054P001C01-SOCA
PVCCIN_CPU1              U1               BY61     SOCKET4677_AZIFS054P001C01-SOCA
PVCCIN_CPU1              U1               BY63     SOCKET4677_AZIFS054P001C01-SOCA
PVCCIN_CPU1              U1               BY65     SOCKET4677_AZIFS054P001C01-SOCA
PVCCIN_CPU1              U1               BY67     SOCKET4677_AZIFS054P001C01-SOCA
PVCCIN_CPU1              U1               BY69     SOCKET4677_AZIFS054P001C01-SOCA
PVCCIN_CPU1              U1               BY71     SOCKET4677_AZIFS054P001C01-SOCA
PVCCIN_CPU1              U1               BY73     SOCKET4677_AZIFS054P001C01-SOCA
PVCCIN_CPU1              U1               BY75     SOCKET4677_AZIFS054P001C01-SOCA
PVCCIN_CPU1              U1               BY77     SOCKET4677_AZIFS054P001C01-SOCA
PVCCIN_CPU1              U1               BY79     SOCKET4677_AZIFS054P001C01-SOCA
PVCCIN_CPU1              U1               BY81     SOCKET4677_AZIFS054P001C01-SOCA
PVCCIN_CPU1              U1               BY83     SOCKET4677_AZIFS054P001C01-SOCA
PVCCIN_CPU1              U1               BY85     SOCKET4677_AZIFS054P001C01-SOCA
PVCCIN_CPU1              U1               BY87     SOCKET4677_AZIFS054P001C01-SOCA
PVCCIN_CPU1              U1               BY89     SOCKET4677_AZIFS054P001C01-SOCA
PVCCIN_CPU1              U1               CA33     SOCKET4677_AZIFS054P001C01-SOCA
PVCCIN_CPU1              U1               CA35     SOCKET4677_AZIFS054P001C01-SOCA
PVCCIN_CPU1              U1               CA37     SOCKET4677_AZIFS054P001C01-SOCA
PVCCIN_CPU1              U1               CA39     SOCKET4677_AZIFS054P001C01-SOCA
PVCCIN_CPU1              U1               CA41     SOCKET4677_AZIFS054P001C01-SOCA
PVCCIN_CPU1              U1               CA43     SOCKET4677_AZIFS054P001C01-SOCA
PVCCIN_CPU1              U1               CA45     SOCKET4677_AZIFS054P001C01-SOCA
PVCCIN_CPU1              U1               CA48     SOCKET4677_AZIFS054P001C01-SOCA
PVCCIN_CPU1              U1               CA50     SOCKET4677_AZIFS054P001C01-SOCA
PVCCIN_CPU1              U1               CA52     SOCKET4677_AZIFS054P001C01-SOCA
PVCCIN_CPU1              U1               CA54     SOCKET4677_AZIFS054P001C01-SOCA
PVCCIN_CPU1              U1               CA56     SOCKET4677_AZIFS054P001C01-SOCA
PVCCIN_CPU1              U1               CA58     SOCKET4677_AZIFS054P001C01-SOCA
PVCCIN_CPU1              U1               CA60     SOCKET4677_AZIFS054P001C01-SOCA
PVCCIN_CPU1              U1               CA62     SOCKET4677_AZIFS054P001C01-SOCA
PVCCIN_CPU1              U1               CA64     SOCKET4677_AZIFS054P001C01-SOCA
PVCCIN_CPU1              U1               CA66     SOCKET4677_AZIFS054P001C01-SOCA
PVCCIN_CPU1              U1               CA68     SOCKET4677_AZIFS054P001C01-SOCA
PVCCIN_CPU1              U1               CA70     SOCKET4677_AZIFS054P001C01-SOCA
PVCCIN_CPU1              U1               CA72     SOCKET4677_AZIFS054P001C01-SOCA
PVCCIN_CPU1              U1               CA74     SOCKET4677_AZIFS054P001C01-SOCA
PVCCIN_CPU1              U1               CA76     SOCKET4677_AZIFS054P001C01-SOCA
PVCCIN_CPU1              U1               CA78     SOCKET4677_AZIFS054P001C01-SOCA
PVCCIN_CPU1              U1               CA80     SOCKET4677_AZIFS054P001C01-SOCA
PVCCIN_CPU1              U1               CA82     SOCKET4677_AZIFS054P001C01-SOCA
PVCCIN_CPU1              U1               CA84     SOCKET4677_AZIFS054P001C01-SOCA
PVCCIN_CPU1              U1               CA86     SOCKET4677_AZIFS054P001C01-SOCA
PVCCIN_CPU1              U1               CA88     SOCKET4677_AZIFS054P001C01-SOCA
PVCCIN_CPU1              U1               CA90     SOCKET4677_AZIFS054P001C01-SOCA
PVCCIN_CPU1              U1               CB61     SOCKET4677_AZIFS054P001C01-SOCA
PVCCIN_CPU1              U1               CB75     SOCKET4677_AZIFS054P001C01-SOCA
PVCCIN_CPU1              U1               CB77     SOCKET4677_AZIFS054P001C01-SOCA
PVCCIN_CPU1              U1               CC33     SOCKET4677_AZIFS054P001C01-SOCA
PVCCIN_CPU1              U1               CC35     SOCKET4677_AZIFS054P001C01-SOCA
PVCCIN_CPU1              U1               CC37     SOCKET4677_AZIFS054P001C01-SOCA
PVCCIN_CPU1              U1               CC39     SOCKET4677_AZIFS054P001C01-SOCA
PVCCIN_CPU1              U1               CC41     SOCKET4677_AZIFS054P001C01-SOCA
PVCCIN_CPU1              U1               CC43     SOCKET4677_AZIFS054P001C01-SOCA
PVCCIN_CPU1              U1               CC45     SOCKET4677_AZIFS054P001C01-SOCA
PVCCIN_CPU1              U1               CC48     SOCKET4677_AZIFS054P001C01-SOCA
PVCCIN_CPU1              U1               CC50     SOCKET4677_AZIFS054P001C01-SOCA
PVCCIN_CPU1              U1               CC52     SOCKET4677_AZIFS054P001C01-SOCA
PVCCIN_CPU1              U1               CC54     SOCKET4677_AZIFS054P001C01-SOCA
PVCCIN_CPU1              U1               CC56     SOCKET4677_AZIFS054P001C01-SOCA
PVCCIN_CPU1              U1               CC58     SOCKET4677_AZIFS054P001C01-SOCA
PVCCIN_CPU1              U1               CC60     SOCKET4677_AZIFS054P001C01-SOCA
PVCCIN_CPU1              U1               CC76     SOCKET4677_AZIFS054P001C01-SOCA
PVCCIN_CPU1              U1               CC78     SOCKET4677_AZIFS054P001C01-SOCA
PVCCIN_CPU1              U1               CC80     SOCKET4677_AZIFS054P001C01-SOCA
PVCCIN_CPU1              U1               CC82     SOCKET4677_AZIFS054P001C01-SOCA
PVCCIN_CPU1              U1               CC84     SOCKET4677_AZIFS054P001C01-SOCA
PVCCIN_CPU1              U1               CC86     SOCKET4677_AZIFS054P001C01-SOCA
PVCCIN_CPU1              U1               CC88     SOCKET4677_AZIFS054P001C01-SOCA
PVCCIN_CPU1              U1               CC90     SOCKET4677_AZIFS054P001C01-SOCA
PVCCIN_CPU1              U1               CD32     SOCKET4677_AZIFS054P001C01-SOCA
PVCCIN_CPU1              U1               CD34     SOCKET4677_AZIFS054P001C01-SOCA
PVCCIN_CPU1              U1               CD36     SOCKET4677_AZIFS054P001C01-SOCA
PVCCIN_CPU1              U1               CD38     SOCKET4677_AZIFS054P001C01-SOCA
PVCCIN_CPU1              U1               CD40     SOCKET4677_AZIFS054P001C01-SOCA
PVCCIN_CPU1              U1               CD42     SOCKET4677_AZIFS054P001C01-SOCA
PVCCIN_CPU1              U1               CD44     SOCKET4677_AZIFS054P001C01-SOCA
PVCCIN_CPU1              U1               CD47     SOCKET4677_AZIFS054P001C01-SOCA
PVCCIN_CPU1              U1               CD49     SOCKET4677_AZIFS054P001C01-SOCA
PVCCIN_CPU1              U1               CD51     SOCKET4677_AZIFS054P001C01-SOCA
PVCCIN_CPU1              U1               CD53     SOCKET4677_AZIFS054P001C01-SOCA
PVCCIN_CPU1              U1               CD55     SOCKET4677_AZIFS054P001C01-SOCA
PVCCIN_CPU1              U1               CD57     SOCKET4677_AZIFS054P001C01-SOCA
PVCCIN_CPU1              U1               CD59     SOCKET4677_AZIFS054P001C01-SOCA
PVCCIN_CPU1              U1               CD79     SOCKET4677_AZIFS054P001C01-SOCA
PVCCIN_CPU1              U1               CD81     SOCKET4677_AZIFS054P001C01-SOCA
PVCCIN_CPU1              U1               CD83     SOCKET4677_AZIFS054P001C01-SOCA
PVCCIN_CPU1              U1               CD85     SOCKET4677_AZIFS054P001C01-SOCA
PVCCIN_CPU1              U1               CD87     SOCKET4677_AZIFS054P001C01-SOCA
PVCCIN_CPU1              U1               CD89     SOCKET4677_AZIFS054P001C01-SOCA
PVCCIN_CPU1              U1               CE80     SOCKET4677_AZIFS054P001C01-SOCA
PVCCIN_CPU1              U1               CE82     SOCKET4677_AZIFS054P001C01-SOCA
PVCCIN_CPU1              U1               CE84     SOCKET4677_AZIFS054P001C01-SOCA
PVCCIN_CPU1              U1               CE86     SOCKET4677_AZIFS054P001C01-SOCA
PVCCIN_CPU1              U1               CE88     SOCKET4677_AZIFS054P001C01-SOCA
PVCCIN_CPU1              U1               CE90     SOCKET4677_AZIFS054P001C01-SOCA
PVCCIN_CPU1              U1               CF79     SOCKET4677_AZIFS054P001C01-SOCA
PVCCIN_CPU1              U1               CF81     SOCKET4677_AZIFS054P001C01-SOCA
PVCCIN_CPU1              U1               CF83     SOCKET4677_AZIFS054P001C01-SOCA
PVCCIN_CPU1              U1               CF85     SOCKET4677_AZIFS054P001C01-SOCA
PVCCIN_CPU1              U1               CF87     SOCKET4677_AZIFS054P001C01-SOCA
PVCCIN_CPU1              U1               CF89     SOCKET4677_AZIFS054P001C01-SOCA
PVCCIN_CPU1              U1               CF91     SOCKET4677_AZIFS054P001C01-SOCA
PVCCIN_CPU1              U1               CG80     SOCKET4677_AZIFS054P001C01-SOCA
PVCCIN_CPU1              U1               CG82     SOCKET4677_AZIFS054P001C01-SOCA
PVCCIN_CPU1              U1               CG84     SOCKET4677_AZIFS054P001C01-SOCA
PVCCIN_CPU1              U1               CG86     SOCKET4677_AZIFS054P001C01-SOCA
PVCCIN_CPU1              U1               CG88     SOCKET4677_AZIFS054P001C01-SOCA
PVCCIN_CPU1              U1               CG90     SOCKET4677_AZIFS054P001C01-SOCA
PVCCIN_CPU1              U1               CH81     SOCKET4677_AZIFS054P001C01-SOCA
PVCCIN_CPU1              U1               CH91     SOCKET4677_AZIFS054P001C01-SOCA
PVCCIN_CPU1              U1               CJ82     SOCKET4677_AZIFS054P001C01-SOCA
PVCCIN_CPU1              U1               CJ84     SOCKET4677_AZIFS054P001C01-SOCA
PVCCIN_CPU1              U1               CJ86     SOCKET4677_AZIFS054P001C01-SOCA
PVCCIN_CPU1              U1               CJ88     SOCKET4677_AZIFS054P001C01-SOCA
PVCCIN_CPU1              U1               CJ90     SOCKET4677_AZIFS054P001C01-SOCA
PVCCIN_CPU1              U1               CK83     SOCKET4677_AZIFS054P001C01-SOCA
PVCCIN_CPU1              U1               CK85     SOCKET4677_AZIFS054P001C01-SOCA
PVCCIN_CPU1              U1               CK87     SOCKET4677_AZIFS054P001C01-SOCA
PVCCIN_CPU1              U1               CK89     SOCKET4677_AZIFS054P001C01-SOCA
PVCCIN_CPU1              U1               CK91     SOCKET4677_AZIFS054P001C01-SOCA
PVCCIN_CPU1              U1               CL84     SOCKET4677_AZIFS054P001C01-SOCA
PVCCIN_CPU1              U1               CL86     SOCKET4677_AZIFS054P001C01-SOCA
PVCCIN_CPU1              U1               CL88     SOCKET4677_AZIFS054P001C01-SOCA
PVCCIN_CPU1              U1               CL90     SOCKET4677_AZIFS054P001C01-SOCA
PVCCIN_CPU1              U1               CM87     SOCKET4677_AZIFS054P001C01-SOCA
PVCCIN_CPU1              U1               CM89     SOCKET4677_AZIFS054P001C01-SOCA
PVCCIN_CPU1              U1               CM91     SOCKET4677_AZIFS054P001C01-SOCA
PVCCIN_CPU1              U1               CN88     SOCKET4677_AZIFS054P001C01-SOCA
PVCCIN_CPU1              U1               CN90     SOCKET4677_AZIFS054P001C01-SOCA
PVCCIN_CPU1              U1               CP89     SOCKET4677_AZIFS054P001C01-SOCA
PVCCIN_CPU1_ADDR         PR306            2        Q_RES_0402LF-28K,1%,1/16W,EMPTA
PVCCIN_CPU1_ADDR         PR318            1        Q_RES_0402LF-5.23K,1%,1/16W,CHA
PVCCIN_CPU1_ADDR         PU29             42       RAA229126GNPHA0-RAA229126GNP#HA
PVCCIN_CPU1_ATSEN        PC554            1        Q_CAP_0402-470PF,50V,10%,X7R,TA
PVCCIN_CPU1_ATSEN        PR637            1        Q_RES_0402LF-10K,1%,1/16W,EMPTB
PVCCIN_CPU1_ATSEN        PU23_P1_8        36       ISL99390FRZTR5935-ISL99390FRZ-A
PVCCIN_CPU1_ATSEN        PU24_P1_7        36       ISL99390FRZTR5935-ISL99390FRZ-A
PVCCIN_CPU1_ATSEN        PU25_P1_6        36       ISL99390FRZTR5935-ISL99390FRZ-A
PVCCIN_CPU1_ATSEN        PU26_P1_5        36       ISL99390FRZTR5935-ISL99390FRZ-A
PVCCIN_CPU1_ATSEN        PU27_P1_4        36       ISL99390FRZTR5935-ISL99390FRZ-A
PVCCIN_CPU1_ATSEN        PU28_P1_3        36       ISL99390FRZTR5935-ISL99390FRZ-A
PVCCIN_CPU1_ATSEN        PU29             43       RAA229126GNPHA0-RAA229126GNP#HA
PVCCIN_CPU1_ATSEN        PU30_P1_2        36       ISL99390FRZTR5935-ISL99390FRZ-A
PVCCIN_CPU1_ATSEN        PU31_P1_1        36       ISL99390FRZTR5935-ISL99390FRZ-A
PVCCIN_CPU1_ATSEN        PU75_P1_1        36       ISL99390FRZTR5935-ISL99390FRZ-A
PVCCIN_CPU1_ATSEN        PU76_P1_2        36       ISL99390FRZTR5935-ISL99390FRZ-A
PVCCIN_CPU1_ATSEN        PU77_P1_3        36       ISL99390FRZTR5935-ISL99390FRZ-A
PVCCIN_CPU1_ATSEN        PU78_P1_4        36       ISL99390FRZTR5935-ISL99390FRZ-A
PVCCIN_CPU1_CSPIN        PC547            1        Q_CAP_0402-0.1UF,25V,10%,EMPTYA
PVCCIN_CPU1_CSPIN        PR304            2        Q_RES_0402LF-0,5%,1/16W,EMPTY,A
PVCCIN_CPU1_CSPIN        PR305            1        Q_RES_0402LF-0,5%,1/16W,CHIP,CA
PVCCIN_CPU1_CSPIN        PU29             45       RAA229126GNPHA0-RAA229126GNP#HA
PVCCIN_CPU1_EN_R         PC550            1        Q_CAP_0402-1000PF,50V,5%,X7R,TA
PVCCIN_CPU1_EN_R         PR309            2        Q_RES_0402LF-0,5%,1/16W,CHIP,CA
PVCCIN_CPU1_EN_R         PU29             17       RAA229126GNPHA0-RAA229126GNP#HA
PVCCIN_CPU1_IMON1        PU29             27       RAA229126GNPHA0-RAA229126GNP#HA
PVCCIN_CPU1_IMON1        PU31_P1_1        38       ISL99390FRZTR5935-ISL99390FRZ-A
PVCCIN_CPU1_IMON2        PU29             28       RAA229126GNPHA0-RAA229126GNP#HA
PVCCIN_CPU1_IMON2        PU30_P1_2        38       ISL99390FRZTR5935-ISL99390FRZ-A
PVCCIN_CPU1_IMON3        PU28_P1_3        38       ISL99390FRZTR5935-ISL99390FRZ-A
PVCCIN_CPU1_IMON3        PU29             29       RAA229126GNPHA0-RAA229126GNP#HA
PVCCIN_CPU1_IMON4        PU27_P1_4        38       ISL99390FRZTR5935-ISL99390FRZ-A
PVCCIN_CPU1_IMON4        PU29             30       RAA229126GNPHA0-RAA229126GNP#HA
PVCCIN_CPU1_IMON5        PU26_P1_5        38       ISL99390FRZTR5935-ISL99390FRZ-A
PVCCIN_CPU1_IMON5        PU29             31       RAA229126GNPHA0-RAA229126GNP#HA
PVCCIN_CPU1_IMON6        PU25_P1_6        38       ISL99390FRZTR5935-ISL99390FRZ-A
PVCCIN_CPU1_IMON6        PU29             32       RAA229126GNPHA0-RAA229126GNP#HA
PVCCIN_CPU1_IMON7        PU24_P1_7        38       ISL99390FRZTR5935-ISL99390FRZ-A
PVCCIN_CPU1_IMON7        PU29             33       RAA229126GNPHA0-RAA229126GNP#HA
PVCCIN_CPU1_IMON8        PU23_P1_8        38       ISL99390FRZTR5935-ISL99390FRZ-A
PVCCIN_CPU1_IMON8        PU29             34       RAA229126GNPHA0-RAA229126GNP#HA
PVCCIN_CPU1_ISYS_R       PR452            1        Q_RES_0402LF-0,5%,1/16W,EMPTY,A
PVCCIN_CPU1_ISYS_R       PR453            1        Q_RES_0402LF-0,5%,1/16W,CHIP,CA
PVCCIN_CPU1_ISYS_R       PU29             44       RAA229126GNPHA0-RAA229126GNP#HA
PVCCIN_CPU1_LSET1        PR326            1        Q_RES_0402LF-8.87K,1%,1/16W,EMA
PVCCIN_CPU1_LSET1        PU31_P1_1        37       ISL99390FRZTR5935-ISL99390FRZ-A
PVCCIN_CPU1_LSET2        PR325            1        Q_RES_0402LF-8.87K,1%,1/16W,EMA
PVCCIN_CPU1_LSET2        PU30_P1_2        37       ISL99390FRZTR5935-ISL99390FRZ-A
PVCCIN_CPU1_LSET3        PR298            1        Q_RES_0402LF-8.87K,1%,1/16W,EMA
PVCCIN_CPU1_LSET3        PU28_P1_3        37       ISL99390FRZTR5935-ISL99390FRZ-A
PVCCIN_CPU1_LSET4        PR297            1        Q_RES_0402LF-8.87K,1%,1/16W,EMA
PVCCIN_CPU1_LSET4        PU27_P1_4        37       ISL99390FRZTR5935-ISL99390FRZ-A
PVCCIN_CPU1_LSET5        PR292            1        Q_RES_0402LF-8.87K,1%,1/16W,EMA
PVCCIN_CPU1_LSET5        PU26_P1_5        37       ISL99390FRZTR5935-ISL99390FRZ-A
PVCCIN_CPU1_LSET6        PR291            1        Q_RES_0402LF-8.87K,1%,1/16W,EMA
PVCCIN_CPU1_LSET6        PU25_P1_6        37       ISL99390FRZTR5935-ISL99390FRZ-A
PVCCIN_CPU1_LSET7        PR286            1        Q_RES_0402LF-8.87K,1%,1/16W,EMA
PVCCIN_CPU1_LSET7        PU24_P1_7        37       ISL99390FRZTR5935-ISL99390FRZ-A
PVCCIN_CPU1_LSET8        PR285            1        Q_RES_0402LF-8.87K,1%,1/16W,EMA
PVCCIN_CPU1_LSET8        PU23_P1_8        37       ISL99390FRZTR5935-ISL99390FRZ-A
PVCCIN_CPU1_PIN_ALERT    PR241            2        Q_RES_0402LF-1K,1%,1/16W,CHIP,A
PVCCIN_CPU1_PIN_ALERT    PU29             19       RAA229126GNPHA0-RAA229126GNP#HA
PVCCIN_CPU1_PVCC         PC481_P1_8       1        Q_CAP_C0402-2.2UF,10V,10%,X6S,A
PVCCIN_CPU1_PVCC         PC482_P1_7       1        Q_CAP_C0402-2.2UF,10V,10%,X6S,A
PVCCIN_CPU1_PVCC         PC503_P1_6       1        Q_CAP_C0402-2.2UF,10V,10%,X6S,A
PVCCIN_CPU1_PVCC         PC504_P1_5       1        Q_CAP_C0402-2.2UF,10V,10%,X6S,A
PVCCIN_CPU1_PVCC         PC525_P1_4       1        Q_CAP_C0402-2.2UF,10V,10%,X6S,A
PVCCIN_CPU1_PVCC         PC526_P1_3       1        Q_CAP_C0402-2.2UF,10V,10%,X6S,A
PVCCIN_CPU1_PVCC         PC558_P1_2       1        Q_CAP_C0402-2.2UF,10V,10%,X6S,A
PVCCIN_CPU1_PVCC         PC559_P1_1       1        Q_CAP_C0402-2.2UF,10V,10%,X6S,A
PVCCIN_CPU1_PVCC         PR287            1        Q_RES_0402LF-2.2,1%,1/16W,CHIPA
PVCCIN_CPU1_PVCC         PR288            1        Q_RES_0402LF-2.2,1%,1/16W,CHIPA
PVCCIN_CPU1_PVCC         PR293            1        Q_RES_0402LF-2.2,1%,1/16W,CHIPA
PVCCIN_CPU1_PVCC         PR294            1        Q_RES_0402LF-2.2,1%,1/16W,CHIPA
PVCCIN_CPU1_PVCC         PR299            1        Q_RES_0402LF-2.2,1%,1/16W,CHIPA
PVCCIN_CPU1_PVCC         PR300            1        Q_RES_0402LF-2.2,1%,1/16W,CHIPA
PVCCIN_CPU1_PVCC         PR327            1        Q_RES_0402LF-2.2,1%,1/16W,CHIPA
PVCCIN_CPU1_PVCC         PR328            1        Q_RES_0402LF-2.2,1%,1/16W,CHIPA
PVCCIN_CPU1_PVCC         PR639            2        Q_RES_0402LF-0,5%,1/16W,CHIP,CA
PVCCIN_CPU1_PVCC         PR640            2        Q_RES_0402LF-0,5%,1/16W,EMPTY,A
PVCCIN_CPU1_PVCC         PU23_P1_8        4        ISL99390FRZTR5935-ISL99390FRZ-A
PVCCIN_CPU1_PVCC         PU24_P1_7        4        ISL99390FRZTR5935-ISL99390FRZ-A
PVCCIN_CPU1_PVCC         PU25_P1_6        4        ISL99390FRZTR5935-ISL99390FRZ-A
PVCCIN_CPU1_PVCC         PU26_P1_5        4        ISL99390FRZTR5935-ISL99390FRZ-A
PVCCIN_CPU1_PVCC         PU27_P1_4        4        ISL99390FRZTR5935-ISL99390FRZ-A
PVCCIN_CPU1_PVCC         PU28_P1_3        4        ISL99390FRZTR5935-ISL99390FRZ-A
PVCCIN_CPU1_PVCC         PU30_P1_2        4        ISL99390FRZTR5935-ISL99390FRZ-A
PVCCIN_CPU1_PVCC         PU31_P1_1        4        ISL99390FRZTR5935-ISL99390FRZ-A
PVCCIN_CPU1_PWM1         PU29             12       RAA229126GNPHA0-RAA229126GNP#HA
PVCCIN_CPU1_PWM1         PU31_P1_1        34       ISL99390FRZTR5935-ISL99390FRZ-A
PVCCIN_CPU1_PWM2         PU29             11       RAA229126GNPHA0-RAA229126GNP#HA
PVCCIN_CPU1_PWM2         PU30_P1_2        34       ISL99390FRZTR5935-ISL99390FRZ-A
PVCCIN_CPU1_PWM3         PU28_P1_3        34       ISL99390FRZTR5935-ISL99390FRZ-A
PVCCIN_CPU1_PWM3         PU29             10       RAA229126GNPHA0-RAA229126GNP#HA
PVCCIN_CPU1_PWM4         PU27_P1_4        34       ISL99390FRZTR5935-ISL99390FRZ-A
PVCCIN_CPU1_PWM4         PU29             9        RAA229126GNPHA0-RAA229126GNP#HA
PVCCIN_CPU1_PWM5         PU26_P1_5        34       ISL99390FRZTR5935-ISL99390FRZ-A
PVCCIN_CPU1_PWM5         PU29             8        RAA229126GNPHA0-RAA229126GNP#HA
PVCCIN_CPU1_PWM6         PU25_P1_6        34       ISL99390FRZTR5935-ISL99390FRZ-A
PVCCIN_CPU1_PWM6         PU29             7        RAA229126GNPHA0-RAA229126GNP#HA
PVCCIN_CPU1_PWM7         PU24_P1_7        34       ISL99390FRZTR5935-ISL99390FRZ-A
PVCCIN_CPU1_PWM7         PU29             6        RAA229126GNPHA0-RAA229126GNP#HA
PVCCIN_CPU1_PWM8         PU23_P1_8        34       ISL99390FRZTR5935-ISL99390FRZ-A
PVCCIN_CPU1_PWM8         PU29             5        RAA229126GNPHA0-RAA229126GNP#HA
PVCCIN_CPU1_VCC          PC552            1        Q_CAP_C0402-100NF,50V,10%,EMPTA
PVCCIN_CPU1_VCC          PC555            1        Q_CAP_C0402-1UF,16V,10%,X6S,CHA
PVCCIN_CPU1_VCC          PR323            1        Q_RES_0402LF-1,1%,1/16W,CHIP,CA
PVCCIN_CPU1_VCC          PU29             47       RAA229126GNPHA0-RAA229126GNP#HA
PVCCIN_CPU1_VDD1         PC557            1        Q_CAP_C0402-2.2UF,10V,10%,X6S,A
PVCCIN_CPU1_VDD1         PR328            2        Q_RES_0402LF-2.2,1%,1/16W,CHIPA
PVCCIN_CPU1_VDD1         PU31_P1_1        3        ISL99390FRZTR5935-ISL99390FRZ-A
PVCCIN_CPU1_VDD1         PU31_P1_1        35       ISL99390FRZTR5935-ISL99390FRZ-A
PVCCIN_CPU1_VDD2         PC556            1        Q_CAP_C0402-2.2UF,10V,10%,X6S,A
PVCCIN_CPU1_VDD2         PR327            2        Q_RES_0402LF-2.2,1%,1/16W,CHIPA
PVCCIN_CPU1_VDD2         PU30_P1_2        3        ISL99390FRZTR5935-ISL99390FRZ-A
PVCCIN_CPU1_VDD2         PU30_P1_2        35       ISL99390FRZTR5935-ISL99390FRZ-A
PVCCIN_CPU1_VDD3         PC524            1        Q_CAP_C0402-2.2UF,10V,10%,X6S,A
PVCCIN_CPU1_VDD3         PR300            2        Q_RES_0402LF-2.2,1%,1/16W,CHIPA
PVCCIN_CPU1_VDD3         PU28_P1_3        3        ISL99390FRZTR5935-ISL99390FRZ-A
PVCCIN_CPU1_VDD3         PU28_P1_3        35       ISL99390FRZTR5935-ISL99390FRZ-A
PVCCIN_CPU1_VDD4         PC523            1        Q_CAP_C0402-2.2UF,10V,10%,X6S,A
PVCCIN_CPU1_VDD4         PR299            2        Q_RES_0402LF-2.2,1%,1/16W,CHIPA
PVCCIN_CPU1_VDD4         PU27_P1_4        3        ISL99390FRZTR5935-ISL99390FRZ-A
PVCCIN_CPU1_VDD4         PU27_P1_4        35       ISL99390FRZTR5935-ISL99390FRZ-A
PVCCIN_CPU1_VDD5         PC502            1        Q_CAP_C0402-2.2UF,10V,10%,X6S,A
PVCCIN_CPU1_VDD5         PR294            2        Q_RES_0402LF-2.2,1%,1/16W,CHIPA
PVCCIN_CPU1_VDD5         PU26_P1_5        3        ISL99390FRZTR5935-ISL99390FRZ-A
PVCCIN_CPU1_VDD5         PU26_P1_5        35       ISL99390FRZTR5935-ISL99390FRZ-A
PVCCIN_CPU1_VDD6         PC501            1        Q_CAP_C0402-2.2UF,10V,10%,X6S,A
PVCCIN_CPU1_VDD6         PR293            2        Q_RES_0402LF-2.2,1%,1/16W,CHIPA
PVCCIN_CPU1_VDD6         PU25_P1_6        3        ISL99390FRZTR5935-ISL99390FRZ-A
PVCCIN_CPU1_VDD6         PU25_P1_6        35       ISL99390FRZTR5935-ISL99390FRZ-A
PVCCIN_CPU1_VDD7         PC480            1        Q_CAP_C0402-2.2UF,10V,10%,X6S,A
PVCCIN_CPU1_VDD7         PR288            2        Q_RES_0402LF-2.2,1%,1/16W,CHIPA
PVCCIN_CPU1_VDD7         PU24_P1_7        3        ISL99390FRZTR5935-ISL99390FRZ-A
PVCCIN_CPU1_VDD7         PU24_P1_7        35       ISL99390FRZTR5935-ISL99390FRZ-A
PVCCIN_CPU1_VDD8         PC479            1        Q_CAP_C0402-2.2UF,10V,10%,X6S,A
PVCCIN_CPU1_VDD8         PR287            2        Q_RES_0402LF-2.2,1%,1/16W,CHIPA
PVCCIN_CPU1_VDD8         PU23_P1_8        3        ISL99390FRZTR5935-ISL99390FRZ-A
PVCCIN_CPU1_VDD8         PU23_P1_8        35       ISL99390FRZTR5935-ISL99390FRZ-A
PVCCIN_CPU1_VIN_CSNIN    PC548            1        Q_CAP_0402-0.1UF,25V,10%,X7R,CA
PVCCIN_CPU1_VIN_CSNIN    PR303            2        Q_RES_0402LF-0,5%,1/16W,CHIP,CA
PVCCIN_CPU1_VIN_CSNIN    PR313            1        Q_RES_0402LF-1K,1%,1/16W,EMPTYA
PVCCIN_CPU1_VIN_CSNIN    PU29             46       RAA229126GNPHA0-RAA229126GNP#HA
PVCCIN_CPU1_VOS1         PR330            1        Q_RES_0402LF-0,5%,1/16W,CHIP,CA
PVCCIN_CPU1_VOS1         PU31_P1_1        1        ISL99390FRZTR5935-ISL99390FRZ-A
PVCCIN_CPU1_VOS2         PR329            1        Q_RES_0402LF-0,5%,1/16W,CHIP,CA
PVCCIN_CPU1_VOS2         PU30_P1_2        1        ISL99390FRZTR5935-ISL99390FRZ-A
PVCCIN_CPU1_VOS3         PR302            1        Q_RES_0402LF-0,5%,1/16W,CHIP,CA
PVCCIN_CPU1_VOS3         PU28_P1_3        1        ISL99390FRZTR5935-ISL99390FRZ-A
PVCCIN_CPU1_VOS4         PR301            1        Q_RES_0402LF-0,5%,1/16W,CHIP,CA
PVCCIN_CPU1_VOS4         PU27_P1_4        1        ISL99390FRZTR5935-ISL99390FRZ-A
PVCCIN_CPU1_VOS5         PR296            1        Q_RES_0402LF-0,5%,1/16W,CHIP,CA
PVCCIN_CPU1_VOS5         PU26_P1_5        1        ISL99390FRZTR5935-ISL99390FRZ-A
PVCCIN_CPU1_VOS6         PR295            1        Q_RES_0402LF-0,5%,1/16W,CHIP,CA
PVCCIN_CPU1_VOS6         PU25_P1_6        1        ISL99390FRZTR5935-ISL99390FRZ-A
PVCCIN_CPU1_VOS7         PR290            1        Q_RES_0402LF-0,5%,1/16W,CHIP,CA
PVCCIN_CPU1_VOS7         PU24_P1_7        1        ISL99390FRZTR5935-ISL99390FRZ-A
PVCCIN_CPU1_VOS8         PR289            1        Q_RES_0402LF-0,5%,1/16W,CHIP,CA
PVCCIN_CPU1_VOS8         PU23_P1_8        1        ISL99390FRZTR5935-ISL99390FRZ-A
PVCCIN_CPU1_VREF         PC553            1        Q_CAP_0402-4.7UF,6.3V,20%,X6S,A
PVCCIN_CPU1_VREF         PC1194           1        Q_CAP_C0402-1UF,16V,10%,X6S,CHA
PVCCIN_CPU1_VREF         PC1338           2        Q_CAP_0402-0.1UF,25V,10%,X7R,CA
PVCCIN_CPU1_VREF         PC1339           2        Q_CAP_0402-0.1UF,25V,10%,X7R,CA
PVCCIN_CPU1_VREF         PC1358           2        Q_CAP_0402-0.1UF,25V,10%,X7R,CA
PVCCIN_CPU1_VREF         PC1359           2        Q_CAP_0402-0.1UF,25V,10%,X7R,CA
PVCCIN_CPU1_VREF         PC1360           2        Q_CAP_0402-0.1UF,25V,10%,X7R,CA
PVCCIN_CPU1_VREF         PC1361           2        Q_CAP_0402-0.1UF,25V,10%,X7R,CA
PVCCIN_CPU1_VREF         PC1362           2        Q_CAP_0402-0.1UF,25V,10%,X7R,CA
PVCCIN_CPU1_VREF         PC1363           2        Q_CAP_0402-0.1UF,25V,10%,X7R,CA
PVCCIN_CPU1_VREF         PC1367           2        Q_CAP_0402-0.1UF,25V,10%,X7R,CA
PVCCIN_CPU1_VREF         PC1368           2        Q_CAP_0402-0.1UF,25V,10%,X7R,CA
PVCCIN_CPU1_VREF         PC1369           2        Q_CAP_0402-0.1UF,25V,10%,X7R,CA
PVCCIN_CPU1_VREF         PC1370           2        Q_CAP_0402-0.1UF,25V,10%,X7R,CA
PVCCIN_CPU1_VREF         PR306            1        Q_RES_0402LF-28K,1%,1/16W,EMPTA
PVCCIN_CPU1_VREF         PU23_P1_8        39       ISL99390FRZTR5935-ISL99390FRZ-A
PVCCIN_CPU1_VREF         PU24_P1_7        39       ISL99390FRZTR5935-ISL99390FRZ-A
PVCCIN_CPU1_VREF         PU25_P1_6        39       ISL99390FRZTR5935-ISL99390FRZ-A
PVCCIN_CPU1_VREF         PU26_P1_5        39       ISL99390FRZTR5935-ISL99390FRZ-A
PVCCIN_CPU1_VREF         PU27_P1_4        39       ISL99390FRZTR5935-ISL99390FRZ-A
PVCCIN_CPU1_VREF         PU28_P1_3        39       ISL99390FRZTR5935-ISL99390FRZ-A
PVCCIN_CPU1_VREF         PU29             48       RAA229126GNPHA0-RAA229126GNP#HA
PVCCIN_CPU1_VREF         PU30_P1_2        39       ISL99390FRZTR5935-ISL99390FRZ-A
PVCCIN_CPU1_VREF         PU31_P1_1        39       ISL99390FRZTR5935-ISL99390FRZ-A
PVCCIN_CPU1_VREF         PU75_P1_1        39       ISL99390FRZTR5935-ISL99390FRZ-A
PVCCIN_CPU1_VREF         PU76_P1_2        39       ISL99390FRZTR5935-ISL99390FRZ-A
PVCCIN_CPU1_VREF         PU77_P1_3        39       ISL99390FRZTR5935-ISL99390FRZ-A
PVCCIN_CPU1_VREF         PU78_P1_4        39       ISL99390FRZTR5935-ISL99390FRZ-A
PVCCIN_CPU1_VR_FAULT     PR243            2        Q_RES_0402LF-1K,1%,1/16W,CHIP,A
PVCCIN_CPU1_VR_FAULT     PU29             41       RAA229126GNPHA0-RAA229126GNP#HA
PVCCIO_PECI_BMC          J41              B28      SCONN168_623403212-SCONN168_6-A
PVCCIO_PECI_BMC          R142             2        Q_RES_0402LF-0,5%,1/16W,CHIP,CA
PVCCIO_PLDIO2            C1120            1        Q_CAP_0402-0.1UF,25V,10%,X7R,CA
PVCCIO_PLDIO2            C1129            1        Q_CAP_0402-0.1UF,25V,10%,X7R,CA
PVCCIO_PLDIO2            C1135            1        Q_CAP_0402-0.1UF,25V,10%,X7R,CA
PVCCIO_PLDIO2            R511             2        Q_RES_1206LF-0,5%,1/4W,CHIP,CSA
PVCCIO_PLDIO2            R512             2        Q_RES_1206LF-0,5%,1/4W,EMPTY,CA
PVCCIO_PLDIO2            U122             P11      10M04SAU324I7G-10M04SAU324I7G,A
PVCCIO_PLDIO2            U122             P12      10M04SAU324I7G-10M04SAU324I7G,A
PVCCIO_PLDIO5            C1160            1        Q_CAP_0402-0.1UF,25V,10%,X7R,CA
PVCCIO_PLDIO5            C1166            1        Q_CAP_0402-0.1UF,25V,10%,X7R,CA
PVCCIO_PLDIO5            C1169            1        Q_CAP_0402-0.1UF,25V,10%,X7R,CA
PVCCIO_PLDIO5            R513             2        Q_RES_1206LF-0,5%,1/4W,CHIP,CSA
PVCCIO_PLDIO5            R514             2        Q_RES_1206LF-0,5%,1/4W,EMPTY,CA
PVCCIO_PLDIO5            R1425            2        Q_RES_0402LF-100,1%,1/16W,CHIPA
PVCCIO_PLDIO5            R1426            2        Q_RES_0402LF-100,1%,1/16W,CHIPA
PVCCIO_PLDIO5            R1427            2        Q_RES_0402LF-100,1%,1/16W,CHIPA
PVCCIO_PLDIO5            R1428            2        Q_RES_0402LF-100,1%,1/16W,CHIPA
PVCCIO_PLDIO5            R1429            2        Q_RES_0402LF-100,1%,1/16W,CHIPA
PVCCIO_PLDIO5            R1430            2        Q_RES_0402LF-100,1%,1/16W,CHIPA
PVCCIO_PLDIO5            R1431            2        Q_RES_0402LF-150,1%,1/16W,CHIPA
PVCCIO_PLDIO5            R1432            2        Q_RES_0402LF-150,1%,1/16W,CHIPA
PVCCIO_PLDIO5            R1433            2        Q_RES_0402LF-150,1%,1/16W,CHIPA
PVCCIO_PLDIO5            U122             N9       10M04SAU324I7G-10M04SAU324I7G,A
PVCCIO_PLDIO5            U122             P7       10M04SAU324I7G-10M04SAU324I7G,A
PVCCIO_PLDIO5            U122             P8       10M04SAU324I7G-10M04SAU324I7G,A
PVCCIO_PLDIO5            U122             P9       10M04SAU324I7G-10M04SAU324I7G,A
PVNN_MAIN_CPU0           C395             1        Q_CAP_C0805-100UF,4V,20%,X6S,CA
PVNN_MAIN_CPU0           C590             1        Q_CAP_C0402-22UF,4V,20%,X6S,CHA
PVNN_MAIN_CPU0           C1362            1        Q_CAP_C0402-22UF,4V,20%,X6S,CHA
PVNN_MAIN_CPU0           C1363            1        Q_CAP_C0402-22UF,4V,20%,X6S,CHA
PVNN_MAIN_CPU0           C1364            1        Q_CAP_C0402-22UF,4V,20%,X6S,CHA
PVNN_MAIN_CPU0           C1399            1        Q_CAP_C0805-100UF,4V,20%,X6S,CA
PVNN_MAIN_CPU0           C1400            1        Q_CAP_C0805-100UF,4V,20%,X6S,CA
PVNN_MAIN_CPU0           C1405            1        Q_CAP_C0603-47UF,2.5V,20%,X6S,A
PVNN_MAIN_CPU0           C1406            1        Q_CAP_C0603-47UF,2.5V,20%,X6S,A
PVNN_MAIN_CPU0           C1407            1        Q_CAP_C0603-47UF,2.5V,20%,X6S,A
PVNN_MAIN_CPU0           PC237            2        Q_CAP_0402-680PF,50V,10%,X7R,TA
PVNN_MAIN_CPU0           PC1206           1        Q_CAP_0805-22UF,4V,20%,X6S,TMPA
PVNN_MAIN_CPU0           PC1276           1        Q_CAP_C0402-100NF,50V,10%,X7R,A
PVNN_MAIN_CPU0           PC1277           1        Q_CAP_0805-22UF,4V,20%,X6S,TMPA
PVNN_MAIN_CPU0           PC1278           1        Q_CAP_0805-22UF,4V,20%,X6S,TMPA
PVNN_MAIN_CPU0           PC1279           1        Q_CAP_0805-22UF,4V,20%,X6S,TMPA
PVNN_MAIN_CPU0           PL120            2        Q_INDUCTOR_SMLF-1UH,IND,CV-10BA
PVNN_MAIN_CPU0           PR501            2        Q_RES_0402LF-8.25K,1%,1/16W,CHA
PVNN_MAIN_CPU0           R324             1        Q_RES_1206LF-0,,1/2W,CHIP,CS00A
PVNN_MAIN_CPU0           U2               BA19     SOCKET4677_AZIFS054P001C01-SOCA
PVNN_MAIN_CPU0           U2               BE19     SOCKET4677_AZIFS054P001C01-SOCA
PVNN_MAIN_CPU0           U2               BJ19     SOCKET4677_AZIFS054P001C01-SOCA
PVNN_MAIN_CPU0           U2               BN19     SOCKET4677_AZIFS054P001C01-SOCA
PVNN_MAIN_CPU0_CS        PR1303           1        Q_RES_0402LF-9.09K,1%,1/16W,CHA
PVNN_MAIN_CPU0_CS        PU81             4        MPQ8626GDZ-MPQ8626GD-Z,SMLF,ICA
PVNN_MAIN_CPU0_FB_RC     PC237            1        Q_CAP_0402-680PF,50V,10%,X7R,TA
PVNN_MAIN_CPU0_FB_RC     PR50             1        Q_RES_0402LF-12.4K,1%,1/16W,CHA
PVNN_MAIN_CPU0_FB_RC     PR501            1        Q_RES_0402LF-8.25K,1%,1/16W,CHA
PVNN_MAIN_CPU0_FB_RC     PU81             6        MPQ8626GDZ-MPQ8626GD-Z,SMLF,ICA
PVNN_MAIN_CPU0_MODE      PR1301           1        Q_RES_0402LF-60.4K,1%,1/16W,CHA
PVNN_MAIN_CPU0_MODE      PU81             12       MPQ8626GDZ-MPQ8626GD-Z,SMLF,ICA
PVNN_MAIN_CPU0_REF       PC27             1        Q_CAP_0402-3300PF,50V,10%,X7R,A
PVNN_MAIN_CPU0_REF       PU81             8        MPQ8626GDZ-MPQ8626GD-Z,SMLF,ICA
PVNN_MAIN_CPU0_VCC       PC2221           1        Q_CAP_C0402-1UF,25V,10%,X6S,CHA
PVNN_MAIN_CPU0_VCC       PU81             13       MPQ8626GDZ-MPQ8626GD-Z,SMLF,ICA
PVNN_MAIN_CPU1           C310             1        Q_CAP_C0402-22UF,4V,20%,X6S,CHA
PVNN_MAIN_CPU1           C1353            1        Q_CAP_C0402-22UF,4V,20%,X6S,CHA
PVNN_MAIN_CPU1           C1365            1        Q_CAP_C0402-22UF,4V,20%,X6S,CHA
PVNN_MAIN_CPU1           C1366            1        Q_CAP_C0402-22UF,4V,20%,X6S,CHA
PVNN_MAIN_CPU1           C1387            1        Q_CAP_C0805-100UF,4V,20%,X6S,CA
PVNN_MAIN_CPU1           C1389            1        Q_CAP_C0603-47UF,2.5V,20%,X6S,A
PVNN_MAIN_CPU1           C1391            1        Q_CAP_C0603-47UF,2.5V,20%,X6S,A
PVNN_MAIN_CPU1           C1393            1        Q_CAP_C0603-47UF,2.5V,20%,X6S,A
PVNN_MAIN_CPU1           C1403            1        Q_CAP_C0805-100UF,4V,20%,X6S,CA
PVNN_MAIN_CPU1           C1404            1        Q_CAP_C0805-100UF,4V,20%,X6S,CA
PVNN_MAIN_CPU1           PC238            2        Q_CAP_0402-680PF,50V,10%,X7R,TA
PVNN_MAIN_CPU1           PC1207           1        Q_CAP_0805-22UF,4V,20%,X6S,TMPA
PVNN_MAIN_CPU1           PC1284           1        Q_CAP_C0402-100NF,50V,10%,X7R,A
PVNN_MAIN_CPU1           PC1285           1        Q_CAP_0805-22UF,4V,20%,X6S,TMPA
PVNN_MAIN_CPU1           PC1286           1        Q_CAP_0805-22UF,4V,20%,X6S,TMPA
PVNN_MAIN_CPU1           PC1287           1        Q_CAP_0805-22UF,4V,20%,X6S,TMPA
PVNN_MAIN_CPU1           PL121            2        Q_INDUCTOR_SMLF-1UH,IND,CV-10BA
PVNN_MAIN_CPU1           PR502            2        Q_RES_0402LF-8.25K,1%,1/16W,CHA
PVNN_MAIN_CPU1           R330             1        Q_RES_1206LF-0,,1/2W,CHIP,CS00A
PVNN_MAIN_CPU1           U1               BA19     SOCKET4677_AZIFS054P001C01-SOCA
PVNN_MAIN_CPU1           U1               BE19     SOCKET4677_AZIFS054P001C01-SOCA
PVNN_MAIN_CPU1           U1               BJ19     SOCKET4677_AZIFS054P001C01-SOCA
PVNN_MAIN_CPU1           U1               BN19     SOCKET4677_AZIFS054P001C01-SOCA
PVNN_MAIN_CPU1_CS        PR2222           1        Q_RES_0402LF-9.09K,1%,1/16W,CHA
PVNN_MAIN_CPU1_CS        PU82             4        MPQ8626GDZ-MPQ8626GD-Z,SMLF,ICA
PVNN_MAIN_CPU1_FB_RC     PC238            1        Q_CAP_0402-680PF,50V,10%,X7R,TA
PVNN_MAIN_CPU1_FB_RC     PR51             1        Q_RES_0402LF-12.4K,1%,1/16W,CHA
PVNN_MAIN_CPU1_FB_RC     PR502            1        Q_RES_0402LF-8.25K,1%,1/16W,CHA
PVNN_MAIN_CPU1_FB_RC     PU82             6        MPQ8626GDZ-MPQ8626GD-Z,SMLF,ICA
PVNN_MAIN_CPU1_MODE      PR2220           1        Q_RES_0402LF-60.4K,1%,1/16W,CHA
PVNN_MAIN_CPU1_MODE      PU82             12       MPQ8626GDZ-MPQ8626GD-Z,SMLF,ICA
PVNN_MAIN_CPU1_REF       PC28             1        Q_CAP_0402-3300PF,50V,10%,X7R,A
PVNN_MAIN_CPU1_REF       PU82             8        MPQ8626GDZ-MPQ8626GD-Z,SMLF,ICA
PVNN_MAIN_CPU1_VCC       PC2222           1        Q_CAP_C0402-1UF,25V,10%,X6S,CHA
PVNN_MAIN_CPU1_VCC       PU82             13       MPQ8626GDZ-MPQ8626GD-Z,SMLF,ICA
PVNN_TERM_CPU0           C559             1        Q_CAP_0402-0.1UF,25V,10%,X7R,CA
PVNN_TERM_CPU0           C567             1        Q_CAP_0402-0.1UF,25V,10%,X7R,CA
PVNN_TERM_CPU0           C1302            1        Q_CAP_C0402-22UF,4V,20%,X6S,CHA
PVNN_TERM_CPU0           C2443            1        Q_CAP_C0402-10UF,6.3V,20%,X6S,A
PVNN_TERM_CPU0           C2444            1        Q_CAP_0402-0.1UF,25V,10%,X7R,CA
PVNN_TERM_CPU0           PC327            1        Q_CAP_C0603-10UF,4V,20%,EMPTY,A
PVNN_TERM_CPU0           PC328            1        Q_CAP_C0402-100NF,50V,10%,X7R,A
PVNN_TERM_CPU0           PR528            2        Q_RES_0402LF-100,1%,1/16W,CHIPA
PVNN_TERM_CPU0           PR529            2        Q_RES_0402LF-49.9     ,1%  ,1/A
PVNN_TERM_CPU0           PR530            2        Q_RES_0402LF-49.9     ,1%  ,1/B
PVNN_TERM_CPU0           R18              1        Q_RES_0402LF-499,1%,1/16W,CHIPA
PVNN_TERM_CPU0           R19              1        Q_RES_0402LF-499,1%,1/16W,CHIPA
PVNN_TERM_CPU0           R94              1        Q_RES_0402LF-240,1%,1/16W,EMPTA
PVNN_TERM_CPU0           R95              1        Q_RES_0402LF-240,1%,1/16W,EMPTA
PVNN_TERM_CPU0           R96              1        Q_RES_0402LF-240,1%,1/16W,EMPTA
PVNN_TERM_CPU0           R97              1        Q_RES_0402LF-240,1%,1/16W,EMPTA
PVNN_TERM_CPU0           R142             1        Q_RES_0402LF-0,5%,1/16W,CHIP,CA
PVNN_TERM_CPU0           R146             1        Q_RES_0402LF-4.75K,1%,1/16W,EMA
PVNN_TERM_CPU0           R183             2        Q_RES_0402LF-100,1%,1/16W,EMPTA
PVNN_TERM_CPU0           R185             2        Q_RES_0402LF-100,1%,1/16W,EMPTA
PVNN_TERM_CPU0           R197             1        Q_RES_0402LF-10K,1%,1/16W,EMPTA
PVNN_TERM_CPU0           R199             1        Q_RES_0402LF-100,1%,1/16W,EMPTA
PVNN_TERM_CPU0           R200             1        Q_RES_0402LF-100,1%,1/16W,EMPTA
PVNN_TERM_CPU0           R219             1        Q_RES_0402LF-100,1%,1/16W,EMPTA
PVNN_TERM_CPU0           R243             1        Q_RES_0402LF-100,1%,1/16W,EMPTA
PVNN_TERM_CPU0           R249             1        Q_RES_0402LF-240,1%,1/16W,EMPTA
PVNN_TERM_CPU0           R250             1        Q_RES_0402LF-240,1%,1/16W,EMPTA
PVNN_TERM_CPU0           R251             1        Q_RES_0402LF-240,1%,1/16W,EMPTA
PVNN_TERM_CPU0           R252             1        Q_RES_0402LF-240,1%,1/16W,CHIPA
PVNN_TERM_CPU0           R253             1        Q_RES_0402LF-240,1%,1/16W,CHIPA
PVNN_TERM_CPU0           R254             1        Q_RES_0402LF-240,1%,1/16W,CHIPA
PVNN_TERM_CPU0           R275             1        Q_RES_0402LF-240,1%,1/16W,CHIPA
PVNN_TERM_CPU0           R276             1        Q_RES_0402LF-240,1%,1/16W,EMPTA
PVNN_TERM_CPU0           R277             1        Q_RES_0402LF-240,1%,1/16W,CHIPA
PVNN_TERM_CPU0           R278             1        Q_RES_0402LF-240,1%,1/16W,EMPTA
PVNN_TERM_CPU0           R279             1        Q_RES_0402LF-240,1%,1/16W,EMPTA
PVNN_TERM_CPU0           R280             1        Q_RES_0402LF-240,1%,1/16W,EMPTA
PVNN_TERM_CPU0           R281             1        Q_RES_0402LF-240,1%,1/16W,EMPTA
PVNN_TERM_CPU0           R282             1        Q_RES_0402LF-240,1%,1/16W,CHIPA
PVNN_TERM_CPU0           R296             1        Q_RES_0402LF-301,1%,1/16W,CHIPA
PVNN_TERM_CPU0           R301             1        Q_RES_0402LF-301,1%,1/16W,CHIPA
PVNN_TERM_CPU0           R323             2        Q_RES_1206LF-0,,1/2W,EMPTY,CS0A
PVNN_TERM_CPU0           R324             2        Q_RES_1206LF-0,,1/2W,CHIP,CS00A
PVNN_TERM_CPU0           R328             2        Q_RES_0402LF-100,1%,1/16W,CHIPA
PVNN_TERM_CPU0           R513             1        Q_RES_1206LF-0,5%,1/4W,CHIP,CSA
PVNN_TERM_CPU0           R548             2        Q_RES_0402LF-49.9     ,1%  ,1/A
PVNN_TERM_CPU0           R555             2        Q_RES_0402LF-100,1%,1/16W,CHIPA
PVNN_TERM_CPU0           R556             2        Q_RES_0402LF-49.9     ,1%  ,1/A
PVNN_TERM_CPU0           R557             2        Q_RES_0402LF-100,1%,1/16W,CHIPA
PVNN_TERM_CPU0           R558             2        Q_RES_0402LF-49.9     ,1%  ,1/A
PVNN_TERM_CPU0           R559             2        Q_RES_0402LF-100,1%,1/16W,CHIPA
PVNN_TERM_CPU0           R560             2        Q_RES_0402LF-49.9     ,1%  ,1/A
PVNN_TERM_CPU0           R561             1        Q_RES_0402LF-100,1%,1/16W,EMPTA
PVNN_TERM_CPU0           R679             1        Q_RES_0402LF-249,1%,1/16W,CHIPA
PVNN_TERM_CPU0           R680             1        Q_RES_0402LF-249,1%,1/16W,CHIPA
PVNN_TERM_CPU0           R681             1        Q_RES_0402LF-249,1%,1/16W,CHIPA
PVNN_TERM_CPU0           R686             1        Q_RES_0402LF-249,1%,1/16W,CHIPA
PVNN_TERM_CPU0           R741             1        Q_RES_0402LF-150,1%,1/16W,CHIPA
PVNN_TERM_CPU0           R744             1        Q_RES_0402LF-75,1%,1/16W,CHIP,A
PVNN_TERM_CPU0           R757             1        Q_RES_0402LF-120,1%,1/16W,CHIPA
PVNN_TERM_CPU0           R758             1        Q_RES_0402LF-150,1%,1/16W,CHIPA
PVNN_TERM_CPU0           R759             1        Q_RES_0402LF-150,1%,1/16W,CHIPA
PVNN_TERM_CPU0           R760             1        Q_RES_0402LF-499,1%,1/16W,CHIPA
PVNN_TERM_CPU0           R761             1        Q_RES_0402LF-499,1%,1/16W,CHIPA
PVNN_TERM_CPU0           R779             1        Q_RES_0402LF-150,5%,1/16W,CHIPA
PVNN_TERM_CPU0           R910             1        Q_RES_0402LF-240,1%,1/16W,CHIPA
PVNN_TERM_CPU0           R911             1        Q_RES_0402LF-240,1%,1/16W,CHIPA
PVNN_TERM_CPU0           R969             1        Q_RES_0402LF-240,1%,1/16W,CHIPA
PVNN_TERM_CPU0           R971             1        Q_RES_0402LF-240,1%,1/16W,CHIPA
PVNN_TERM_CPU0           R1006            1        Q_RES_0402LF-4.7K,5%,1/16W,CHIA
PVNN_TERM_CPU0           R1009            1        Q_RES_0402LF-1K,1%,1/16W,EMPTYA
PVNN_TERM_CPU0           R1232            1        Q_RES_0402LF-240,1%,1/16W,EMPTA
PVNN_TERM_CPU0           R1233            1        Q_RES_0402LF-240,1%,1/16W,EMPTA
PVNN_TERM_CPU0           R1242            1        Q_RES_0402LF-301,1%,1/16W,CHIPA
PVNN_TERM_CPU0           R1485            1        Q_RES_0402LF-200,1%,1/16W,EMPTA
PVNN_TERM_CPU0           R1486            1        Q_RES_0402LF-200,1%,1/16W,EMPTA
PVNN_TERM_CPU0           R1717            1        Q_RES_0402LF-49.9     ,1%  ,1/A
PVNN_TERM_CPU0           R1735            1        Q_RES_0402LF-100,1%,1/16W,CHIPA
PVNN_TERM_CPU0           R1956            2        Q_RES_0402LF-100,1%,1/16W,CHIPA
PVNN_TERM_CPU0           R2322            1        Q_RES_0402LF-49.9     ,1%  ,1/B
PVNN_TERM_CPU0           U28              1        PCA9617ADP-PCA9617ADP,SMLF,IC,A
PVNN_TERM_CPU0           U30              1        PCA9617ADP-PCA9617ADP,SMLF,IC,A
PVNN_TERM_CPU1           C560             1        Q_CAP_0402-0.1UF,25V,10%,X7R,CA
PVNN_TERM_CPU1           C568             1        Q_CAP_0402-0.1UF,25V,10%,X7R,CA
PVNN_TERM_CPU1           PC545            1        Q_CAP_C0603-10UF,4V,20%,EMPTY,A
PVNN_TERM_CPU1           PC546            1        Q_CAP_C0402-100NF,50V,10%,X7R,A
PVNN_TERM_CPU1           PC1336           1        Q_CAP_C0402-10UF,6.3V,20%,X6S,A
PVNN_TERM_CPU1           PC1337           1        Q_CAP_0402-0.1UF,25V,10%,X7R,CA
PVNN_TERM_CPU1           PR575            2        Q_RES_0402LF-100,1%,1/16W,CHIPA
PVNN_TERM_CPU1           PR576            2        Q_RES_0402LF-49.9     ,1%  ,1/A
PVNN_TERM_CPU1           PR577            2        Q_RES_0402LF-49.9     ,1%  ,1/B
PVNN_TERM_CPU1           PR1718           1        Q_RES_0402LF-49.9     ,1%  ,1/A
PVNN_TERM_CPU1           PR1747           1        Q_RES_0402LF-100,1%,1/16W,CHIPA
PVNN_TERM_CPU1           R49              1        Q_RES_0402LF-499,1%,1/16W,CHIPA
PVNN_TERM_CPU1           R50              1        Q_RES_0402LF-499,1%,1/16W,CHIPA
PVNN_TERM_CPU1           R90              1        Q_RES_0402LF-240,1%,1/16W,EMPTA
PVNN_TERM_CPU1           R91              1        Q_RES_0402LF-240,1%,1/16W,EMPTA
PVNN_TERM_CPU1           R92              1        Q_RES_0402LF-240,1%,1/16W,EMPTA
PVNN_TERM_CPU1           R93              1        Q_RES_0402LF-240,1%,1/16W,EMPTA
PVNN_TERM_CPU1           R155             2        Q_RES_0402LF-100,1%,1/16W,EMPTA
PVNN_TERM_CPU1           R157             2        Q_RES_0402LF-100,1%,1/16W,EMPTA
PVNN_TERM_CPU1           R198             1        Q_RES_0402LF-10K,1%,1/16W,EMPTA
PVNN_TERM_CPU1           R201             1        Q_RES_0402LF-100,1%,1/16W,EMPTA
PVNN_TERM_CPU1           R202             1        Q_RES_0402LF-100,1%,1/16W,EMPTA
PVNN_TERM_CPU1           R220             1        Q_RES_0402LF-100,1%,1/16W,EMPTA
PVNN_TERM_CPU1           R244             1        Q_RES_0402LF-100,1%,1/16W,EMPTA
PVNN_TERM_CPU1           R255             1        Q_RES_0402LF-240,1%,1/16W,EMPTA
PVNN_TERM_CPU1           R256             1        Q_RES_0402LF-240,1%,1/16W,EMPTA
PVNN_TERM_CPU1           R257             1        Q_RES_0402LF-240,1%,1/16W,EMPTA
PVNN_TERM_CPU1           R258             1        Q_RES_0402LF-240,1%,1/16W,CHIPA
PVNN_TERM_CPU1           R259             1        Q_RES_0402LF-240,1%,1/16W,CHIPA
PVNN_TERM_CPU1           R260             1        Q_RES_0402LF-240,1%,1/16W,CHIPA
PVNN_TERM_CPU1           R261             1        Q_RES_0402LF-240,1%,1/16W,EMPTA
PVNN_TERM_CPU1           R262             1        Q_RES_0402LF-240,1%,1/16W,EMPTA
PVNN_TERM_CPU1           R263             1        Q_RES_0402LF-240,1%,1/16W,EMPTA
PVNN_TERM_CPU1           R264             1        Q_RES_0402LF-240,1%,1/16W,EMPTA
PVNN_TERM_CPU1           R265             1        Q_RES_0402LF-240,1%,1/16W,CHIPA
PVNN_TERM_CPU1           R266             1        Q_RES_0402LF-240,1%,1/16W,EMPTA
PVNN_TERM_CPU1           R267             1        Q_RES_0402LF-240,1%,1/16W,EMPTA
PVNN_TERM_CPU1           R268             1        Q_RES_0402LF-240,1%,1/16W,EMPTA
PVNN_TERM_CPU1           R298             1        Q_RES_0402LF-301,1%,1/16W,CHIPA
PVNN_TERM_CPU1           R303             1        Q_RES_0402LF-301,1%,1/16W,CHIPA
PVNN_TERM_CPU1           R329             2        Q_RES_1206LF-0,,1/2W,EMPTY,CS0A
PVNN_TERM_CPU1           R330             2        Q_RES_1206LF-0,,1/2W,CHIP,CS00A
PVNN_TERM_CPU1           R662             1        Q_RES_0402LF-249,1%,1/16W,CHIPA
PVNN_TERM_CPU1           R663             1        Q_RES_0402LF-249,1%,1/16W,CHIPA
PVNN_TERM_CPU1           R664             1        Q_RES_0402LF-249,1%,1/16W,CHIPA
PVNN_TERM_CPU1           R669             1        Q_RES_0402LF-249,1%,1/16W,CHIPA
PVNN_TERM_CPU1           R742             1        Q_RES_0402LF-75,1%,1/16W,CHIP,A
PVNN_TERM_CPU1           R743             1        Q_RES_0402LF-150,1%,1/16W,CHIPA
PVNN_TERM_CPU1           R963             1        Q_RES_0402LF-240,1%,1/16W,CHIPA
PVNN_TERM_CPU1           R964             1        Q_RES_0402LF-240,1%,1/16W,CHIPA
PVNN_TERM_CPU1           R970             1        Q_RES_0402LF-240,1%,1/16W,CHIPA
PVNN_TERM_CPU1           R972             1        Q_RES_0402LF-240,1%,1/16W,CHIPA
PVNN_TERM_CPU1           R1007            1        Q_RES_0402LF-4.7K,5%,1/16W,CHIA
PVNN_TERM_CPU1           R1008            1        Q_RES_0402LF-1K,1%,1/16W,EMPTYA
PVNN_TERM_CPU1           R1229            1        Q_RES_0402LF-240,1%,1/16W,EMPTA
PVNN_TERM_CPU1           R1230            1        Q_RES_0402LF-240,1%,1/16W,EMPTA
PVNN_TERM_CPU1           R1244            1        Q_RES_0402LF-301,1%,1/16W,CHIPA
PVNN_TERM_CPU1           R1957            2        Q_RES_0402LF-100,1%,1/16W,CHIPA
PVNN_TERM_CPU1           R2345            1        Q_RES_0402LF-49.9     ,1%  ,1/B
PVNN_TERM_CPU1           R2354            1        Q_RES_0402LF-100,1%,1/16W,EMPTA
PVNN_TERM_CPU1           U29              1        PCA9617ADP-PCA9617ADP,SMLF,IC,A
PVNN_TERM_CPU1           U31              1        PCA9617ADP-PCA9617ADP,SMLF,IC,A
PVPP_HBM_CPU0            C1396            1        Q_CAP_C0805-100UF,4V,20%,X6S,CA
PVPP_HBM_CPU0            C1397            1        Q_CAP_C0805-100UF,4V,20%,X6S,CA
PVPP_HBM_CPU0            C1398            1        Q_CAP_C0805-100UF,4V,20%,X6S,CA
PVPP_HBM_CPU0            C1436            1        Q_CAP_C0201-0.22UF,6.3V,10%,X6A
PVPP_HBM_CPU0            PC1254           1        Q_CAP_0402-0.1UF,25V,10%,EMPTYA
PVPP_HBM_CPU0            PC1255           1        Q_CAP_0805-22UF,4V,20%,EMPTY,TA
PVPP_HBM_CPU0            PC1256           1        Q_CAP_0805-22UF,4V,20%,EMPTY,TA
PVPP_HBM_CPU0            PC1257           1        Q_CAP_0805-22UF,4V,20%,EMPTY,TA
PVPP_HBM_CPU0            PC1258           1        Q_CAPP_THLF-560UF,6.3V,20%,EMPA
PVPP_HBM_CPU0            PJ64             2        Q_SHORT_SM-EMPTY,SHORT6
PVPP_HBM_CPU0            PL118            2        Q_INDUCTOR_SMLF-1UH,EMPTY,CV-1A
PVPP_HBM_CPU0            U2               CC68     SOCKET4677_AZIFS054P001C01-SOCA
PVPP_HBM_CPU0            U2               CD67     SOCKET4677_AZIFS054P001C01-SOCA
PVPP_HBM_CPU0            U2               CE68     SOCKET4677_AZIFS054P001C01-SOCA
PVPP_HBM_CPU0            U2               CF67     SOCKET4677_AZIFS054P001C01-SOCA
PVPP_HBM_CPU0            U2               CG68     SOCKET4677_AZIFS054P001C01-SOCA
PVPP_HBM_CPU0_CS         PR1336           1        Q_RES_0402LF-8.87K,1%,1/16W,EMA
PVPP_HBM_CPU0_CS         PU79             3        MPQ8633AGLEC807Z-MPQ8633AGLE-CA
PVPP_HBM_CPU0_FB         PC1253           1        Q_CAP_0402-100PF,50V,5%,EMPTY,A
PVPP_HBM_CPU0_FB         PR1310           1        Q_RES_0402LF-18.2K,0.1%,1/16W,A
PVPP_HBM_CPU0_FB         PR1337           1        Q_RES_0402LF-36K,1%,1/16W,EMPTA
PVPP_HBM_CPU0_FB         PU79             7        MPQ8633AGLEC807Z-MPQ8633AGLE-CA
PVPP_HBM_CPU0_FB         R2336            1        Q_RES_0402LF-26.1K,1%,1/16W,EMA
PVPP_HBM_CPU0_REF        PC1251           1        Q_CAP_0402-0.1UF,25V,10%,EMPTYA
PVPP_HBM_CPU0_REF        PC2001           1        Q_CAP_0402-0.022UF,16V,10%,EMPA
PVPP_HBM_CPU0_REF        PU79             5        MPQ8633AGLEC807Z-MPQ8633AGLE-CA
PVPP_HBM_CPU0_VCC        PC2643           1        Q_CAP_C0402-1UF,25V,10%,EMPTY,A
PVPP_HBM_CPU0_VCC        PR1335           2        Q_RES_0402LF-0,5%,1/16W,EMPTY,A
PVPP_HBM_CPU0_VCC        PU79             4        MPQ8633AGLEC807Z-MPQ8633AGLE-CA
PVPP_HBM_CPU0_VCC        PU79             19       MPQ8633AGLEC807Z-MPQ8633AGLE-CA
PVPP_HBM_CPU1            C1388            1        Q_CAP_C0805-100UF,4V,20%,X6S,CA
PVPP_HBM_CPU1            C1390            1        Q_CAP_C0805-100UF,4V,20%,X6S,CA
PVPP_HBM_CPU1            C1392            1        Q_CAP_C0805-100UF,4V,20%,X6S,CA
PVPP_HBM_CPU1            C1437            1        Q_CAP_C0201-0.22UF,6.3V,10%,X6A
PVPP_HBM_CPU1            PC1267           1        Q_CAP_0402-0.1UF,25V,10%,X7R,CA
PVPP_HBM_CPU1            PC1268           1        Q_CAP_0805-22UF,4V,20%,X6S,TMPA
PVPP_HBM_CPU1            PC1269           1        Q_CAP_0805-22UF,4V,20%,X6S,TMPA
PVPP_HBM_CPU1            PC1270           1        Q_CAP_0805-22UF,4V,20%,X6S,TMPA
PVPP_HBM_CPU1            PC1771           1        Q_CAPP_THLF-560UF,6.3V,20%,OSCA
PVPP_HBM_CPU1            PJ66             2        Q_SHORT_SM-EMPTY,SHORT6
PVPP_HBM_CPU1            PL119            2        Q_INDUCTOR_SMLF-1UH,IND,CV-10BA
PVPP_HBM_CPU1            U1               CC68     SOCKET4677_AZIFS054P001C01-SOCA
PVPP_HBM_CPU1            U1               CD67     SOCKET4677_AZIFS054P001C01-SOCA
PVPP_HBM_CPU1            U1               CE68     SOCKET4677_AZIFS054P001C01-SOCA
PVPP_HBM_CPU1            U1               CF67     SOCKET4677_AZIFS054P001C01-SOCA
PVPP_HBM_CPU1            U1               CG68     SOCKET4677_AZIFS054P001C01-SOCA
PVPP_HBM_CPU1_CS         PR1339           1        Q_RES_0402LF-9.31K,1%,1/16W,CHA
PVPP_HBM_CPU1_CS         PU80             3        MPQ8633AGLEC807Z-MPQ8633AGLE-CB
PVPP_HBM_CPU1_FB         PC1266           1        Q_CAP_0402-100PF,50V,5%,NPO,CHA
PVPP_HBM_CPU1_FB         PR1314           1        Q_RES_0402LF-18.2K,0.1%,1/16W,B
PVPP_HBM_CPU1_FB         PR1340           1        Q_RES_0402LF-36K,1%,1/16W,CHIPA
PVPP_HBM_CPU1_FB         PU80             7        MPQ8633AGLEC807Z-MPQ8633AGLE-CB
PVPP_HBM_CPU1_FB         R2381            1        Q_RES_0402LF-26.1K,1%,1/16W,CHA
PVPP_HBM_CPU1_REF        PC1264           1        Q_CAP_0402-0.1UF,25V,10%,X7R,CA
PVPP_HBM_CPU1_REF        PC2002           1        Q_CAP_0402-0.022UF,16V,10%,X7RA
PVPP_HBM_CPU1_REF        PU80             5        MPQ8633AGLEC807Z-MPQ8633AGLE-CB
PVPP_HBM_CPU1_VCC        PC644            1        Q_CAP_C0402-1UF,25V,10%,X6S,CHA
PVPP_HBM_CPU1_VCC        PR1338           2        Q_RES_0402LF-0,5%,1/16W,CHIP,CA
PVPP_HBM_CPU1_VCC        PU80             4        MPQ8633AGLEC807Z-MPQ8633AGLE-CB
PVPP_HBM_CPU1_VCC        PU80             19       MPQ8633AGLEC807Z-MPQ8633AGLE-CB
PWRGD_CHA_CPU0_DIMM1     J1               147      SCONN288_ADR50001P013C01-SCONNA
PWRGD_CHA_CPU0_DIMM1     R877             1        Q_RES_0402LF-33,5%,1/16W,CHIP,A
PWRGD_CHA_CPU0_DIMM2     J2               147      SCONN288_ADR50001P003C01-SCONNA
PWRGD_CHA_CPU0_DIMM2     R878             1        Q_RES_0402LF-33,5%,1/16W,CHIP,A
PWRGD_CHA_CPU1_DIMM1     J17              147      SCONN288_ADR50001P013C01-SCONNA
PWRGD_CHA_CPU1_DIMM1     R893             1        Q_RES_0402LF-33,5%,1/16W,CHIP,A
PWRGD_CHA_CPU1_DIMM2     J18              147      SCONN288_ADR50001P003C01-SCONNA
PWRGD_CHA_CPU1_DIMM2     R894             1        Q_RES_0402LF-33,5%,1/16W,CHIP,A
PWRGD_CHB_CPU0_DIMM1     J3               147      SCONN288_ADR50001P013C01-SCONNA
PWRGD_CHB_CPU0_DIMM1     R879             1        Q_RES_0402LF-33,5%,1/16W,CHIP,A
PWRGD_CHB_CPU0_DIMM2     J4               147      SCONN288_ADR50001P003C01-SCONNA
PWRGD_CHB_CPU0_DIMM2     R880             1        Q_RES_0402LF-33,5%,1/16W,CHIP,A
PWRGD_CHB_CPU1_DIMM1     J19              147      SCONN288_ADR50001P013C01-SCONNA
PWRGD_CHB_CPU1_DIMM1     R895             1        Q_RES_0402LF-33,5%,1/16W,CHIP,A
PWRGD_CHB_CPU1_DIMM2     J20              147      SCONN288_ADR50001P003C01-SCONNA
PWRGD_CHB_CPU1_DIMM2     R896             1        Q_RES_0402LF-33,5%,1/16W,CHIP,A
PWRGD_CHC_CPU0_DIMM1     J5               147      SCONN288_ADR50001P013C01-SCONNA
PWRGD_CHC_CPU0_DIMM1     R881             1        Q_RES_0402LF-33,5%,1/16W,CHIP,A
PWRGD_CHC_CPU0_DIMM2     J6               147      SCONN288_ADR50001P003C01-SCONNA
PWRGD_CHC_CPU0_DIMM2     R882             1        Q_RES_0402LF-33,5%,1/16W,CHIP,A
PWRGD_CHC_CPU1_DIMM1     J21              147      SCONN288_ADR50001P013C01-SCONNA
PWRGD_CHC_CPU1_DIMM1     R897             1        Q_RES_0402LF-33,5%,1/16W,CHIP,A
PWRGD_CHC_CPU1_DIMM2     J22              147      SCONN288_ADR50001P003C01-SCONNA
PWRGD_CHC_CPU1_DIMM2     R898             1        Q_RES_0402LF-33,5%,1/16W,CHIP,A
PWRGD_CHD_CPU0_DIMM1     J7               147      SCONN288_ADR50001P013C01-SCONNA
PWRGD_CHD_CPU0_DIMM1     R883             1        Q_RES_0402LF-33,5%,1/16W,CHIP,A
PWRGD_CHD_CPU0_DIMM2     J8               147      SCONN288_ADR50001P003C01-SCONNA
PWRGD_CHD_CPU0_DIMM2     R884             1        Q_RES_0402LF-33,5%,1/16W,CHIP,A
PWRGD_CHD_CPU1_DIMM1     J23              147      SCONN288_ADR50001P013C01-SCONNA
PWRGD_CHD_CPU1_DIMM1     R899             1        Q_RES_0402LF-33,5%,1/16W,CHIP,A
PWRGD_CHD_CPU1_DIMM2     J24              147      SCONN288_ADR50001P003C01-SCONNA
PWRGD_CHD_CPU1_DIMM2     R900             1        Q_RES_0402LF-33,5%,1/16W,CHIP,A
PWRGD_CHE_CPU0_DIMM1     J9               147      SCONN288_ADR50001P013C01-SCONNA
PWRGD_CHE_CPU0_DIMM1     R885             1        Q_RES_0402LF-33,5%,1/16W,CHIP,A
PWRGD_CHE_CPU0_DIMM2     J10              147      SCONN288_ADR50001P003C01-SCONNA
PWRGD_CHE_CPU0_DIMM2     R886             1        Q_RES_0402LF-33,5%,1/16W,CHIP,A
PWRGD_CHE_CPU1_DIMM1     J25              147      SCONN288_ADR50001P013C01-SCONNA
PWRGD_CHE_CPU1_DIMM1     R901             1        Q_RES_0402LF-33,5%,1/16W,CHIP,A
PWRGD_CHE_CPU1_DIMM2     J26              147      SCONN288_ADR50001P003C01-SCONNA
PWRGD_CHE_CPU1_DIMM2     R902             1        Q_RES_0402LF-33,5%,1/16W,CHIP,A
PWRGD_CHF_CPU0_DIMM1     J11              147      SCONN288_ADR50001P013C01-SCONNA
PWRGD_CHF_CPU0_DIMM1     R887             1        Q_RES_0402LF-33,5%,1/16W,CHIP,A
PWRGD_CHF_CPU0_DIMM2     J12              147      SCONN288_ADR50001P003C01-SCONNA
PWRGD_CHF_CPU0_DIMM2     R888             1        Q_RES_0402LF-33,5%,1/16W,CHIP,A
PWRGD_CHF_CPU1_DIMM1     J27              147      SCONN288_ADR50001P013C01-SCONNA
PWRGD_CHF_CPU1_DIMM1     R903             1        Q_RES_0402LF-33,5%,1/16W,CHIP,A
PWRGD_CHF_CPU1_DIMM2     J28              147      SCONN288_ADR50001P003C01-SCONNA
PWRGD_CHF_CPU1_DIMM2     R904             1        Q_RES_0402LF-33,5%,1/16W,CHIP,A
PWRGD_CHG_CPU0_DIMM1     J13              147      SCONN288_ADR50001P013C01-SCONNA
PWRGD_CHG_CPU0_DIMM1     R889             1        Q_RES_0402LF-33,5%,1/16W,CHIP,A
PWRGD_CHG_CPU0_DIMM2     J14              147      SCONN288_ADR50001P003C01-SCONNA
PWRGD_CHG_CPU0_DIMM2     R890             1        Q_RES_0402LF-33,5%,1/16W,CHIP,A
PWRGD_CHG_CPU1_DIMM1     J29              147      SCONN288_ADR50001P013C01-SCONNA
PWRGD_CHG_CPU1_DIMM1     R905             1        Q_RES_0402LF-33,5%,1/16W,CHIP,A
PWRGD_CHG_CPU1_DIMM2     J30              147      SCONN288_ADR50001P003C01-SCONNA
PWRGD_CHG_CPU1_DIMM2     R906             1        Q_RES_0402LF-33,5%,1/16W,CHIP,A
PWRGD_CHH_CPU0_DIMM1     J15              147      SCONN288_ADR50001P013C01-SCONNA
PWRGD_CHH_CPU0_DIMM1     R891             1        Q_RES_0402LF-33,5%,1/16W,CHIP,A
PWRGD_CHH_CPU0_DIMM2     J16              147      SCONN288_ADR50001P003C01-SCONNA
PWRGD_CHH_CPU0_DIMM2     R892             1        Q_RES_0402LF-33,5%,1/16W,CHIP,A
PWRGD_CHH_CPU1_DIMM1     J31              147      SCONN288_ADR50001P013C01-SCONNA
PWRGD_CHH_CPU1_DIMM1     R907             1        Q_RES_0402LF-33,5%,1/16W,CHIP,A
PWRGD_CHH_CPU1_DIMM2     J32              147      SCONN288_ADR50001P003C01-SCONNA
PWRGD_CHH_CPU1_DIMM2     R908             1        Q_RES_0402LF-33,5%,1/16W,CHIP,A
PWRGD_CPU0_BUF_R         R168             2        Q_RES_0402LF-0,5%,1/16W,CHIP,CA
PWRGD_CPU0_BUF_R         R183             1        Q_RES_0402LF-100,1%,1/16W,EMPTA
PWRGD_CPU0_BUF_R         R184             1        Q_RES_0402LF-33,5%,1/16W,CHIP,A
PWRGD_CPU0_LVC1          R184             2        Q_RES_0402LF-33,5%,1/16W,CHIP,A
PWRGD_CPU0_LVC1          U2               AV20     SOCKET4677_AZIFS054P001C01-SOCA
PWRGD_CPU0_LVC1_R        R168             1        Q_RES_0402LF-0,5%,1/16W,CHIP,CA
PWRGD_CPU0_LVC1_R        R992             1        Q_RES_0402LF-2K,1%,1/16W,CHIP,A
PWRGD_CPU0_LVC1_R        U122             U3       10M04SAU324I7G-10M04SAU324I7G,A
PWRGD_CPU1_BUF_R         R130             2        Q_RES_0402LF-0,5%,1/16W,CHIP,CA
PWRGD_CPU1_BUF_R         R155             1        Q_RES_0402LF-100,1%,1/16W,EMPTA
PWRGD_CPU1_BUF_R         R156             1        Q_RES_0402LF-33,5%,1/16W,CHIP,A
PWRGD_CPU1_LVC1          R156             2        Q_RES_0402LF-33,5%,1/16W,CHIP,A
PWRGD_CPU1_LVC1          U1               AV20     SOCKET4677_AZIFS054P001C01-SOCA
PWRGD_CPU1_LVC1_R        R130             1        Q_RES_0402LF-0,5%,1/16W,CHIP,CA
PWRGD_CPU1_LVC1_R        R1398            1        Q_RES_0402LF-2K,1%,1/16W,CHIP,A
PWRGD_CPU1_LVC1_R        U122             R4       10M04SAU324I7G-10M04SAU324I7G,A
PWRGD_CPUPWRGD_GTL       R315             1        Q_RES_0402LF-33,5%,1/16W,CHIP,A
PWRGD_CPUPWRGD_GTL       U4               G10      EMMITSBURG_REV0P9-GFNOCPU04302A
PWRGD_CPUPWRGD_LVC1      R1443            1        Q_RES_0402LF-33.2,1%,1/16W,CHIA
PWRGD_CPUPWRGD_LVC1      U122             U7       10M04SAU324I7G-10M04SAU324I7G,A
PWRGD_CPUPWRGD_LVC1_R    R315             2        Q_RES_0402LF-33,5%,1/16W,CHIP,A
PWRGD_CPUPWRGD_LVC1_R    R1443            2        Q_RES_0402LF-33.2,1%,1/16W,CHIA
PWRGD_DRAMPWRGD_CPU0_AB_LVC1_R R160             2        Q_RES_0402LF-0,5%,1/16W,CHIP,CA
PWRGD_DRAMPWRGD_CPU0_AB_LVC1_R R175             1        Q_RES_0402LF-100,1%,1/16W,EMPTA
PWRGD_DRAMPWRGD_CPU0_AB_LVC1_R U2               A43      SOCKET4677_AZIFS054P001C01-SOCA
PWRGD_DRAMPWRGD_CPU0_AB_R_LVC1 R160             1        Q_RES_0402LF-0,5%,1/16W,CHIP,CA
PWRGD_DRAMPWRGD_CPU0_AB_R_LVC1 R1302            1        Q_RES_0402LF-2K,1%,1/16W,CHIP,A
PWRGD_DRAMPWRGD_CPU0_AB_R_LVC1 U122             P10      10M04SAU324I7G-10M04SAU324I7G,A
PWRGD_DRAMPWRGD_CPU0_CD_LVC1_R R162             2        Q_RES_0402LF-0,5%,1/16W,CHIP,CA
PWRGD_DRAMPWRGD_CPU0_CD_LVC1_R R177             1        Q_RES_0402LF-100,1%,1/16W,EMPTA
PWRGD_DRAMPWRGD_CPU0_CD_LVC1_R U2               F47      SOCKET4677_AZIFS054P001C01-SOCA
PWRGD_DRAMPWRGD_CPU0_CD_R_LVC1 R162             1        Q_RES_0402LF-0,5%,1/16W,CHIP,CA
PWRGD_DRAMPWRGD_CPU0_CD_R_LVC1 R1326            1        Q_RES_0402LF-2K,1%,1/16W,CHIP,A
PWRGD_DRAMPWRGD_CPU0_CD_R_LVC1 U122             M10      10M04SAU324I7G-10M04SAU324I7G,A
PWRGD_DRAMPWRGD_CPU0_EF_LVC1_R R164             2        Q_RES_0402LF-0,5%,1/16W,CHIP,CA
PWRGD_DRAMPWRGD_CPU0_EF_LVC1_R R179             1        Q_RES_0402LF-100,1%,1/16W,EMPTA
PWRGD_DRAMPWRGD_CPU0_EF_LVC1_R U2               CY44     SOCKET4677_AZIFS054P001C01-SOCA
PWRGD_DRAMPWRGD_CPU0_EF_R_LVC1 R164             1        Q_RES_0402LF-0,5%,1/16W,CHIP,CA
PWRGD_DRAMPWRGD_CPU0_EF_R_LVC1 R1327            1        Q_RES_0402LF-2K,1%,1/16W,CHIP,A
PWRGD_DRAMPWRGD_CPU0_EF_R_LVC1 U122             N11      10M04SAU324I7G-10M04SAU324I7G,A
PWRGD_DRAMPWRGD_CPU0_GH_LVC1_R R166             2        Q_RES_0402LF-0,5%,1/16W,CHIP,CA
PWRGD_DRAMPWRGD_CPU0_GH_LVC1_R R181             1        Q_RES_0402LF-100,1%,1/16W,EMPTA
PWRGD_DRAMPWRGD_CPU0_GH_LVC1_R U2               CW45     SOCKET4677_AZIFS054P001C01-SOCA
PWRGD_DRAMPWRGD_CPU0_GH_R_LVC1 R166             1        Q_RES_0402LF-0,5%,1/16W,CHIP,CA
PWRGD_DRAMPWRGD_CPU0_GH_R_LVC1 R1328            1        Q_RES_0402LF-2K,1%,1/16W,CHIP,A
PWRGD_DRAMPWRGD_CPU0_GH_R_LVC1 U122             L10      10M04SAU324I7G-10M04SAU324I7G,A
PWRGD_DRAMPWRGD_CPU1_AB_LVC1_R R122             2        Q_RES_0402LF-0,5%,1/16W,CHIP,CA
PWRGD_DRAMPWRGD_CPU1_AB_LVC1_R R135             1        Q_RES_0402LF-100,1%,1/16W,EMPTA
PWRGD_DRAMPWRGD_CPU1_AB_LVC1_R U1               A43      SOCKET4677_AZIFS054P001C01-SOCA
PWRGD_DRAMPWRGD_CPU1_AB_R_LVC1 R122             1        Q_RES_0402LF-0,5%,1/16W,CHIP,CA
PWRGD_DRAMPWRGD_CPU1_AB_R_LVC1 R1329            1        Q_RES_0402LF-2K,1%,1/16W,CHIP,A
PWRGD_DRAMPWRGD_CPU1_AB_R_LVC1 U122             U15      10M04SAU324I7G-10M04SAU324I7G,A
PWRGD_DRAMPWRGD_CPU1_CD_LVC1_R R124             2        Q_RES_0402LF-0,5%,1/16W,CHIP,CA
PWRGD_DRAMPWRGD_CPU1_CD_LVC1_R R137             1        Q_RES_0402LF-100,1%,1/16W,EMPTA
PWRGD_DRAMPWRGD_CPU1_CD_LVC1_R U1               F47      SOCKET4677_AZIFS054P001C01-SOCA
PWRGD_DRAMPWRGD_CPU1_CD_R_LVC1 R124             1        Q_RES_0402LF-0,5%,1/16W,CHIP,CA
PWRGD_DRAMPWRGD_CPU1_CD_R_LVC1 R1330            1        Q_RES_0402LF-2K,1%,1/16W,CHIP,A
PWRGD_DRAMPWRGD_CPU1_CD_R_LVC1 U122             U17      10M04SAU324I7G-10M04SAU324I7G,A
PWRGD_DRAMPWRGD_CPU1_EF_LVC1_R R126             2        Q_RES_0402LF-0,5%,1/16W,CHIP,CA
PWRGD_DRAMPWRGD_CPU1_EF_LVC1_R R151             1        Q_RES_0402LF-100,1%,1/16W,EMPTA
PWRGD_DRAMPWRGD_CPU1_EF_LVC1_R U1               CY44     SOCKET4677_AZIFS054P001C01-SOCA
PWRGD_DRAMPWRGD_CPU1_EF_R_LVC1 R126             1        Q_RES_0402LF-0,5%,1/16W,CHIP,CA
PWRGD_DRAMPWRGD_CPU1_EF_R_LVC1 R1388            1        Q_RES_0402LF-2K,1%,1/16W,CHIP,A
PWRGD_DRAMPWRGD_CPU1_EF_R_LVC1 U122             U13      10M04SAU324I7G-10M04SAU324I7G,A
PWRGD_DRAMPWRGD_CPU1_GH_LVC1_R R128             2        Q_RES_0402LF-0,5%,1/16W,CHIP,CA
PWRGD_DRAMPWRGD_CPU1_GH_LVC1_R R153             1        Q_RES_0402LF-100,1%,1/16W,EMPTA
PWRGD_DRAMPWRGD_CPU1_GH_LVC1_R U1               CW45     SOCKET4677_AZIFS054P001C01-SOCA
PWRGD_DRAMPWRGD_CPU1_GH_R_LVC1 R128             1        Q_RES_0402LF-0,5%,1/16W,CHIP,CA
PWRGD_DRAMPWRGD_CPU1_GH_R_LVC1 R1389            1        Q_RES_0402LF-2K,1%,1/16W,CHIP,A
PWRGD_DRAMPWRGD_CPU1_GH_R_LVC1 U122             V17      10M04SAU324I7G-10M04SAU324I7G,A
PWRGD_DSW_PWROK          C1319            1        Q_CAP_C0402-1UF,25V,10%,X6S,CHA
PWRGD_DSW_PWROK          R1693            2        Q_RES_0402LF-33.2,1%,1/16W,CHIA
PWRGD_DSW_PWROK          R1694            2        Q_RES_0402LF-10K,1%,1/16W,CHIPA
PWRGD_DSW_PWROK          R1695            1        Q_RES_0402LF-0,5%,1/16W,EMPTY,A
PWRGD_DSW_PWROK          U4               BE8      EMMITSBURG_REV0P9-GFNOCPU04302A
PWRGD_DSW_PWROK_R1       C1318            1        Q_CAP_C0402-1UF,25V,10%,EMPTY,A
PWRGD_DSW_PWROK_R1       R1691            2        Q_RES_0402LF-10K,1%,1/16W,EMPTA
PWRGD_DSW_PWROK_R1       R1692            1        Q_RES_0402LF-100K,1%,1/16W,CHIA
PWRGD_DSW_PWROK_R1       U94              4        ADM1086AKSZREEL7-ADM1086AKSZ-RA
PWRGD_DSW_PWROK_R1       U95              2        SN74LVC1G07DCKR-SN74LVC1G07DCKA
PWRGD_DSW_PWROK_R1       U117             4        TPS3897PDRYR-TPS3897PDRYR,SMLFA
PWRGD_DSW_PWROK_R2       R1693            1        Q_RES_0402LF-33.2,1%,1/16W,CHIA
PWRGD_DSW_PWROK_R2       U95              4        SN74LVC1G07DCKR-SN74LVC1G07DCKA
PWRGD_FAIL_CPU0_AB       R877             2        Q_RES_0402LF-33,5%,1/16W,CHIP,A
PWRGD_FAIL_CPU0_AB       R878             2        Q_RES_0402LF-33,5%,1/16W,CHIP,A
PWRGD_FAIL_CPU0_AB       R879             2        Q_RES_0402LF-33,5%,1/16W,CHIP,A
PWRGD_FAIL_CPU0_AB       R880             2        Q_RES_0402LF-33,5%,1/16W,CHIP,A
PWRGD_FAIL_CPU0_AB       R940             2        Q_RES_0402LF-1K,1%,1/16W,CHIP,A
PWRGD_FAIL_CPU0_AB       U122             D4       10M04SAU324I7G-10M04SAU324I7G,A
PWRGD_FAIL_CPU0_CD       R881             2        Q_RES_0402LF-33,5%,1/16W,CHIP,A
PWRGD_FAIL_CPU0_CD       R882             2        Q_RES_0402LF-33,5%,1/16W,CHIP,A
PWRGD_FAIL_CPU0_CD       R883             2        Q_RES_0402LF-33,5%,1/16W,CHIP,A
PWRGD_FAIL_CPU0_CD       R884             2        Q_RES_0402LF-33,5%,1/16W,CHIP,A
PWRGD_FAIL_CPU0_CD       R941             2        Q_RES_0402LF-1K,1%,1/16W,CHIP,A
PWRGD_FAIL_CPU0_CD       U122             C2       10M04SAU324I7G-10M04SAU324I7G,A
PWRGD_FAIL_CPU0_EF       R885             2        Q_RES_0402LF-33,5%,1/16W,CHIP,A
PWRGD_FAIL_CPU0_EF       R886             2        Q_RES_0402LF-33,5%,1/16W,CHIP,A
PWRGD_FAIL_CPU0_EF       R887             2        Q_RES_0402LF-33,5%,1/16W,CHIP,A
PWRGD_FAIL_CPU0_EF       R888             2        Q_RES_0402LF-33,5%,1/16W,CHIP,A
PWRGD_FAIL_CPU0_EF       R942             2        Q_RES_0402LF-1K,1%,1/16W,CHIP,A
PWRGD_FAIL_CPU0_EF       U122             E4       10M04SAU324I7G-10M04SAU324I7G,A
PWRGD_FAIL_CPU0_GH       R889             2        Q_RES_0402LF-33,5%,1/16W,CHIP,A
PWRGD_FAIL_CPU0_GH       R890             2        Q_RES_0402LF-33,5%,1/16W,CHIP,A
PWRGD_FAIL_CPU0_GH       R891             2        Q_RES_0402LF-33,5%,1/16W,CHIP,A
PWRGD_FAIL_CPU0_GH       R892             2        Q_RES_0402LF-33,5%,1/16W,CHIP,A
PWRGD_FAIL_CPU0_GH       R943             2        Q_RES_0402LF-1K,1%,1/16W,CHIP,A
PWRGD_FAIL_CPU0_GH       U122             D2       10M04SAU324I7G-10M04SAU324I7G,A
PWRGD_FAIL_CPU1_AB       R893             2        Q_RES_0402LF-33,5%,1/16W,CHIP,A
PWRGD_FAIL_CPU1_AB       R894             2        Q_RES_0402LF-33,5%,1/16W,CHIP,A
PWRGD_FAIL_CPU1_AB       R895             2        Q_RES_0402LF-33,5%,1/16W,CHIP,A
PWRGD_FAIL_CPU1_AB       R896             2        Q_RES_0402LF-33,5%,1/16W,CHIP,A
PWRGD_FAIL_CPU1_AB       R944             2        Q_RES_0402LF-1K,1%,1/16W,CHIP,A
PWRGD_FAIL_CPU1_AB       U122             G6       10M04SAU324I7G-10M04SAU324I7G,A
PWRGD_FAIL_CPU1_CD       R897             2        Q_RES_0402LF-33,5%,1/16W,CHIP,A
PWRGD_FAIL_CPU1_CD       R898             2        Q_RES_0402LF-33,5%,1/16W,CHIP,A
PWRGD_FAIL_CPU1_CD       R899             2        Q_RES_0402LF-33,5%,1/16W,CHIP,A
PWRGD_FAIL_CPU1_CD       R900             2        Q_RES_0402LF-33,5%,1/16W,CHIP,A
PWRGD_FAIL_CPU1_CD       R945             2        Q_RES_0402LF-1K,1%,1/16W,CHIP,A
PWRGD_FAIL_CPU1_CD       U122             B1       10M04SAU324I7G-10M04SAU324I7G,A
PWRGD_FAIL_CPU1_EF       R901             2        Q_RES_0402LF-33,5%,1/16W,CHIP,A
PWRGD_FAIL_CPU1_EF       R902             2        Q_RES_0402LF-33,5%,1/16W,CHIP,A
PWRGD_FAIL_CPU1_EF       R903             2        Q_RES_0402LF-33,5%,1/16W,CHIP,A
PWRGD_FAIL_CPU1_EF       R904             2        Q_RES_0402LF-33,5%,1/16W,CHIP,A
PWRGD_FAIL_CPU1_EF       R946             2        Q_RES_0402LF-1K,1%,1/16W,CHIP,A
PWRGD_FAIL_CPU1_EF       U122             H6       10M04SAU324I7G-10M04SAU324I7G,A
PWRGD_FAIL_CPU1_GH       R905             2        Q_RES_0402LF-33,5%,1/16W,CHIP,A
PWRGD_FAIL_CPU1_GH       R906             2        Q_RES_0402LF-33,5%,1/16W,CHIP,A
PWRGD_FAIL_CPU1_GH       R907             2        Q_RES_0402LF-33,5%,1/16W,CHIP,A
PWRGD_FAIL_CPU1_GH       R908             2        Q_RES_0402LF-33,5%,1/16W,CHIP,A
PWRGD_FAIL_CPU1_GH       R947             2        Q_RES_0402LF-1K,1%,1/16W,CHIP,A
PWRGD_FAIL_CPU1_GH       U122             C1       10M04SAU324I7G-10M04SAU324I7G,A
PWRGD_HSC_P12V_PWROK     J44              17       CONN24_52SH90245BRD-CONN24_52SA
PWRGD_HSC_P12V_PWROK     R955             1        Q_RES_0402LF-33,5%,1/16W,CHIP,A
PWRGD_HSC_P12V_PWROK     R2186            1        Q_RES_0402LF-33,5%,1/16W,CHIP,A
PWRGD_P1V05_PCH_AUX      PR1650           2        Q_RES_0402LF-0,5%,1/16W,CHIP,CA
PWRGD_P1V05_PCH_AUX      U122             N4       10M04SAU324I7G-10M04SAU324I7G,A
PWRGD_P1V05_PCH_AUX_R    PR186            2        Q_RES_0402LF-10K,1%,1/16W,CHIPA
PWRGD_P1V05_PCH_AUX_R    PR1650           1        Q_RES_0402LF-0,5%,1/16W,CHIP,CA
PWRGD_P1V05_PCH_AUX_R    PR2390           1        Q_RES_0402LF-0,5%,1/16W,CHIP,CA
PWRGD_P1V05_PCH_AUX_R    PU73             9        MPQ8633BGLEC838Z-MPQ8633BGLE-CA
PWRGD_P1V8_PCH_AUX       PC2287           1        Q_CAP_0402-0.01UF,25V,10%,X7R,A
PWRGD_P1V8_PCH_AUX       PR1651           2        Q_RES_0402LF-0,5%,1/16W,CHIP,CA
PWRGD_P1V8_PCH_AUX       R1444            1        Q_RES_0402LF-33.2,1%,1/16W,CHIA
PWRGD_P1V8_PCH_AUX_PLD   R1444            2        Q_RES_0402LF-33.2,1%,1/16W,CHIA
PWRGD_P1V8_PCH_AUX_PLD   U122             P4       10M04SAU324I7G-10M04SAU324I7G,A
PWRGD_P1V8_PCH_AUX_R     PR1302           2        Q_RES_0402LF-10K,1%,1/16W,CHIPA
PWRGD_P1V8_PCH_AUX_R     PR1651           1        Q_RES_0402LF-0,5%,1/16W,CHIP,CA
PWRGD_P1V8_PCH_AUX_R     PU74             13       NB695GDZ-NB695GD-Z,SMLF,IC,AL0A
PWRGD_P3V3               R1682            2        Q_RES_0402LF-10K,5%,1/16W,CHIPA
PWRGD_P3V3               R1698            1        Q_RES_0402LF-20K,5%,1/16W,CHIPA
PWRGD_P3V3               R1706            2        Q_RES_0402LF-4.7K,5%,1/16W,EMPA
PWRGD_P3V3               U122             U2       10M04SAU324I7G-10M04SAU324I7G,A
PWRGD_P3V3_AUX           PR73             2        Q_RES_0402LF-10K,5%,1/16W,CHIPA
PWRGD_P3V3_AUX           PU9              2        NCP3284MNTXG-NCP3284MNTXG,SMLFA
PWRGD_P3V3_AUX           R1919            1        Q_RES_0402LF-33.2,1%,1/16W,CHIA
PWRGD_P3V3_AUX           R1950            2        Q_RES_0402LF-0,5%,1/16W,CHIP,CA
PWRGD_P3V3_AUX_PLD       R1919            2        Q_RES_0402LF-33.2,1%,1/16W,CHIA
PWRGD_P3V3_AUX_PLD       U122             M1       10M04SAU324I7G-10M04SAU324I7G,A
PWRGD_P3V3_R             R1682            1        Q_RES_0402LF-10K,5%,1/16W,CHIPA
PWRGD_P3V3_R             U79              8        SLG55221120010VTR-SLG55221-120A
PWRGD_P5V                R1655            2        Q_RES_0402LF-10K,5%,1/16W,CHIPA
PWRGD_P5V                U79              2        SLG55221120010VTR-SLG55221-120A
PWRGD_P5V                U99              1        RT9818C44GV-RT9818C-44GV,SMLF,A
PWRGD_P5V_AUX            PR90             2        Q_RES_0402LF-10K,5%,1/16W,CHIPA
PWRGD_P5V_AUX            PU9              27       NCP3284MNTXG-NCP3284MNTXG,SMLFA
PWRGD_P5V_AUX            PU181            9        MPQ8633BGLEC838Z-MPQ8633BGLE-CA
PWRGD_PCH_PWROK          R1403            1        Q_RES_0402LF-2K,1%,1/16W,CHIP,A
PWRGD_PCH_PWROK          R1442            2        Q_RES_0402LF-33.2,1%,1/16W,CHIA
PWRGD_PCH_PWROK          U4               BE4      EMMITSBURG_REV0P9-GFNOCPU04302A
PWRGD_PCH_PWROK_R        C1211            1        Q_CAP_0402-100PF,50V,5%,X7R,CHA
PWRGD_PCH_PWROK_R        R1442            1        Q_RES_0402LF-33.2,1%,1/16W,CHIA
PWRGD_PCH_PWROK_R        U122             H11      10M04SAU324I7G-10M04SAU324I7G,A
PWRGD_PLT_AUX_CPU0_LVT3  R67              2        Q_RES_0402LF-33.2,1%,1/16W,CHIA
PWRGD_PLT_AUX_CPU0_LVT3  R69              1        Q_RES_0402LF-10K,1%,1/16W,CHIPA
PWRGD_PLT_AUX_CPU0_LVT3  U2               CV20     SOCKET4677_AZIFS054P001C01-SOCA
PWRGD_PLT_AUX_CPU0_LVT3_R R67              1        Q_RES_0402LF-33.2,1%,1/16W,CHIA
PWRGD_PLT_AUX_CPU0_LVT3_R U122             N15      10M04SAU324I7G-10M04SAU324I7G,A
PWRGD_PLT_AUX_CPU1_LVT3  R68              2        Q_RES_0402LF-33.2,1%,1/16W,CHIA
PWRGD_PLT_AUX_CPU1_LVT3  R70              1        Q_RES_0402LF-10K,1%,1/16W,CHIPA
PWRGD_PLT_AUX_CPU1_LVT3  U1               CV20     SOCKET4677_AZIFS054P001C01-SOCA
PWRGD_PLT_AUX_CPU1_LVT3_R R68              1        Q_RES_0402LF-33.2,1%,1/16W,CHIA
PWRGD_PLT_AUX_CPU1_LVT3_R U122             N16      10M04SAU324I7G-10M04SAU324I7G,A
PWRGD_PS_PWROK           R1816            1        Q_RES_0402LF-0,5%,1/16W,CHIP,CA
PWRGD_PS_PWROK           R2186            2        Q_RES_0402LF-33,5%,1/16W,CHIP,A
PWRGD_PS_PWROK_PLD       R955             2        Q_RES_0402LF-33,5%,1/16W,CHIP,A
PWRGD_PS_PWROK_PLD       R1446            1        Q_RES_0402LF-33.2,1%,1/16W,CHIA
PWRGD_PS_PWROK_PLD_R     R1446            2        Q_RES_0402LF-33.2,1%,1/16W,CHIA
PWRGD_PS_PWROK_PLD_R     U122             N14      10M04SAU324I7G-10M04SAU324I7G,A
PWRGD_PS_PWROK_R         J41              A44      SCONN168_623403212-SCONN168_6-A
PWRGD_PS_PWROK_R         R1816            2        Q_RES_0402LF-0,5%,1/16W,CHIP,CA
PWRGD_PVCCD_HV_CPU0      PR362            1        Q_RES_0402LF-0,5%,1/16W,CHIP,CA
PWRGD_PVCCD_HV_CPU0      U122             M2       10M04SAU324I7G-10M04SAU324I7G,A
PWRGD_PVCCD_HV_CPU0_R    PC626            1        Q_CAP_0402-1000PF,50V,5%,EMPTYA
PWRGD_PVCCD_HV_CPU0_R    PR361            2        Q_RES_0402LF-1K,1%,1/16W,CHIP,A
PWRGD_PVCCD_HV_CPU0_R    PR362            2        Q_RES_0402LF-0,5%,1/16W,CHIP,CA
PWRGD_PVCCD_HV_CPU0_R    PU35             12       ISL69260IRAZT-ISL69260IRAZ-T,SA
PWRGD_PVCCD_HV_CPU1      PR207            1        Q_RES_0402LF-0,5%,1/16W,CHIP,CA
PWRGD_PVCCD_HV_CPU1      U122             M3       10M04SAU324I7G-10M04SAU324I7G,A
PWRGD_PVCCD_HV_CPU1_R    PC388            1        Q_CAP_0402-1000PF,50V,5%,EMPTYA
PWRGD_PVCCD_HV_CPU1_R    PR206            2        Q_RES_0402LF-1K,1%,1/16W,CHIP,A
PWRGD_PVCCD_HV_CPU1_R    PR207            2        Q_RES_0402LF-0,5%,1/16W,CHIP,CA
PWRGD_PVCCD_HV_CPU1_R    PU18             12       ISL69260IRAZT-ISL69260IRAZ-T,SA
PWRGD_PVCCFA_EHV_CPU0    PR118            1        Q_RES_0402LF-0,5%,1/16W,CHIP,CA
PWRGD_PVCCFA_EHV_CPU0    U122             M4       10M04SAU324I7G-10M04SAU324I7G,A
PWRGD_PVCCFA_EHV_CPU0_R  PC220            1        Q_CAP_0402-1000PF,50V,5%,EMPTYA
PWRGD_PVCCFA_EHV_CPU0_R  PR117            2        Q_RES_0402LF-1K,1%,1/16W,CHIP,A
PWRGD_PVCCFA_EHV_CPU0_R  PR118            2        Q_RES_0402LF-0,5%,1/16W,CHIP,CA
PWRGD_PVCCFA_EHV_CPU0_R  PU5              16       ISL69260IRAZT-ISL69260IRAZ-T,SA
PWRGD_PVCCFA_EHV_CPU1    PR271            1        Q_RES_0402LF-0,5%,1/16W,CHIP,CA
PWRGD_PVCCFA_EHV_CPU1    U122             K8       10M04SAU324I7G-10M04SAU324I7G,A
PWRGD_PVCCFA_EHV_CPU1_R  PC473            1        Q_CAP_0402-1000PF,50V,5%,EMPTYA
PWRGD_PVCCFA_EHV_CPU1_R  PR270            2        Q_RES_0402LF-1K,1%,1/16W,CHIP,A
PWRGD_PVCCFA_EHV_CPU1_R  PR271            2        Q_RES_0402LF-0,5%,1/16W,CHIP,CA
PWRGD_PVCCFA_EHV_CPU1_R  PU22             16       ISL69260IRAZT-ISL69260IRAZ-T,SA
PWRGD_PVCCFA_EHV_FIVRA_CPU0 PR336            1        Q_RES_0402LF-0,5%,1/16W,CHIP,CA
PWRGD_PVCCFA_EHV_FIVRA_CPU0 U122             N1       10M04SAU324I7G-10M04SAU324I7G,A
PWRGD_PVCCFA_EHV_FIVRA_CPU0_R PC593            1        Q_CAP_0402-1000PF,50V,5%,EMPTYA
PWRGD_PVCCFA_EHV_FIVRA_CPU0_R PR335            2        Q_RES_0402LF-1K,1%,1/16W,CHIP,A
PWRGD_PVCCFA_EHV_FIVRA_CPU0_R PR336            2        Q_RES_0402LF-0,5%,1/16W,CHIP,CA
PWRGD_PVCCFA_EHV_FIVRA_CPU0_R PU14             20       RAA229126GNPHA0-RAA229126GNP#HA
PWRGD_PVCCFA_EHV_FIVRA_CPU1 PR233            1        Q_RES_0402LF-0,5%,1/16W,CHIP,CA
PWRGD_PVCCFA_EHV_FIVRA_CPU1 U122             L8       10M04SAU324I7G-10M04SAU324I7G,A
PWRGD_PVCCFA_EHV_FIVRA_CPU1_R PC421            1        Q_CAP_0402-1000PF,50V,5%,EMPTYA
PWRGD_PVCCFA_EHV_FIVRA_CPU1_R PR232            2        Q_RES_0402LF-1K,1%,1/16W,CHIP,A
PWRGD_PVCCFA_EHV_FIVRA_CPU1_R PR233            2        Q_RES_0402LF-0,5%,1/16W,CHIP,CA
PWRGD_PVCCFA_EHV_FIVRA_CPU1_R PU29             20       RAA229126GNPHA0-RAA229126GNP#HA
PWRGD_PVCCINFAON_CPU0    PR110            1        Q_RES_0402LF-0,5%,1/16W,CHIP,CA
PWRGD_PVCCINFAON_CPU0    U122             N3       10M04SAU324I7G-10M04SAU324I7G,A
PWRGD_PVCCINFAON_CPU0_R  PC218            1        Q_CAP_0402-1000PF,50V,5%,EMPTYA
PWRGD_PVCCINFAON_CPU0_R  PR109            2        Q_RES_0402LF-1K,1%,1/16W,CHIP,A
PWRGD_PVCCINFAON_CPU0_R  PR110            2        Q_RES_0402LF-0,5%,1/16W,CHIP,CA
PWRGD_PVCCINFAON_CPU0_R  PU5              12       ISL69260IRAZT-ISL69260IRAZ-T,SA
PWRGD_PVCCINFAON_CPU1    PR263            1        Q_RES_0402LF-0,5%,1/16W,CHIP,CA
PWRGD_PVCCINFAON_CPU1    U122             R2       10M04SAU324I7G-10M04SAU324I7G,A
PWRGD_PVCCINFAON_CPU1_R  PC471            1        Q_CAP_0402-1000PF,50V,5%,EMPTYA
PWRGD_PVCCINFAON_CPU1_R  PR262            2        Q_RES_0402LF-1K,1%,1/16W,CHIP,A
PWRGD_PVCCINFAON_CPU1_R  PR263            2        Q_RES_0402LF-0,5%,1/16W,CHIP,CA
PWRGD_PVCCINFAON_CPU1_R  PU22             12       ISL69260IRAZT-ISL69260IRAZ-T,SA
PWRGD_PVCCIN_CPU0        PR161            1        Q_RES_0402LF-0,5%,1/16W,CHIP,CA
PWRGD_PVCCIN_CPU0        U122             P1       10M04SAU324I7G-10M04SAU324I7G,A
PWRGD_PVCCIN_CPU0_R      PC333            1        Q_CAP_0402-1000PF,50V,5%,EMPTYA
PWRGD_PVCCIN_CPU0_R      PR160            2        Q_RES_0402LF-1K,1%,1/16W,CHIP,A
PWRGD_PVCCIN_CPU0_R      PR161            2        Q_RES_0402LF-0,5%,1/16W,CHIP,CA
PWRGD_PVCCIN_CPU0_R      PU14             16       RAA229126GNPHA0-RAA229126GNP#HA
PWRGD_PVCCIN_CPU1        PR308            1        Q_RES_0402LF-0,5%,1/16W,CHIP,CA
PWRGD_PVCCIN_CPU1        U122             R1       10M04SAU324I7G-10M04SAU324I7G,A
PWRGD_PVCCIN_CPU1_R      PC551            1        Q_CAP_0402-1000PF,50V,5%,EMPTYA
PWRGD_PVCCIN_CPU1_R      PR307            2        Q_RES_0402LF-1K,1%,1/16W,CHIP,A
PWRGD_PVCCIN_CPU1_R      PR308            2        Q_RES_0402LF-0,5%,1/16W,CHIP,CA
PWRGD_PVCCIN_CPU1_R      PU29             16       RAA229126GNPHA0-RAA229126GNP#HA
PWRGD_PVNN_MAIN_CPU0     C1296            1        Q_CAP_0402-1000PF,50V,5%,X7R,TA
PWRGD_PVNN_MAIN_CPU0     R1652            2        Q_RES_0402LF-0,5%,1/16W,CHIP,CA
PWRGD_PVNN_MAIN_CPU0     U17              1        74CBTLV3126PW-74CBTLV3126PW,SMA
PWRGD_PVNN_MAIN_CPU0     U17              4        74CBTLV3126PW-74CBTLV3126PW,SMA
PWRGD_PVNN_MAIN_CPU0     U17              10       74CBTLV3126PW-74CBTLV3126PW,SMA
PWRGD_PVNN_MAIN_CPU0     U17              13       74CBTLV3126PW-74CBTLV3126PW,SMA
PWRGD_PVNN_MAIN_CPU0     U18              1        74CBTLV3126PW-74CBTLV3126PW,SMA
PWRGD_PVNN_MAIN_CPU0     U18              4        74CBTLV3126PW-74CBTLV3126PW,SMA
PWRGD_PVNN_MAIN_CPU0     U18              10       74CBTLV3126PW-74CBTLV3126PW,SMA
PWRGD_PVNN_MAIN_CPU0     U18              13       74CBTLV3126PW-74CBTLV3126PW,SMA
PWRGD_PVNN_MAIN_CPU0     U122             R3       10M04SAU324I7G-10M04SAU324I7G,A
PWRGD_PVNN_MAIN_CPU0_R   PR1317           2        Q_RES_0402LF-10K,1%,1/16W,CHIPA
PWRGD_PVNN_MAIN_CPU0_R   PU81             9        MPQ8626GDZ-MPQ8626GD-Z,SMLF,ICA
PWRGD_PVNN_MAIN_CPU0_R   R1652            1        Q_RES_0402LF-0,5%,1/16W,CHIP,CA
PWRGD_PVNN_MAIN_CPU1     C1297            1        Q_CAP_0402-1000PF,50V,5%,X7R,TA
PWRGD_PVNN_MAIN_CPU1     R2387            2        Q_RES_0402LF-0,5%,1/16W,CHIP,CA
PWRGD_PVNN_MAIN_CPU1     U122             P2       10M04SAU324I7G-10M04SAU324I7G,A
PWRGD_PVNN_MAIN_CPU1_R   PR1320           2        Q_RES_0402LF-10K,1%,1/16W,CHIPA
PWRGD_PVNN_MAIN_CPU1_R   PU82             9        MPQ8626GDZ-MPQ8626GD-Z,SMLF,ICA
PWRGD_PVNN_MAIN_CPU1_R   R2387            1        Q_RES_0402LF-0,5%,1/16W,CHIP,CA
PWRGD_PVNN_PCH_AUX       PR2390           2        Q_RES_0402LF-0,5%,1/16W,CHIP,CA
PWRGD_PVNN_PCH_AUX       U122             T3       10M04SAU324I7G-10M04SAU324I7G,A
PWRGD_PVPP_HBM_CPU0      R2334            2        Q_RES_0402LF-0,5%,1/16W,EMPTY,A
PWRGD_PVPP_HBM_CPU0      U122             P3       10M04SAU324I7G-10M04SAU324I7G,A
PWRGD_PVPP_HBM_CPU0_R    C1301            1        Q_CAP_0402-1000PF,50V,5%,EMPTYA
PWRGD_PVPP_HBM_CPU0_R    PR1309           2        Q_RES_0402LF-10K,1%,1/16W,EMPTA
PWRGD_PVPP_HBM_CPU0_R    PU79             9        MPQ8633AGLEC807Z-MPQ8633AGLE-CA
PWRGD_PVPP_HBM_CPU0_R    R2334            1        Q_RES_0402LF-0,5%,1/16W,EMPTY,A
PWRGD_PVPP_HBM_CPU1      R2380            2        Q_RES_0402LF-0,5%,1/16W,CHIP,CA
PWRGD_PVPP_HBM_CPU1      U122             L7       10M04SAU324I7G-10M04SAU324I7G,A
PWRGD_PVPP_HBM_CPU1_R    C2446            1        Q_CAP_0402-1000PF,50V,5%,X7R,TA
PWRGD_PVPP_HBM_CPU1_R    PR1313           2        Q_RES_0402LF-10K,1%,1/16W,CHIPA
PWRGD_PVPP_HBM_CPU1_R    PU80             9        MPQ8633AGLEC807Z-MPQ8633AGLE-CB
PWRGD_PVPP_HBM_CPU1_R    R2380            1        Q_RES_0402LF-0,5%,1/16W,CHIP,CA
PWRGD_S0_PWROK_CPU0_LVC1 R1218            1        Q_RES_0402LF-33.2,1%,1/16W,CHIA
PWRGD_S0_PWROK_CPU0_LVC1 U2               CH71     SOCKET4677_AZIFS054P001C01-SOCA
PWRGD_S0_PWROK_CPU0_LVC1_R R9               1        Q_RES_0402LF-4.32K,1%,1/16W,CHA
PWRGD_S0_PWROK_CPU0_LVC1_R R1218            2        Q_RES_0402LF-33.2,1%,1/16W,CHIA
PWRGD_S0_PWROK_CPU0_LVC1_R U122             U11      10M04SAU324I7G-10M04SAU324I7G,A
PWRGD_S0_PWROK_CPU1_LVC1 R1219            1        Q_RES_0402LF-33.2,1%,1/16W,CHIA
PWRGD_S0_PWROK_CPU1_LVC1 U1               CH71     SOCKET4677_AZIFS054P001C01-SOCA
PWRGD_S0_PWROK_CPU1_LVC1_R R316             1        Q_RES_0402LF-4.32K,1%,1/16W,CHA
PWRGD_S0_PWROK_CPU1_LVC1_R R1219            2        Q_RES_0402LF-33.2,1%,1/16W,CHIA
PWRGD_S0_PWROK_CPU1_LVC1_R U122             U5       10M04SAU324I7G-10M04SAU324I7G,A
PWRGD_SYS_PWROK          J41              A48      SCONN168_623403212-SCONN168_6-A
PWRGD_SYS_PWROK          R1402            1        Q_RES_0402LF-2K,1%,1/16W,CHIP,A
PWRGD_SYS_PWROK          R1423            2        Q_RES_0402LF-33.2,1%,1/16W,CHIA
PWRGD_SYS_PWROK          U4               AL10     EMMITSBURG_REV0P9-GFNOCPU04302A
PWRGD_SYS_PWROK_R        C1209            1        Q_CAP_0402-100PF,50V,5%,X7R,CHA
PWRGD_SYS_PWROK_R        R1423            1        Q_RES_0402LF-33.2,1%,1/16W,CHIA
PWRGD_SYS_PWROK_R        U122             H12      10M04SAU324I7G-10M04SAU324I7G,A
RISER1_CLK0_EN_N         J55              B11      SCONN140_G64V3431BHR-SCONN140_A
RISER1_CLK0_EN_N         R2173            2        Q_RES_0402LF-10K,5%,1/16W,CHIPA
RISER1_CLK1_EN_N         J55              B12      SCONN140_G64V3431BHR-SCONN140_A
RISER1_CLK1_EN_N         R2174            2        Q_RES_0402LF-10K,5%,1/16W,CHIPA
RISER1_TYPE_ID           J55              A9       SCONN140_G64V3431BHR-SCONN140_A
RISER1_TYPE_ID           R2167            2        Q_RES_0402LF-10K,1%,1/16W,CHIPA
RISER2_CLK2_EN_N         J89              A31      SCONN280_ME1028040102011-SCONNA
RISER2_CLK2_EN_N         R1576            2        Q_RES_0402LF-10K,5%,1/16W,CHIPA
RISER2_CLK2_EN_N         U13              A26      9SQ440NQQI8-9SQ440NQQI8,SMLF,IA
RISER2_CLK3_EN_N         J89              B27      SCONN280_ME1028040102011-SCONNA
RISER2_CLK3_EN_N         R1575            2        Q_RES_0402LF-10K,5%,1/16W,CHIPA
RISER2_CLK3_EN_N         U13              B19      9SQ440NQQI8-9SQ440NQQI8,SMLF,IA
RISER2_TYPE_ID           J89              B31      SCONN280_ME1028040102011-SCONNA
RISER2_TYPE_ID           R388             2        Q_RES_0402LF-10K,1%,1/16W,CHIPA
RISER2_TYPE_ID           U4               AA7      EMMITSBURG_REV0P9-GFNOCPU04302A
RISER2_USB2_4_DN         J89              B20      SCONN280_ME1028040102011-SCONNA
RISER2_USB2_4_DN         R2130            2        Q_RES_0402LF-0,5%,1/16W,CHIP,CA
RISER2_USB2_4_DP         J89              B21      SCONN280_ME1028040102011-SCONNA
RISER2_USB2_4_DP         R2131            2        Q_RES_0402LF-0,5%,1/16W,CHIP,CA
RISER3_CLK4_EN_N         J57              B11      SCONN140_G64V3431BHR-SCONN140_A
RISER3_CLK4_EN_N         R1579            2        Q_RES_0402LF-10K,5%,1/16W,CHIPA
RISER3_CLK4_EN_N         U13              B15      9SQ440NQQI8-9SQ440NQQI8,SMLF,IA
RISER3_CLK5_EN_N         J57              B12      SCONN140_G64V3431BHR-SCONN140_A
RISER3_CLK5_EN_N         R1580            2        Q_RES_0402LF-10K,5%,1/16W,CHIPA
RISER3_CLK5_EN_N         U13              B14      9SQ440NQQI8-9SQ440NQQI8,SMLF,IA
RISER3_TYPE_ID           J57              A9       SCONN140_G64V3431BHR-SCONN140_A
RISER3_TYPE_ID           R391             2        Q_RES_0402LF-10K,1%,1/16W,CHIPA
RISER3_TYPE_ID           U4               W7       EMMITSBURG_REV0P9-GFNOCPU04302A
RMII_BMC_OCP_RX_ER       J41              B23      SCONN168_623403212-SCONN168_6-A
RMII_BMC_OCP_RX_ER       R1356            1        Q_RES_0402LF-1K,1%,1/16W,CHIP,A
RMII_BMC_OCP_TXD_0       J41              B21      SCONN168_623403212-SCONN168_6-A
RMII_BMC_OCP_TXD_0       R1295            2        Q_RES_0402LF-22,1%,1/16W,CHIP,A
RMII_BMC_OCP_TXD_0       R1354            1        Q_RES_0402LF-100K,1%,1/16W,CHIA
RMII_BMC_OCP_TXD_1       J41              B22      SCONN168_623403212-SCONN168_6-A
RMII_BMC_OCP_TXD_1       R1296            2        Q_RES_0402LF-22,1%,1/16W,CHIP,A
RMII_BMC_OCP_TXD_1       R1355            1        Q_RES_0402LF-100K,1%,1/16W,CHIA
RMII_BMC_OCP_TX_EN       J41              B20      SCONN168_623403212-SCONN168_6-A
RMII_BMC_OCP_TX_EN       R1294            2        Q_RES_0402LF-22,1%,1/16W,CHIP,A
RMII_BMC_OCP_TX_EN       R1353            1        Q_RES_0402LF-100K,1%,1/16W,CHIA
RMII_OCP_BMC_CRSDV       J41              B19      SCONN168_623403212-SCONN168_6-A
RMII_OCP_BMC_CRSDV       R1291            2        Q_RES_0402LF-22,1%,1/16W,CHIP,A
RMII_OCP_BMC_CRSDV       R1350            1        Q_RES_0402LF-100K,1%,1/16W,CHIA
RMII_OCP_BMC_RXD_0       J41              B24      SCONN168_623403212-SCONN168_6-A
RMII_OCP_BMC_RXD_0       R1292            2        Q_RES_0402LF-22,1%,1/16W,CHIP,A
RMII_OCP_BMC_RXD_0       R1351            1        Q_RES_0402LF-100K,1%,1/16W,CHIA
RMII_OCP_BMC_RXD_1       J41              B25      SCONN168_623403212-SCONN168_6-A
RMII_OCP_BMC_RXD_1       R1293            2        Q_RES_0402LF-22,1%,1/16W,CHIP,A
RMII_OCP_BMC_RXD_1       R1352            1        Q_RES_0402LF-100K,1%,1/16W,CHIA
ROT_P1_RST_IND_N         J41              A53      SCONN168_623403212-SCONN168_6-A
ROT_P1_RST_IND_N         R1798            2        Q_RES_0402LF-0,5%,1/16W,CHIP,CA
ROT_P1_RST_IND_N_R       R1798            1        Q_RES_0402LF-0,5%,1/16W,CHIP,CA
ROT_P1_RST_IND_N_R       U122             F2       10M04SAU324I7G-10M04SAU324I7G,A
RST_CPU0_BUF_R_N         R171             2        Q_RES_0402LF-0,5%,1/16W,CHIP,CA
RST_CPU0_BUF_R_N         R185             1        Q_RES_0402LF-100,1%,1/16W,EMPTA
RST_CPU0_BUF_R_N         R186             1        Q_RES_0402LF-33,5%,1/16W,CHIP,A
RST_CPU0_DRAM_AB_N       R851             1        Q_RES_0402LF-0,5%,1/16W,CHIP,CA
RST_CPU0_DRAM_AB_N       R932             1        Q_RES_0402LF-10K,1%,1/16W,CHIPA
RST_CPU0_DRAM_AB_N       U2               AU50     SOCKET4677_AZIFS054P001C01-SOCA
RST_CPU0_DRAM_AB_PLD_N   R851             2        Q_RES_0402LF-0,5%,1/16W,CHIP,CA
RST_CPU0_DRAM_AB_PLD_N   U122             U12      10M04SAU324I7G-10M04SAU324I7G,A
RST_CPU0_DRAM_CD_N       R852             1        Q_RES_0402LF-0,5%,1/16W,CHIP,CA
RST_CPU0_DRAM_CD_N       R934             1        Q_RES_0402LF-10K,1%,1/16W,CHIPA
RST_CPU0_DRAM_CD_N       U2               AV51     SOCKET4677_AZIFS054P001C01-SOCA
RST_CPU0_DRAM_CD_PLD_N   R852             2        Q_RES_0402LF-0,5%,1/16W,CHIP,CA
RST_CPU0_DRAM_CD_PLD_N   U122             R13      10M04SAU324I7G-10M04SAU324I7G,A
RST_CPU0_DRAM_EF_N       R853             1        Q_RES_0402LF-0,5%,1/16W,CHIP,CA
RST_CPU0_DRAM_EF_N       R936             1        Q_RES_0402LF-10K,1%,1/16W,CHIPA
RST_CPU0_DRAM_EF_N       U2               CY42     SOCKET4677_AZIFS054P001C01-SOCA
RST_CPU0_DRAM_EF_PLD_N   R853             2        Q_RES_0402LF-0,5%,1/16W,CHIP,CA
RST_CPU0_DRAM_EF_PLD_N   U122             T14      10M04SAU324I7G-10M04SAU324I7G,A
RST_CPU0_DRAM_GH_N       R854             1        Q_RES_0402LF-0,5%,1/16W,CHIP,CA
RST_CPU0_DRAM_GH_N       R938             1        Q_RES_0402LF-10K,1%,1/16W,CHIPA
RST_CPU0_DRAM_GH_N       U2               CY55     SOCKET4677_AZIFS054P001C01-SOCA
RST_CPU0_DRAM_GH_PLD_N   R854             2        Q_RES_0402LF-0,5%,1/16W,CHIP,CA
RST_CPU0_DRAM_GH_PLD_N   U122             R12      10M04SAU324I7G-10M04SAU324I7G,A
RST_CPU0_LVC1_N          R186             2        Q_RES_0402LF-33,5%,1/16W,CHIP,A
RST_CPU0_LVC1_N          U2               BH61     SOCKET4677_AZIFS054P001C01-SOCA
RST_CPU0_LVC1_R_N        R171             1        Q_RES_0402LF-0,5%,1/16W,CHIP,CA
RST_CPU0_LVC1_R_N        R1415            1        Q_RES_0402LF-2K,1%,1/16W,CHIP,A
RST_CPU0_LVC1_R_N        U122             U6       10M04SAU324I7G-10M04SAU324I7G,A
RST_CPU1_BUF_R_N         R132             2        Q_RES_0402LF-0,5%,1/16W,CHIP,CA
RST_CPU1_BUF_R_N         R157             1        Q_RES_0402LF-100,1%,1/16W,EMPTA
RST_CPU1_BUF_R_N         R158             1        Q_RES_0402LF-33,5%,1/16W,CHIP,A
RST_CPU1_DRAM_AB_N       R859             1        Q_RES_0402LF-0,5%,1/16W,CHIP,CA
RST_CPU1_DRAM_AB_N       R933             1        Q_RES_0402LF-10K,1%,1/16W,CHIPA
RST_CPU1_DRAM_AB_N       U1               AU50     SOCKET4677_AZIFS054P001C01-SOCA
RST_CPU1_DRAM_AB_PLD_N   R859             2        Q_RES_0402LF-0,5%,1/16W,CHIP,CA
RST_CPU1_DRAM_AB_PLD_N   U122             T13      10M04SAU324I7G-10M04SAU324I7G,A
RST_CPU1_DRAM_CD_N       R860             1        Q_RES_0402LF-0,5%,1/16W,CHIP,CA
RST_CPU1_DRAM_CD_N       R935             1        Q_RES_0402LF-10K,1%,1/16W,CHIPA
RST_CPU1_DRAM_CD_N       U1               AV51     SOCKET4677_AZIFS054P001C01-SOCA
RST_CPU1_DRAM_CD_PLD_N   R860             2        Q_RES_0402LF-0,5%,1/16W,CHIP,CA
RST_CPU1_DRAM_CD_PLD_N   U122             R14      10M04SAU324I7G-10M04SAU324I7G,A
RST_CPU1_DRAM_EF_N       R861             1        Q_RES_0402LF-0,5%,1/16W,CHIP,CA
RST_CPU1_DRAM_EF_N       R937             1        Q_RES_0402LF-10K,1%,1/16W,CHIPA
RST_CPU1_DRAM_EF_N       U1               CY42     SOCKET4677_AZIFS054P001C01-SOCA
RST_CPU1_DRAM_EF_PLD_N   R861             2        Q_RES_0402LF-0,5%,1/16W,CHIP,CA
RST_CPU1_DRAM_EF_PLD_N   U122             T15      10M04SAU324I7G-10M04SAU324I7G,A
RST_CPU1_DRAM_GH_N       R862             1        Q_RES_0402LF-0,5%,1/16W,CHIP,CA
RST_CPU1_DRAM_GH_N       R939             1        Q_RES_0402LF-10K,1%,1/16W,CHIPA
RST_CPU1_DRAM_GH_N       U1               CY55     SOCKET4677_AZIFS054P001C01-SOCA
RST_CPU1_DRAM_GH_PLD_N   R862             2        Q_RES_0402LF-0,5%,1/16W,CHIP,CA
RST_CPU1_DRAM_GH_PLD_N   U122             R10      10M04SAU324I7G-10M04SAU324I7G,A
RST_CPU1_LVC1_N          R158             2        Q_RES_0402LF-33,5%,1/16W,CHIP,A
RST_CPU1_LVC1_N          U1               BH61     SOCKET4677_AZIFS054P001C01-SOCA
RST_CPU1_LVC1_R_N        R132             1        Q_RES_0402LF-0,5%,1/16W,CHIP,CA
RST_CPU1_LVC1_R_N        R1416            1        Q_RES_0402LF-2K,1%,1/16W,CHIP,A
RST_CPU1_LVC1_R_N        U122             M9       10M04SAU324I7G-10M04SAU324I7G,A
RST_ESPI_RESET_N         U4               BF17     EMMITSBURG_REV0P9-GFNOCPU04302A
RST_ESPI_RESET_N         U61              1        NC7SB3157_SMLF-NC7SB3157P6X,NCA
RST_HP_OCP_V3_1_N        U53              4        SN74LVC1G08DBVR_SMLF-SN74LVC1GA
RST_HP_OCP_V3_1_N        U75              2        SN74LVC1G17DCKR-SN74LVC1G17DCKA
RST_MB_STBY_N            J41              A46      SCONN168_623403212-SCONN168_6-A
RST_MB_STBY_N            R1206            2        Q_RES_0402LF-33,5%,1/16W,CHIP,A
RST_MB_STBY_R_N          R1206            1        Q_RES_0402LF-33,5%,1/16W,CHIP,A
RST_MB_STBY_R_N          R1823            2        Q_RES_0402LF-1K,1%,1/16W,CHIP,A
RST_MB_STBY_R_N          U122             C17      10M04SAU324I7G-10M04SAU324I7G,A
RST_M_AB_CPU0_FPGA_N     J1               207      SCONN288_ADR50001P013C01-SCONNA
RST_M_AB_CPU0_FPGA_N     J2               207      SCONN288_ADR50001P003C01-SCONNA
RST_M_AB_CPU0_FPGA_N     J3               207      SCONN288_ADR50001P013C01-SCONNA
RST_M_AB_CPU0_FPGA_N     J4               207      SCONN288_ADR50001P003C01-SCONNA
RST_M_AB_CPU0_FPGA_N     R836             2        Q_RES_0402LF-0,5%,1/16W,CHIP,CA
RST_M_AB_CPU0_FPGA_N     R840             2        Q_RES_0402LF-1K,1%,1/16W,EMPTYA
RST_M_AB_CPU1_FPGA_N     J17              207      SCONN288_ADR50001P013C01-SCONNA
RST_M_AB_CPU1_FPGA_N     J18              207      SCONN288_ADR50001P003C01-SCONNA
RST_M_AB_CPU1_FPGA_N     J19              207      SCONN288_ADR50001P013C01-SCONNA
RST_M_AB_CPU1_FPGA_N     J20              207      SCONN288_ADR50001P003C01-SCONNA
RST_M_AB_CPU1_FPGA_N     R816             2        Q_RES_0402LF-0,5%,1/16W,CHIP,CA
RST_M_AB_CPU1_FPGA_N     R820             2        Q_RES_0402LF-1K,1%,1/16W,EMPTYA
RST_M_CD_CPU0_FPGA_N     J5               207      SCONN288_ADR50001P013C01-SCONNA
RST_M_CD_CPU0_FPGA_N     J6               207      SCONN288_ADR50001P003C01-SCONNA
RST_M_CD_CPU0_FPGA_N     J7               207      SCONN288_ADR50001P013C01-SCONNA
RST_M_CD_CPU0_FPGA_N     J8               207      SCONN288_ADR50001P003C01-SCONNA
RST_M_CD_CPU0_FPGA_N     R837             2        Q_RES_0402LF-0,5%,1/16W,CHIP,CA
RST_M_CD_CPU0_FPGA_N     R841             2        Q_RES_0402LF-1K,1%,1/16W,EMPTYA
RST_M_CD_CPU1_FPGA_N     J21              207      SCONN288_ADR50001P013C01-SCONNA
RST_M_CD_CPU1_FPGA_N     J22              207      SCONN288_ADR50001P003C01-SCONNA
RST_M_CD_CPU1_FPGA_N     J23              207      SCONN288_ADR50001P013C01-SCONNA
RST_M_CD_CPU1_FPGA_N     J24              207      SCONN288_ADR50001P003C01-SCONNA
RST_M_CD_CPU1_FPGA_N     R817             2        Q_RES_0402LF-0,5%,1/16W,CHIP,CA
RST_M_CD_CPU1_FPGA_N     R821             2        Q_RES_0402LF-1K,1%,1/16W,EMPTYA
RST_M_EF_CPU0_FPGA_N     J9               207      SCONN288_ADR50001P013C01-SCONNA
RST_M_EF_CPU0_FPGA_N     J10              207      SCONN288_ADR50001P003C01-SCONNA
RST_M_EF_CPU0_FPGA_N     J11              207      SCONN288_ADR50001P013C01-SCONNA
RST_M_EF_CPU0_FPGA_N     J12              207      SCONN288_ADR50001P003C01-SCONNA
RST_M_EF_CPU0_FPGA_N     R838             2        Q_RES_0402LF-0,5%,1/16W,CHIP,CA
RST_M_EF_CPU0_FPGA_N     R842             2        Q_RES_0402LF-1K,1%,1/16W,EMPTYA
RST_M_EF_CPU1_FPGA_N     J25              207      SCONN288_ADR50001P013C01-SCONNA
RST_M_EF_CPU1_FPGA_N     J26              207      SCONN288_ADR50001P003C01-SCONNA
RST_M_EF_CPU1_FPGA_N     J27              207      SCONN288_ADR50001P013C01-SCONNA
RST_M_EF_CPU1_FPGA_N     J28              207      SCONN288_ADR50001P003C01-SCONNA
RST_M_EF_CPU1_FPGA_N     R818             2        Q_RES_0402LF-0,5%,1/16W,CHIP,CA
RST_M_EF_CPU1_FPGA_N     R822             2        Q_RES_0402LF-1K,1%,1/16W,EMPTYA
RST_M_GH_CPU0_FPGA_N     J13              207      SCONN288_ADR50001P013C01-SCONNA
RST_M_GH_CPU0_FPGA_N     J14              207      SCONN288_ADR50001P003C01-SCONNA
RST_M_GH_CPU0_FPGA_N     J15              207      SCONN288_ADR50001P013C01-SCONNA
RST_M_GH_CPU0_FPGA_N     J16              207      SCONN288_ADR50001P003C01-SCONNA
RST_M_GH_CPU0_FPGA_N     R835             2        Q_RES_0402LF-0,5%,1/16W,CHIP,CA
RST_M_GH_CPU0_FPGA_N     R839             2        Q_RES_0402LF-1K,1%,1/16W,EMPTYA
RST_M_GH_CPU1_FPGA_N     J29              207      SCONN288_ADR50001P013C01-SCONNA
RST_M_GH_CPU1_FPGA_N     J30              207      SCONN288_ADR50001P003C01-SCONNA
RST_M_GH_CPU1_FPGA_N     J31              207      SCONN288_ADR50001P013C01-SCONNA
RST_M_GH_CPU1_FPGA_N     J32              207      SCONN288_ADR50001P003C01-SCONNA
RST_M_GH_CPU1_FPGA_N     R815             2        Q_RES_0402LF-0,5%,1/16W,CHIP,CA
RST_M_GH_CPU1_FPGA_N     R819             2        Q_RES_0402LF-1K,1%,1/16W,EMPTYA
RST_OCP_V3_1_BUF_N       R419             1        Q_RES_0402LF-33.2,1%,1/16W,CHIA
RST_OCP_V3_1_BUF_N       R435             1        Q_RES_0402LF-33.2,1%,1/16W,CHIA
RST_OCP_V3_1_BUF_N       R1504            1        Q_RES_0402LF-33.2,1%,1/16W,CHIA
RST_OCP_V3_1_BUF_N       R1505            1        Q_RES_0402LF-33.2,1%,1/16W,CHIA
RST_OCP_V3_1_BUF_N       U75              4        SN74LVC1G17DCKR-SN74LVC1G17DCKA
RST_OCP_V3_1_N           R1514            2        Q_RES_0402LF-33.2,1%,1/16W,CHIA
RST_OCP_V3_1_N           U53              2        SN74LVC1G08DBVR_SMLF-SN74LVC1GA
RST_PCH_RSTBTN_R_N       R696             2        Q_RES_0402LF-4.75K,1%,1/16W,CHA
RST_PCH_RSTBTN_R_N       R697             2        Q_RES_0402LF-33,5%,1/16W,CHIP,A
RST_PCH_RSTBTN_R_N       U4               AJ10     EMMITSBURG_REV0P9-GFNOCPU04302A
RST_PCIE_BUF_E1S_0_PERST_N R2113            1        Q_RES_0402LF-0,5%,1/16W,CHIP,CA
RST_PCIE_BUF_E1S_0_PERST_N U134             6        SN74LVC2G07DCKR_SMLF-SN74LVC2GA
RST_PCIE_BUF_E1S_1_PERST_N R2114            1        Q_RES_0402LF-0,5%,1/16W,CHIP,CA
RST_PCIE_BUF_E1S_1_PERST_N U134             4        SN74LVC2G07DCKR_SMLF-SN74LVC2GA
RST_PCIE_BUF_E1S_2_PERST_N R2115            1        Q_RES_0402LF-0,5%,1/16W,CHIP,CA
RST_PCIE_BUF_E1S_2_PERST_N U135             6        SN74LVC2G07DCKR_SMLF-SN74LVC2GA
RST_PCIE_BUF_E1S_3_PERST_N R2116            1        Q_RES_0402LF-0,5%,1/16W,CHIP,CA
RST_PCIE_BUF_E1S_3_PERST_N U135             4        SN74LVC2G07DCKR_SMLF-SN74LVC2GA
RST_PCIE_CPU0_DEV_PERST_N R1417            1        Q_RES_0402LF-2K,1%,1/16W,CHIP,A
RST_PCIE_CPU0_DEV_PERST_N R1512            1        Q_RES_0402LF-33.2,1%,1/16W,CHIA
RST_PCIE_CPU0_DEV_PERST_N R1513            1        Q_RES_0402LF-33.2,1%,1/16W,CHIA
RST_PCIE_CPU0_DEV_PERST_N R1514            1        Q_RES_0402LF-33.2,1%,1/16W,CHIA
RST_PCIE_CPU0_DEV_PERST_N R1515            1        Q_RES_0402LF-33.2,1%,1/16W,CHIA
RST_PCIE_CPU0_DEV_PERST_N R1516            1        Q_RES_0402LF-33.2,1%,1/16W,CHIA
RST_PCIE_CPU0_DEV_PERST_N R2050            1        Q_RES_0402LF-33.2,1%,1/16W,CHIA
RST_PCIE_CPU0_DEV_PERST_N R2129            1        Q_RES_0402LF-33.2,1%,1/16W,CHIA
RST_PCIE_CPU0_DEV_PERST_N U122             H15      10M04SAU324I7G-10M04SAU324I7G,A
RST_PCIE_CPU1_DEV_PERST_N R1418            1        Q_RES_0402LF-2K,1%,1/16W,CHIP,A
RST_PCIE_CPU1_DEV_PERST_N R1518            1        Q_RES_0402LF-33.2,1%,1/16W,CHIA
RST_PCIE_CPU1_DEV_PERST_N R1519            1        Q_RES_0402LF-33.2,1%,1/16W,CHIA
RST_PCIE_CPU1_DEV_PERST_N R1520            1        Q_RES_0402LF-33.2,1%,1/16W,CHIA
RST_PCIE_CPU1_DEV_PERST_N R1521            1        Q_RES_0402LF-33.2,1%,1/16W,CHIA
RST_PCIE_CPU1_DEV_PERST_N U122             H16      10M04SAU324I7G-10M04SAU324I7G,A
RST_PCIE_E1S_0_PERST_N   J90              B10      CONN56_ME2005602311011-CONN56_A
RST_PCIE_E1S_0_PERST_N   R2113            2        Q_RES_0402LF-0,5%,1/16W,CHIP,CA
RST_PCIE_E1S_0_PERST_N   R2121            2        Q_RES_0402LF-4.7K,5%,1/16W,CHIA
RST_PCIE_E1S_1_PERST_N   J91              B10      CONN56_ME2005602311011-CONN56_A
RST_PCIE_E1S_1_PERST_N   R2114            2        Q_RES_0402LF-0,5%,1/16W,CHIP,CA
RST_PCIE_E1S_1_PERST_N   R2125            2        Q_RES_0402LF-4.7K,5%,1/16W,CHIA
RST_PCIE_E1S_2_PERST_N   J92              B10      CONN56_ME2005602311011-CONN56_A
RST_PCIE_E1S_2_PERST_N   R2115            2        Q_RES_0402LF-0,5%,1/16W,CHIP,CA
RST_PCIE_E1S_2_PERST_N   R2122            2        Q_RES_0402LF-4.7K,5%,1/16W,CHIA
RST_PCIE_E1S_3_PERST_N   J93              B10      CONN56_ME2005602311011-CONN56_A
RST_PCIE_E1S_3_PERST_N   R2116            2        Q_RES_0402LF-0,5%,1/16W,CHIP,CA
RST_PCIE_E1S_3_PERST_N   R2126            2        Q_RES_0402LF-4.7K,5%,1/16W,CHIA
RST_PCIE_E1S_PERST_N     R2129            2        Q_RES_0402LF-33.2,1%,1/16W,CHIA
RST_PCIE_E1S_PERST_N     U134             1        SN74LVC2G07DCKR_SMLF-SN74LVC2GA
RST_PCIE_E1S_PERST_N     U134             3        SN74LVC2G07DCKR_SMLF-SN74LVC2GA
RST_PCIE_E1S_PERST_N     U135             1        SN74LVC2G07DCKR_SMLF-SN74LVC2GA
RST_PCIE_E1S_PERST_N     U135             3        SN74LVC2G07DCKR_SMLF-SN74LVC2GA
RST_PCIE_EDSFF1A_PERST_N J62              B10      SCONN84_123318136-SCONN84_1-23A
RST_PCIE_EDSFF1A_PERST_N R1515            2        Q_RES_0402LF-33.2,1%,1/16W,CHIA
RST_PCIE_EDSFF1B_PERST_N J87              B10      SCONN84_123318136-SCONN84_1-23A
RST_PCIE_EDSFF1B_PERST_N R1516            2        Q_RES_0402LF-33.2,1%,1/16W,CHIA
RST_PCIE_EDSFF2A_PERST_N J33              B10      SCONN84_123318136-SCONN84_1-23A
RST_PCIE_EDSFF2A_PERST_N R1512            2        Q_RES_0402LF-33.2,1%,1/16W,CHIA
RST_PCIE_EDSFF2B_PERST_N J34              B10      SCONN84_123318136-SCONN84_1-23A
RST_PCIE_EDSFF2B_PERST_N R2050            2        Q_RES_0402LF-33.2,1%,1/16W,CHIA
RST_PCIE_EDSFF3_PERST_N  J35              A9       SCONN140_G64V3431BHR-SCONN140_B
RST_PCIE_EDSFF3_PERST_N  R1520            2        Q_RES_0402LF-33.2,1%,1/16W,CHIA
RST_PCIE_EDSFF4A_PERST_N J88              B10      SCONN84_123318136-SCONN84_1-23A
RST_PCIE_EDSFF4A_PERST_N R1521            2        Q_RES_0402LF-33.2,1%,1/16W,CHIA
RST_PCIE_EDSFF4B_PERST_N J61              B10      SCONN84_123318136-SCONN84_1-23A
RST_PCIE_EDSFF4B_PERST_N R1519            2        Q_RES_0402LF-33.2,1%,1/16W,CHIA
RST_PCIE_PCH_DEV_0_N     J59              50       SCONN75K_APCI0155P004A-SCONN75A
RST_PCIE_PCH_DEV_0_N     R485             2        Q_RES_0402LF-0,5%,1/16W,CHIP,CA
RST_PCIE_PCH_DEV_PERST_N R485             1        Q_RES_0402LF-0,5%,1/16W,CHIP,CA
RST_PCIE_PCH_DEV_PERST_N R1419            1        Q_RES_0402LF-2K,1%,1/16W,CHIP,A
RST_PCIE_PCH_DEV_PERST_N U122             H17      10M04SAU324I7G-10M04SAU324I7G,A
RST_PCIE_RISER2_N        J89              A30      SCONN280_ME1028040102011-SCONNA
RST_PCIE_RISER2_N        R1513            2        Q_RES_0402LF-33.2,1%,1/16W,CHIA
RST_PCIE_RISER3_N        J57              A10      SCONN140_G64V3431BHR-SCONN140_A
RST_PCIE_RISER3_N        R1518            2        Q_RES_0402LF-33.2,1%,1/16W,CHIA
RST_PERST0_OCP_SFF_N     J37              B10      SCONN168_623403212-SCONN168_6-A
RST_PERST0_OCP_SFF_N     R419             2        Q_RES_0402LF-33.2,1%,1/16W,CHIA
RST_PERST1_OCP_SFF_N     J37              A11      SCONN168_623403212-SCONN168_6-A
RST_PERST1_OCP_SFF_N     R435             2        Q_RES_0402LF-33.2,1%,1/16W,CHIA
RST_PERST2_OCP_SFF_N     J37              OCP_A1   SCONN168_623403212-SCONN168_6-A
RST_PERST2_OCP_SFF_N     R1504            2        Q_RES_0402LF-33.2,1%,1/16W,CHIA
RST_PERST3_OCP_SFF_N     J37              OCP_A2   SCONN168_623403212-SCONN168_6-A
RST_PERST3_OCP_SFF_N     R1505            2        Q_RES_0402LF-33.2,1%,1/16W,CHIA
RST_PFR_OVR_RTC          Q34              G        MOSFET_N_GSD-NX7002AK,SMLF,IC,A
RST_PFR_OVR_RTC          R1839            1        Q_RES_0402LF-0,5%,1/16W,EMPTY,A
RST_PFR_OVR_RTC          R1843            2        Q_RES_0402LF-33.2,1%,1/16W,CHIA
RST_PFR_OVR_RTC_R        R1843            1        Q_RES_0402LF-33.2,1%,1/16W,CHIA
RST_PFR_OVR_RTC_R        U122             T17      10M04SAU324I7G-10M04SAU324I7G,A
RST_PFR_OVR_SRTC         Q35              G        MOSFET_N_GSD-NX7002AK,SMLF,IC,A
RST_PFR_OVR_SRTC         R1840            1        Q_RES_0402LF-0,5%,1/16W,EMPTY,A
RST_PFR_OVR_SRTC         R1844            2        Q_RES_0402LF-33.2,1%,1/16W,CHIA
RST_PFR_OVR_SRTC_R       R1844            1        Q_RES_0402LF-33.2,1%,1/16W,CHIA
RST_PFR_OVR_SRTC_R       U122             T18      10M04SAU324I7G-10M04SAU324I7G,A
RST_PLD_CPU0_DRAM_AB_N   C622             1        Q_CAP_C0402-1UF,25V,10%,EMPTY,A
RST_PLD_CPU0_DRAM_AB_N   R706             1        Q_RES_0402LF-10K,1%,1/16W,EMPTA
RST_PLD_CPU0_DRAM_AB_N   R836             1        Q_RES_0402LF-0,5%,1/16W,CHIP,CA
RST_PLD_CPU0_DRAM_AB_N   U122             T11      10M04SAU324I7G-10M04SAU324I7G,A
RST_PLD_CPU0_DRAM_CD_N   C623             1        Q_CAP_C0402-1UF,25V,10%,EMPTY,A
RST_PLD_CPU0_DRAM_CD_N   R707             1        Q_RES_0402LF-10K,1%,1/16W,EMPTA
RST_PLD_CPU0_DRAM_CD_N   R837             1        Q_RES_0402LF-0,5%,1/16W,CHIP,CA
RST_PLD_CPU0_DRAM_CD_N   U122             R11      10M04SAU324I7G-10M04SAU324I7G,A
RST_PLD_CPU0_DRAM_EF_N   C624             1        Q_CAP_C0402-1UF,25V,10%,EMPTY,A
RST_PLD_CPU0_DRAM_EF_N   R708             1        Q_RES_0402LF-10K,1%,1/16W,EMPTA
RST_PLD_CPU0_DRAM_EF_N   R838             1        Q_RES_0402LF-0,5%,1/16W,CHIP,CA
RST_PLD_CPU0_DRAM_EF_N   U122             T12      10M04SAU324I7G-10M04SAU324I7G,A
RST_PLD_CPU0_DRAM_GH_N   C621             1        Q_CAP_C0402-1UF,25V,10%,EMPTY,A
RST_PLD_CPU0_DRAM_GH_N   R705             1        Q_RES_0402LF-10K,1%,1/16W,EMPTA
RST_PLD_CPU0_DRAM_GH_N   R835             1        Q_RES_0402LF-0,5%,1/16W,CHIP,CA
RST_PLD_CPU0_DRAM_GH_N   U122             V13      10M04SAU324I7G-10M04SAU324I7G,A
RST_PLD_CPU1_DRAM_AB_N   C614             1        Q_CAP_C0402-1UF,25V,10%,EMPTY,A
RST_PLD_CPU1_DRAM_AB_N   R703             1        Q_RES_0402LF-10K,1%,1/16W,EMPTA
RST_PLD_CPU1_DRAM_AB_N   R816             1        Q_RES_0402LF-0,5%,1/16W,CHIP,CA
RST_PLD_CPU1_DRAM_AB_N   U122             V15      10M04SAU324I7G-10M04SAU324I7G,A
RST_PLD_CPU1_DRAM_CD_N   C615             1        Q_CAP_C0402-1UF,25V,10%,EMPTY,A
RST_PLD_CPU1_DRAM_CD_N   R701             1        Q_RES_0402LF-10K,1%,1/16W,EMPTA
RST_PLD_CPU1_DRAM_CD_N   R817             1        Q_RES_0402LF-0,5%,1/16W,CHIP,CA
RST_PLD_CPU1_DRAM_CD_N   U122             U16      10M04SAU324I7G-10M04SAU324I7G,A
RST_PLD_CPU1_DRAM_EF_N   C616             1        Q_CAP_C0402-1UF,25V,10%,EMPTY,A
RST_PLD_CPU1_DRAM_EF_N   R704             1        Q_RES_0402LF-10K,1%,1/16W,EMPTA
RST_PLD_CPU1_DRAM_EF_N   R818             1        Q_RES_0402LF-0,5%,1/16W,CHIP,CA
RST_PLD_CPU1_DRAM_EF_N   U122             V14      10M04SAU324I7G-10M04SAU324I7G,A
RST_PLD_CPU1_DRAM_GH_N   C613             1        Q_CAP_C0402-1UF,25V,10%,EMPTY,A
RST_PLD_CPU1_DRAM_GH_N   R702             1        Q_RES_0402LF-10K,1%,1/16W,EMPTA
RST_PLD_CPU1_DRAM_GH_N   R815             1        Q_RES_0402LF-0,5%,1/16W,CHIP,CA
RST_PLD_CPU1_DRAM_GH_N   U122             V16      10M04SAU324I7G-10M04SAU324I7G,A
RST_PLTRST_B_MUX_N       R1470            2        Q_RES_0402LF-33.2,1%,1/16W,CHIA
RST_PLTRST_B_MUX_N       U61              3        NC7SB3157_SMLF-NC7SB3157P6X,NCA
RST_PLTRST_B_N           J41              A51      SCONN168_623403212-SCONN168_6-A
RST_PLTRST_B_N           R1469            2        Q_RES_0402LF-33.2,1%,1/16W,CHIA
RST_PLTRST_N             R1205            1        Q_RES_0402LF-33,5%,1/16W,CHIP,A
RST_PLTRST_N             R1541            2        Q_RES_0402LF-100K,1%,1/16W,CHIA
RST_PLTRST_N             U4               AB4      EMMITSBURG_REV0P9-GFNOCPU04302A
RST_PLTRST_PLD_B_N       R1420            1        Q_RES_0402LF-2K,1%,1/16W,CHIP,A
RST_PLTRST_PLD_B_N       R1469            1        Q_RES_0402LF-33.2,1%,1/16W,CHIA
RST_PLTRST_PLD_B_N       R1470            1        Q_RES_0402LF-33.2,1%,1/16W,CHIA
RST_PLTRST_PLD_B_N       U122             H18      10M04SAU324I7G-10M04SAU324I7G,A
RST_PLTRST_PLD_N         R1205            2        Q_RES_0402LF-33,5%,1/16W,CHIP,A
RST_PLTRST_PLD_N         U122             K11      10M04SAU324I7G-10M04SAU324I7G,A
RST_RSMRST_PCH_N         R772             2        Q_RES_0402LF-1K,1%,1/16W,CHIP,A
RST_RSMRST_PCH_N         R1207            2        Q_RES_0402LF-33,5%,1/16W,CHIP,A
RST_RSMRST_PCH_N         R1695            2        Q_RES_0402LF-0,5%,1/16W,EMPTY,A
RST_RSMRST_PCH_N         U4               BD9      EMMITSBURG_REV0P9-GFNOCPU04302A
RST_RSMRST_PLD_R_N       R1207            1        Q_RES_0402LF-33,5%,1/16W,CHIP,A
RST_RSMRST_PLD_R_N       R1421            1        Q_RES_0402LF-2K,1%,1/16W,CHIP,A
RST_RSMRST_PLD_R_N       U122             K12      10M04SAU324I7G-10M04SAU324I7G,A
RST_RTCRST_N             C1177            1        Q_CAP_C0402-1UF,25V,10%,X6S,CHA
RST_RTCRST_N             Q34              D        MOSFET_N_GSD-NX7002AK,SMLF,IC,A
RST_RTCRST_N             R1340            2        Q_RES_0402LF-20K,5%,1/16W,CHIPA
RST_RTCRST_N             R1839            2        Q_RES_0402LF-0,5%,1/16W,EMPTY,A
RST_RTCRST_N             S2               7        SW8S_DHNF04FTVTR-SW8S_DHNF04FTA
RST_RTCRST_N             U4               BD7      EMMITSBURG_REV0P9-GFNOCPU04302A
RST_SGPIO_RESET_N        J41              B39      SCONN168_623403212-SCONN168_6-A
RST_SGPIO_RESET_N        R1811            1        Q_RES_0402LF-33.2,1%,1/16W,CHIA
RST_SGPIO_RESET_N_R      R1811            2        Q_RES_0402LF-33.2,1%,1/16W,CHIA
RST_SGPIO_RESET_N_R      U122             M18      10M04SAU324I7G-10M04SAU324I7G,A
RST_SMB_BUF_E1S_0_N      R2117            1        Q_RES_0402LF-0,5%,1/16W,CHIP,CA
RST_SMB_BUF_E1S_0_N      U136             6        SN74LVC2G07DCKR_SMLF-SN74LVC2GA
RST_SMB_BUF_E1S_1_N      R2118            1        Q_RES_0402LF-0,5%,1/16W,CHIP,CA
RST_SMB_BUF_E1S_1_N      U136             4        SN74LVC2G07DCKR_SMLF-SN74LVC2GA
RST_SMB_BUF_E1S_2_N      R2119            1        Q_RES_0402LF-0,5%,1/16W,CHIP,CA
RST_SMB_BUF_E1S_2_N      U137             6        SN74LVC2G07DCKR_SMLF-SN74LVC2GA
RST_SMB_BUF_E1S_3_N      R2120            1        Q_RES_0402LF-0,5%,1/16W,CHIP,CA
RST_SMB_BUF_E1S_3_N      U137             4        SN74LVC2G07DCKR_SMLF-SN74LVC2GA
RST_SMB_E1S_0_N          J90              A9       CONN56_ME2005602311011-CONN56_A
RST_SMB_E1S_0_N          R1673            2        Q_RES_0402LF-10K,1%,1/16W,EMPTA
RST_SMB_E1S_0_N          R2117            2        Q_RES_0402LF-0,5%,1/16W,CHIP,CA
RST_SMB_E1S_0_N          R2123            2        Q_RES_0402LF-4.7K,5%,1/16W,CHIA
RST_SMB_E1S_1_N          J91              A9       CONN56_ME2005602311011-CONN56_A
RST_SMB_E1S_1_N          R2005            2        Q_RES_0402LF-10K,1%,1/16W,EMPTA
RST_SMB_E1S_1_N          R2118            2        Q_RES_0402LF-0,5%,1/16W,CHIP,CA
RST_SMB_E1S_1_N          R2127            2        Q_RES_0402LF-4.7K,5%,1/16W,CHIA
RST_SMB_E1S_2_N          J92              A9       CONN56_ME2005602311011-CONN56_A
RST_SMB_E1S_2_N          R2006            2        Q_RES_0402LF-10K,1%,1/16W,EMPTA
RST_SMB_E1S_2_N          R2119            2        Q_RES_0402LF-0,5%,1/16W,CHIP,CA
RST_SMB_E1S_2_N          R2124            2        Q_RES_0402LF-4.7K,5%,1/16W,CHIA
RST_SMB_E1S_3_N          J93              A9       CONN56_ME2005602311011-CONN56_A
RST_SMB_E1S_3_N          R2007            2        Q_RES_0402LF-10K,1%,1/16W,EMPTA
RST_SMB_E1S_3_N          R2120            2        Q_RES_0402LF-0,5%,1/16W,CHIP,CA
RST_SMB_E1S_3_N          R2128            2        Q_RES_0402LF-4.7K,5%,1/16W,CHIA
RST_SMB_E1S_N            U136             1        SN74LVC2G07DCKR_SMLF-SN74LVC2GA
RST_SMB_E1S_N            U136             3        SN74LVC2G07DCKR_SMLF-SN74LVC2GA
RST_SMB_E1S_N            U137             1        SN74LVC2G07DCKR_SMLF-SN74LVC2GA
RST_SMB_E1S_N            U137             3        SN74LVC2G07DCKR_SMLF-SN74LVC2GA
RST_SMB_EDSFF1A_N        J62              A9       SCONN84_123318136-SCONN84_1-23A
RST_SMB_EDSFF1A_N        R1967            1        Q_RES_0402LF-4.7K,5%,1/16W,CHIA
RST_SMB_EDSFF1B_N        J87              A9       SCONN84_123318136-SCONN84_1-23A
RST_SMB_EDSFF1B_N        R1977            1        Q_RES_0402LF-4.7K,5%,1/16W,CHIA
RST_SMB_EDSFF2A_N        J33              A9       SCONN84_123318136-SCONN84_1-23A
RST_SMB_EDSFF2A_N        R1613            1        Q_RES_0402LF-4.7K,5%,1/16W,CHIA
RST_SMB_EDSFF2B_N        J34              A9       SCONN84_123318136-SCONN84_1-23A
RST_SMB_EDSFF2B_N        R1615            1        Q_RES_0402LF-4.7K,5%,1/16W,CHIA
RST_SMB_EDSFF4A_N        J88              A9       SCONN84_123318136-SCONN84_1-23A
RST_SMB_EDSFF4A_N        R1987            1        Q_RES_0402LF-4.7K,5%,1/16W,CHIA
RST_SRTCRST_N            C610             1        Q_CAP_C0402-1UF,25V,10%,X6S,CHA
RST_SRTCRST_N            Q35              D        MOSFET_N_GSD-NX7002AK,SMLF,IC,A
RST_SRTCRST_N            R1202            2        Q_RES_0402LF-20K,1%,1/16W,CHIPA
RST_SRTCRST_N            R1840            2        Q_RES_0402LF-0,5%,1/16W,EMPTY,A
RST_SRTCRST_N            U4               BF9      EMMITSBURG_REV0P9-GFNOCPU04302A
RTC_EXT_CAP              C609             1        Q_CAP_0402-0.1UF,25V,10%,X7R,CA
RTC_EXT_CAP              U4               BF5      EMMITSBURG_REV0P9-GFNOCPU04302A
SATA_P11_RX_C_DN         C636             1        Q_CAP_SATA6G_C0402-SATA6G_0.01A
SATA_P11_RX_C_DN         J54              5        CONN7_ABASAT054KA1-CONN7_ABA-SA
SATA_P11_RX_C_DP         C637             1        Q_CAP_SATA6G_C0402-SATA6G_0.01A
SATA_P11_RX_C_DP         J54              6        CONN7_ABASAT054KA1-CONN7_ABA-SA
SATA_P11_RX_DN           C636             2        Q_CAP_SATA6G_C0402-SATA6G_0.01A
SATA_P11_RX_DN           U4               L40      EMMITSBURG_REV0P9-GFNOCPU04302A
SATA_P11_RX_DP           C637             2        Q_CAP_SATA6G_C0402-SATA6G_0.01A
SATA_P11_RX_DP           U4               L42      EMMITSBURG_REV0P9-GFNOCPU04302A
SATA_P11_TX_C_DN         C635             1        Q_CAP_SATA6G_C0402-SATA6G_0.01A
SATA_P11_TX_C_DN         J54              3        CONN7_ABASAT054KA1-CONN7_ABA-SA
SATA_P11_TX_C_DP         C634             1        Q_CAP_SATA6G_C0402-SATA6G_0.01A
SATA_P11_TX_C_DP         J54              2        CONN7_ABASAT054KA1-CONN7_ABA-SA
SATA_P11_TX_DN           C635             2        Q_CAP_SATA6G_C0402-SATA6G_0.01A
SATA_P11_TX_DN           U4               T37      EMMITSBURG_REV0P9-GFNOCPU04302A
SATA_P11_TX_DP           C634             2        Q_CAP_SATA6G_C0402-SATA6G_0.01A
SATA_P11_TX_DP           U4               V37      EMMITSBURG_REV0P9-GFNOCPU04302A
SGPIO_BMC_CLK            R1752            2        Q_RES_0402LF-33.2,1%,1/16W,CHIA
SGPIO_BMC_CLK            U122             J12      10M04SAU324I7G-10M04SAU324I7G,A
SGPIO_BMC_DIN_R          R1753            2        Q_RES_0402LF-33.2,1%,1/16W,CHIA
SGPIO_BMC_DIN_R          U122             J11      10M04SAU324I7G-10M04SAU324I7G,A
SGPIO_BMC_DOUT           R1751            2        Q_RES_0402LF-33.2,1%,1/16W,CHIA
SGPIO_BMC_DOUT           U122             M17      10M04SAU324I7G-10M04SAU324I7G,A
SGPIO_BMC_LD_N           R1754            2        Q_RES_0402LF-33.2,1%,1/16W,CHIA
SGPIO_BMC_LD_N           U122             B18      10M04SAU324I7G-10M04SAU324I7G,A
SGPIO_CLK_0              J41              B30      SCONN168_623403212-SCONN168_6-A
SGPIO_CLK_0              R1752            1        Q_RES_0402LF-33.2,1%,1/16W,CHIA
SGPIO_CLK_1              J41              B35      SCONN168_623403212-SCONN168_6-A
SGPIO_CLK_1              R1756            1        Q_RES_0402LF-33.2,1%,1/16W,CHIA
SGPIO_DEBUG_PLD_CLK      R1756            2        Q_RES_0402LF-33.2,1%,1/16W,CHIA
SGPIO_DEBUG_PLD_CLK      U122             M11      10M04SAU324I7G-10M04SAU324I7G,A
SGPIO_DEBUG_PLD_DIN      R1757            2        Q_RES_0402LF-33.2,1%,1/16W,CHIA
SGPIO_DEBUG_PLD_DIN      U122             M15      10M04SAU324I7G-10M04SAU324I7G,A
SGPIO_DEBUG_PLD_DOUT     R1755            2        Q_RES_0402LF-33.2,1%,1/16W,CHIA
SGPIO_DEBUG_PLD_DOUT     U122             M12      10M04SAU324I7G-10M04SAU324I7G,A
SGPIO_DEBUG_PLD_LD_N     R1758            2        Q_RES_0402LF-33.2,1%,1/16W,CHIA
SGPIO_DEBUG_PLD_LD_N     U122             M16      10M04SAU324I7G-10M04SAU324I7G,A
SGPIO_DI_0               J41              B31      SCONN168_623403212-SCONN168_6-A
SGPIO_DI_0               R1753            1        Q_RES_0402LF-33.2,1%,1/16W,CHIA
SGPIO_DI_1               J41              B36      SCONN168_623403212-SCONN168_6-A
SGPIO_DI_1               R1757            1        Q_RES_0402LF-33.2,1%,1/16W,CHIA
SGPIO_DO_0               J41              B29      SCONN168_623403212-SCONN168_6-A
SGPIO_DO_0               R1751            1        Q_RES_0402LF-33.2,1%,1/16W,CHIA
SGPIO_DO_1               J41              B34      SCONN168_623403212-SCONN168_6-A
SGPIO_DO_1               R1755            1        Q_RES_0402LF-33.2,1%,1/16W,CHIA
SGPIO_LD_0               J41              B32      SCONN168_623403212-SCONN168_6-A
SGPIO_LD_0               R1754            1        Q_RES_0402LF-33.2,1%,1/16W,CHIA
SGPIO_LD_1               J41              B37      SCONN168_623403212-SCONN168_6-A
SGPIO_LD_1               R1758            1        Q_RES_0402LF-33.2,1%,1/16W,CHIA
SGPIO_OCP_SFF_CLK_N      J37              OCP_B6   SCONN168_623403212-SCONN168_6-A
SGPIO_OCP_SFF_CLK_N      R423             1        Q_RES_0402LF-0,5%,1/16W,EMPTY,A
SGPIO_OCP_SFF_DATAIN_N   J37              OCP_B4   SCONN168_623403212-SCONN168_6-A
SGPIO_OCP_SFF_DATAIN_N   R421             1        Q_RES_0402LF-4.7K,5%,1/16W,CHIA
SGPIO_OCP_SFF_DATAOUT_N  J37              OCP_B5   SCONN168_623403212-SCONN168_6-A
SGPIO_OCP_SFF_DATAOUT_N  R422             1        Q_RES_0402LF-1K,1%,1/16W,EMPTYA
SGPIO_OCP_SFF_LD_N       J37              OCP_B3   SCONN168_623403212-SCONN168_6-A
SGPIO_OCP_SFF_LD_N       R420             1        Q_RES_0402LF-1K,1%,1/16W,EMPTYA
SH_P1V05_PCH_AUX_N       PC1221           2        Q_CAP_0402-0.1UF,25V,10%,X7R,CA
SH_P1V05_PCH_AUX_N       PJ63             1        Q_SHORT_SM-EMPTY,SHORT6
SH_P1V05_PCH_AUX_N       PR187            2        Q_RES_0402LF-10K,1%,1/16W,CHIPA
SH_P1V05_PCH_AUX_N       PU73             6        MPQ8633BGLEC838Z-MPQ8633BGLE-CA
SH_P1V05_PCH_AUX_P       PC1223           2        Q_CAP_C0402-470PF,50V,5%,NPO,CA
SH_P1V05_PCH_AUX_P       PJ62             1        Q_SHORT_SM-EMPTY,SHORT6
SH_P1V05_PCH_AUX_P       PR1328           2        Q_RES_0402LF-7.32K,1%,1/16W,CHA
SH_PVCCD_HV_CPU0         PJ54             2        Q_SHORT_SM-EMPTY,SHORT6
SH_PVCCD_HV_CPU0         PR371            1        Q_RES_0402LF-0,5%,1/16W,CHIP,CA
SH_PVCCD_HV_CPU0_R       PC627            1        Q_CAP_0402-3300PF,50V,10%,X7R,A
SH_PVCCD_HV_CPU0_R       PR371            2        Q_RES_0402LF-0,5%,1/16W,CHIP,CA
SH_PVCCD_HV_CPU0_R       PU35             21       ISL69260IRAZT-ISL69260IRAZ-T,SA
SH_PVCCD_HV_CPU1         PJ48             2        Q_SHORT_SM-EMPTY,SHORT6
SH_PVCCD_HV_CPU1         PR216            1        Q_RES_0402LF-0,5%,1/16W,CHIP,CA
SH_PVCCD_HV_CPU1_R       PC389            1        Q_CAP_0402-3300PF,50V,10%,X7R,A
SH_PVCCD_HV_CPU1_R       PR216            2        Q_RES_0402LF-0,5%,1/16W,CHIP,CA
SH_PVCCD_HV_CPU1_R       PU18             21       ISL69260IRAZT-ISL69260IRAZ-T,SA
SH_PVCCFA_EHV_CPU0       PJ46             2        Q_SHORT_SM-EMPTY,SHORT6
SH_PVCCFA_EHV_CPU0       PR121            1        Q_RES_0402LF-0,5%,1/16W,CHIP,CA
SH_PVCCFA_EHV_CPU0_R     PC216            1        Q_CAP_0402-3300PF,50V,10%,X7R,A
SH_PVCCFA_EHV_CPU0_R     PR121            2        Q_RES_0402LF-0,5%,1/16W,CHIP,CA
SH_PVCCFA_EHV_CPU0_R     PU5              32       ISL69260IRAZT-ISL69260IRAZ-T,SA
SH_PVCCFA_EHV_CPU1       PJ51             2        Q_SHORT_SM-EMPTY,SHORT6
SH_PVCCFA_EHV_CPU1       PR274            1        Q_RES_0402LF-0,5%,1/16W,CHIP,CA
SH_PVCCFA_EHV_CPU1_R     PC469            1        Q_CAP_0402-3300PF,50V,10%,X7R,A
SH_PVCCFA_EHV_CPU1_R     PR274            2        Q_RES_0402LF-0,5%,1/16W,CHIP,CA
SH_PVCCFA_EHV_CPU1_R     PU22             32       ISL69260IRAZT-ISL69260IRAZ-T,SA
SH_PVCCFA_EHV_FIVRA_CPU0 PJ53             2        Q_SHORT_SM-EMPTY,SHORT6
SH_PVCCFA_EHV_FIVRA_CPU0 PR345            1        Q_RES_0402LF-0,5%,1/16W,CHIP,CA
SH_PVCCFA_EHV_FIVRA_CPU0_R PC594            1        Q_CAP_0402-3300PF,50V,10%,X7R,A
SH_PVCCFA_EHV_FIVRA_CPU0_R PR345            2        Q_RES_0402LF-0,5%,1/16W,CHIP,CA
SH_PVCCFA_EHV_FIVRA_CPU0_R PU14             40       RAA229126GNPHA0-RAA229126GNP#HA
SH_PVCCFA_EHV_FIVRA_CPU1 PJ49             2        Q_SHORT_SM-EMPTY,SHORT6
SH_PVCCFA_EHV_FIVRA_CPU1 PR242            1        Q_RES_0402LF-0,5%,1/16W,CHIP,CA
SH_PVCCFA_EHV_FIVRA_CPU1_R PC422            1        Q_CAP_0402-3300PF,50V,10%,X7R,A
SH_PVCCFA_EHV_FIVRA_CPU1_R PR242            2        Q_RES_0402LF-0,5%,1/16W,CHIP,CA
SH_PVCCFA_EHV_FIVRA_CPU1_R PU29             40       RAA229126GNPHA0-RAA229126GNP#HA
SH_PVCCINFAON_CPU0       PJ45             2        Q_SHORT_SM-EMPTY,SHORT6
SH_PVCCINFAON_CPU0       PR120            1        Q_RES_0402LF-0,5%,1/16W,CHIP,CA
SH_PVCCINFAON_CPU0_R     PC215            1        Q_CAP_0402-3300PF,50V,10%,X7R,A
SH_PVCCINFAON_CPU0_R     PR120            2        Q_RES_0402LF-0,5%,1/16W,CHIP,CA
SH_PVCCINFAON_CPU0_R     PU5              21       ISL69260IRAZT-ISL69260IRAZ-T,SA
SH_PVCCINFAON_CPU1       PJ50             2        Q_SHORT_SM-EMPTY,SHORT6
SH_PVCCINFAON_CPU1       PR273            1        Q_RES_0402LF-0,5%,1/16W,CHIP,CA
SH_PVCCINFAON_CPU1_R     PC468            1        Q_CAP_0402-3300PF,50V,10%,X7R,A
SH_PVCCINFAON_CPU1_R     PR273            2        Q_RES_0402LF-0,5%,1/16W,CHIP,CA
SH_PVCCINFAON_CPU1_R     PU22             21       ISL69260IRAZT-ISL69260IRAZ-T,SA
SH_PVCCIN_CPU0           PJ47             2        Q_SHORT_SM-EMPTY,SHORT6
SH_PVCCIN_CPU0           PR170            1        Q_RES_0402LF-0,5%,1/16W,CHIP,CA
SH_PVCCIN_CPU0_R         PC331            1        Q_CAP_0402-3300PF,50V,10%,X7R,A
SH_PVCCIN_CPU0_R         PR170            2        Q_RES_0402LF-0,5%,1/16W,CHIP,CA
SH_PVCCIN_CPU0_R         PU14             25       RAA229126GNPHA0-RAA229126GNP#HA
SH_PVCCIN_CPU1           PJ52             2        Q_SHORT_SM-EMPTY,SHORT6
SH_PVCCIN_CPU1           PR317            1        Q_RES_0402LF-0,5%,1/16W,CHIP,CA
SH_PVCCIN_CPU1_R         PC549            1        Q_CAP_0402-3300PF,50V,10%,X7R,A
SH_PVCCIN_CPU1_R         PR317            2        Q_RES_0402LF-0,5%,1/16W,CHIP,CA
SH_PVCCIN_CPU1_R         PU29             25       RAA229126GNPHA0-RAA229126GNP#HA
SH_PVPP_HBM_CPU0_N       PC1251           2        Q_CAP_0402-0.1UF,25V,10%,EMPTYA
SH_PVPP_HBM_CPU0_N       PJ65             1        Q_SHORT_SM-EMPTY,SHORT6
SH_PVPP_HBM_CPU0_N       PR1310           2        Q_RES_0402LF-18.2K,0.1%,1/16W,A
SH_PVPP_HBM_CPU0_N       PU79             6        MPQ8633AGLEC807Z-MPQ8633AGLE-CA
SH_PVPP_HBM_CPU0_N       U73              S        MOSFET_N_SMLF-BSS138K,BSS138K,B
SH_PVPP_HBM_CPU0_P       PC1253           2        Q_CAP_0402-100PF,50V,5%,EMPTY,A
SH_PVPP_HBM_CPU0_P       PJ64             1        Q_SHORT_SM-EMPTY,SHORT6
SH_PVPP_HBM_CPU0_P       PR1337           2        Q_RES_0402LF-36K,1%,1/16W,EMPTA
SH_PVPP_HBM_CPU1_N       PC1264           2        Q_CAP_0402-0.1UF,25V,10%,X7R,CA
SH_PVPP_HBM_CPU1_N       PJ67             1        Q_SHORT_SM-EMPTY,SHORT6
SH_PVPP_HBM_CPU1_N       PR1314           2        Q_RES_0402LF-18.2K,0.1%,1/16W,B
SH_PVPP_HBM_CPU1_N       PU80             6        MPQ8633AGLEC807Z-MPQ8633AGLE-CB
SH_PVPP_HBM_CPU1_N       U74              S        MOSFET_N_SMLF-BSS138K,BSS138K,A
SH_PVPP_HBM_CPU1_P       PC1266           2        Q_CAP_0402-100PF,50V,5%,NPO,CHA
SH_PVPP_HBM_CPU1_P       PJ66             1        Q_SHORT_SM-EMPTY,SHORT6
SH_PVPP_HBM_CPU1_P       PR1340           2        Q_RES_0402LF-36K,1%,1/16W,CHIPA
SMB_CLK_PVCCD_HV_CPU0    PR367            2        Q_RES_0402LF-0,5%,1/16W,CHIP,CA
SMB_CLK_PVCCD_HV_CPU0    PU35             10       ISL69260IRAZT-ISL69260IRAZ-T,SA
SMB_CLK_PVCCD_HV_CPU1    PR212            2        Q_RES_0402LF-0,5%,1/16W,CHIP,CA
SMB_CLK_PVCCD_HV_CPU1    PU18             10       ISL69260IRAZT-ISL69260IRAZ-T,SA
SMB_CLK_PVCCINFAON_CPU0  PR115            2        Q_RES_0402LF-0,5%,1/16W,CHIP,CA
SMB_CLK_PVCCINFAON_CPU0  PU5              10       ISL69260IRAZT-ISL69260IRAZ-T,SA
SMB_CLK_PVCCINFAON_CPU1  PR268            2        Q_RES_0402LF-0,5%,1/16W,CHIP,CA
SMB_CLK_PVCCINFAON_CPU1  PU22             10       ISL69260IRAZT-ISL69260IRAZ-T,SA
SMB_CLK_PVCCIN_CPU0      PR167            2        Q_RES_0402LF-0,5%,1/16W,CHIP,CA
SMB_CLK_PVCCIN_CPU0      PU14             14       RAA229126GNPHA0-RAA229126GNP#HA
SMB_CLK_PVCCIN_CPU1      PR314            2        Q_RES_0402LF-0,5%,1/16W,CHIP,CA
SMB_CLK_PVCCIN_CPU1      PU29             14       RAA229126GNPHA0-RAA229126GNP#HA
SMB_CPU0_PIROM_3V3AUX_SCL_R R1932            2        Q_RES_0402LF-33.2,1%,1/16W,CHIA
SMB_CPU0_PIROM_3V3AUX_SCL_R U2               CU70     SOCKET4677_AZIFS054P001C01-SOCA
SMB_CPU0_PIROM_3V3AUX_SDA_R R1933            2        Q_RES_0402LF-33.2,1%,1/16W,CHIA
SMB_CPU0_PIROM_3V3AUX_SDA_R U2               CM71     SOCKET4677_AZIFS054P001C01-SOCA
SMB_CPU1_PIROM_3V3AUX_SCL_R R1934            2        Q_RES_0402LF-33.2,1%,1/16W,CHIA
SMB_CPU1_PIROM_3V3AUX_SCL_R U1               CU70     SOCKET4677_AZIFS054P001C01-SOCA
SMB_CPU1_PIROM_3V3AUX_SDA_R R1935            2        Q_RES_0402LF-33.2,1%,1/16W,CHIA
SMB_CPU1_PIROM_3V3AUX_SDA_R U1               CM71     SOCKET4677_AZIFS054P001C01-SOCA
SMB_CPU_PIROM_3V3AUX_SCL J41              A21      SCONN168_623403212-SCONN168_6-A
SMB_CPU_PIROM_3V3AUX_SCL R606             1        Q_RES_0402LF-2.2K ,5%,1/16W,CHA
SMB_CPU_PIROM_3V3AUX_SCL R1932            1        Q_RES_0402LF-33.2,1%,1/16W,CHIA
SMB_CPU_PIROM_3V3AUX_SCL R1934            1        Q_RES_0402LF-33.2,1%,1/16W,CHIA
SMB_CPU_PIROM_3V3AUX_SDA J41              A22      SCONN168_623403212-SCONN168_6-A
SMB_CPU_PIROM_3V3AUX_SDA R649             1        Q_RES_0402LF-2.2K ,5%,1/16W,CHA
SMB_CPU_PIROM_3V3AUX_SDA R1933            1        Q_RES_0402LF-33.2,1%,1/16W,CHIA
SMB_CPU_PIROM_3V3AUX_SDA R1935            1        Q_RES_0402LF-33.2,1%,1/16W,CHIA
SMB_DIO_PVCCD_HV_CPU0    PR368            2        Q_RES_0402LF-0,5%,1/16W,CHIP,CA
SMB_DIO_PVCCD_HV_CPU0    PU35             9        ISL69260IRAZT-ISL69260IRAZ-T,SA
SMB_DIO_PVCCD_HV_CPU1    PR213            2        Q_RES_0402LF-0,5%,1/16W,CHIP,CA
SMB_DIO_PVCCD_HV_CPU1    PU18             9        ISL69260IRAZT-ISL69260IRAZ-T,SA
SMB_DIO_PVCCINFAON_CPU0  PR116            2        Q_RES_0402LF-0,5%,1/16W,CHIP,CA
SMB_DIO_PVCCINFAON_CPU0  PU5              9        ISL69260IRAZT-ISL69260IRAZ-T,SA
SMB_DIO_PVCCINFAON_CPU1  PR269            2        Q_RES_0402LF-0,5%,1/16W,CHIP,CA
SMB_DIO_PVCCINFAON_CPU1  PU22             9        ISL69260IRAZT-ISL69260IRAZ-T,SA
SMB_DIO_PVCCIN_CPU0      PR168            2        Q_RES_0402LF-0,5%,1/16W,CHIP,CA
SMB_DIO_PVCCIN_CPU0      PU14             13       RAA229126GNPHA0-RAA229126GNP#HA
SMB_DIO_PVCCIN_CPU1      PR315            2        Q_RES_0402LF-0,5%,1/16W,CHIP,CA
SMB_DIO_PVCCIN_CPU1      PU29             13       RAA229126GNPHA0-RAA229126GNP#HA
SMB_E1S_0_3V3AUX_SCL     J90              A7       CONN56_ME2005602311011-CONN56_A
SMB_E1S_0_3V3AUX_SCL     R1057            1        Q_RES_0402LF-33.2,1%,1/16W,CHIA
SMB_E1S_0_3V3AUX_SCL     R1065            2        Q_RES_0402LF-2.2K ,5%,1/16W,EMA
SMB_E1S_0_3V3AUX_SDA     J90              A8       CONN56_ME2005602311011-CONN56_A
SMB_E1S_0_3V3AUX_SDA     R1058            1        Q_RES_0402LF-0,5%,1/16W,CHIP,CA
SMB_E1S_0_3V3AUX_SDA     R1066            2        Q_RES_0402LF-2.2K ,5%,1/16W,EMA
SMB_E1S_1_3V3AUX_SCL     J91              A7       CONN56_ME2005602311011-CONN56_A
SMB_E1S_1_3V3AUX_SCL     R1059            1        Q_RES_0402LF-0,5%,1/16W,CHIP,CA
SMB_E1S_1_3V3AUX_SCL     R1067            2        Q_RES_0402LF-2.2K ,5%,1/16W,EMA
SMB_E1S_1_3V3AUX_SDA     J91              A8       CONN56_ME2005602311011-CONN56_A
SMB_E1S_1_3V3AUX_SDA     R1060            1        Q_RES_0402LF-0,5%,1/16W,CHIP,CA
SMB_E1S_1_3V3AUX_SDA     R1068            2        Q_RES_0402LF-2.2K ,5%,1/16W,EMA
SMB_E1S_2_3V3AUX_SCL     J92              A7       CONN56_ME2005602311011-CONN56_A
SMB_E1S_2_3V3AUX_SCL     R1061            2        Q_RES_0402LF-0,5%,1/16W,CHIP,CA
SMB_E1S_2_3V3AUX_SCL     R1069            2        Q_RES_0402LF-2.2K ,5%,1/16W,EMA
SMB_E1S_2_3V3AUX_SDA     J92              A8       CONN56_ME2005602311011-CONN56_A
SMB_E1S_2_3V3AUX_SDA     R1062            2        Q_RES_0402LF-0,5%,1/16W,CHIP,CA
SMB_E1S_2_3V3AUX_SDA     R1070            2        Q_RES_0402LF-2.2K ,5%,1/16W,EMA
SMB_E1S_3_3V3AUX_SCL     J93              A7       CONN56_ME2005602311011-CONN56_A
SMB_E1S_3_3V3AUX_SCL     R1063            2        Q_RES_0402LF-0,5%,1/16W,CHIP,CA
SMB_E1S_3_3V3AUX_SCL     R1071            2        Q_RES_0402LF-2.2K ,5%,1/16W,EMA
SMB_E1S_3_3V3AUX_SDA     J93              A8       CONN56_ME2005602311011-CONN56_A
SMB_E1S_3_3V3AUX_SDA     R1064            2        Q_RES_0402LF-0,5%,1/16W,CHIP,CA
SMB_E1S_3_3V3AUX_SDA     R1072            2        Q_RES_0402LF-2.2K ,5%,1/16W,EMA
SMB_EDSFF1A_3V3AUX_SCL_R J62              A7       SCONN84_123318136-SCONN84_1-23A
SMB_EDSFF1A_3V3AUX_SCL_R R787             2        Q_RES_0402LF-0,5%,1/16W,CHIP,CA
SMB_EDSFF1A_3V3AUX_SCL_R R791             2        Q_RES_0402LF-2.2K ,5%,1/16W,CHA
SMB_EDSFF1A_3V3AUX_SCL_R1 R787             1        Q_RES_0402LF-0,5%,1/16W,CHIP,CA
SMB_EDSFF1A_3V3AUX_SCL_R1 U24              5        PCA9548APW-PCA9548APW,SMLF,IC,A
SMB_EDSFF1A_3V3AUX_SDA_R J62              A8       SCONN84_123318136-SCONN84_1-23A
SMB_EDSFF1A_3V3AUX_SDA_R R788             2        Q_RES_0402LF-0,5%,1/16W,CHIP,CA
SMB_EDSFF1A_3V3AUX_SDA_R R792             2        Q_RES_0402LF-2.2K ,5%,1/16W,CHA
SMB_EDSFF1A_3V3AUX_SDA_R1 R788             1        Q_RES_0402LF-0,5%,1/16W,CHIP,CA
SMB_EDSFF1A_3V3AUX_SDA_R1 U24              4        PCA9548APW-PCA9548APW,SMLF,IC,A
SMB_EDSFF1B_3V3AUX_SCL_R J87              A7       SCONN84_123318136-SCONN84_1-23A
SMB_EDSFF1B_3V3AUX_SCL_R R2051            2        Q_RES_0402LF-2.2K ,5%,1/16W,CHA
SMB_EDSFF1B_3V3AUX_SCL_R R2059            2        Q_RES_0402LF-0,5%,1/16W,CHIP,CA
SMB_EDSFF1B_3V3AUX_SCL_R1 R2059            1        Q_RES_0402LF-0,5%,1/16W,CHIP,CA
SMB_EDSFF1B_3V3AUX_SCL_R1 U24              7        PCA9548APW-PCA9548APW,SMLF,IC,A
SMB_EDSFF1B_3V3AUX_SDA_R J87              A8       SCONN84_123318136-SCONN84_1-23A
SMB_EDSFF1B_3V3AUX_SDA_R R2052            2        Q_RES_0402LF-2.2K ,5%,1/16W,CHA
SMB_EDSFF1B_3V3AUX_SDA_R R2060            2        Q_RES_0402LF-0,5%,1/16W,CHIP,CA
SMB_EDSFF1B_3V3AUX_SDA_R1 R2060            1        Q_RES_0402LF-0,5%,1/16W,CHIP,CA
SMB_EDSFF1B_3V3AUX_SDA_R1 U24              6        PCA9548APW-PCA9548APW,SMLF,IC,A
SMB_EDSFF2A_3V3AUX_SCL_R J33              A7       SCONN84_123318136-SCONN84_1-23A
SMB_EDSFF2A_3V3AUX_SCL_R R789             2        Q_RES_0402LF-0,5%,1/16W,CHIP,CA
SMB_EDSFF2A_3V3AUX_SCL_R R793             2        Q_RES_0402LF-2.2K ,5%,1/16W,CHA
SMB_EDSFF2A_3V3AUX_SCL_R1 R789             1        Q_RES_0402LF-0,5%,1/16W,CHIP,CA
SMB_EDSFF2A_3V3AUX_SCL_R1 U24              9        PCA9548APW-PCA9548APW,SMLF,IC,A
SMB_EDSFF2A_3V3AUX_SDA_R J33              A8       SCONN84_123318136-SCONN84_1-23A
SMB_EDSFF2A_3V3AUX_SDA_R R790             2        Q_RES_0402LF-0,5%,1/16W,CHIP,CA
SMB_EDSFF2A_3V3AUX_SDA_R R794             2        Q_RES_0402LF-2.2K ,5%,1/16W,CHA
SMB_EDSFF2A_3V3AUX_SDA_R1 R790             1        Q_RES_0402LF-0,5%,1/16W,CHIP,CA
SMB_EDSFF2A_3V3AUX_SDA_R1 U24              8        PCA9548APW-PCA9548APW,SMLF,IC,A
SMB_EDSFF2B_3V3AUX_SCL_R J34              A7       SCONN84_123318136-SCONN84_1-23A
SMB_EDSFF2B_3V3AUX_SCL_R R2053            2        Q_RES_0402LF-2.2K ,5%,1/16W,CHA
SMB_EDSFF2B_3V3AUX_SCL_R R2061            2        Q_RES_0402LF-0,5%,1/16W,CHIP,CA
SMB_EDSFF2B_3V3AUX_SCL_R1 R2061            1        Q_RES_0402LF-0,5%,1/16W,CHIP,CA
SMB_EDSFF2B_3V3AUX_SCL_R1 U24              11       PCA9548APW-PCA9548APW,SMLF,IC,A
SMB_EDSFF2B_3V3AUX_SDA_R J34              A8       SCONN84_123318136-SCONN84_1-23A
SMB_EDSFF2B_3V3AUX_SDA_R R2054            2        Q_RES_0402LF-2.2K ,5%,1/16W,CHA
SMB_EDSFF2B_3V3AUX_SDA_R R2062            2        Q_RES_0402LF-0,5%,1/16W,CHIP,CA
SMB_EDSFF2B_3V3AUX_SDA_R1 R2062            1        Q_RES_0402LF-0,5%,1/16W,CHIP,CA
SMB_EDSFF2B_3V3AUX_SDA_R1 U24              10       PCA9548APW-PCA9548APW,SMLF,IC,A
SMB_EDSFF3_3V3AUX_SCL_R  J35              A11      SCONN140_G64V3431BHR-SCONN140_B
SMB_EDSFF3_3V3AUX_SCL_R  R795             2        Q_RES_0402LF-2.2K ,5%,1/16W,CHA
SMB_EDSFF3_3V3AUX_SCL_R  R801             2        Q_RES_0402LF-0,5%,1/16W,CHIP,CA
SMB_EDSFF3_3V3AUX_SCL_R1 R801             1        Q_RES_0402LF-0,5%,1/16W,CHIP,CA
SMB_EDSFF3_3V3AUX_SCL_R1 U24              14       PCA9548APW-PCA9548APW,SMLF,IC,A
SMB_EDSFF3_3V3AUX_SDA_R  J35              A12      SCONN140_G64V3431BHR-SCONN140_B
SMB_EDSFF3_3V3AUX_SDA_R  R796             2        Q_RES_0402LF-2.2K ,5%,1/16W,CHA
SMB_EDSFF3_3V3AUX_SDA_R  R802             2        Q_RES_0402LF-0,5%,1/16W,CHIP,CA
SMB_EDSFF3_3V3AUX_SDA_R1 R802             1        Q_RES_0402LF-0,5%,1/16W,CHIP,CA
SMB_EDSFF3_3V3AUX_SDA_R1 U24              13       PCA9548APW-PCA9548APW,SMLF,IC,A
SMB_EDSFF4A_3V3AUX_SCL_R J88              A7       SCONN84_123318136-SCONN84_1-23A
SMB_EDSFF4A_3V3AUX_SCL_R R797             2        Q_RES_0402LF-2.2K ,5%,1/16W,CHA
SMB_EDSFF4A_3V3AUX_SCL_R R799             2        Q_RES_0402LF-0,5%,1/16W,CHIP,CA
SMB_EDSFF4A_3V3AUX_SCL_R1 R799             1        Q_RES_0402LF-0,5%,1/16W,CHIP,CA
SMB_EDSFF4A_3V3AUX_SCL_R1 U24              16       PCA9548APW-PCA9548APW,SMLF,IC,A
SMB_EDSFF4A_3V3AUX_SDA_R J88              A8       SCONN84_123318136-SCONN84_1-23A
SMB_EDSFF4A_3V3AUX_SDA_R R798             2        Q_RES_0402LF-2.2K ,5%,1/16W,CHA
SMB_EDSFF4A_3V3AUX_SDA_R R800             2        Q_RES_0402LF-0,5%,1/16W,CHIP,CA
SMB_EDSFF4A_3V3AUX_SDA_R1 R800             1        Q_RES_0402LF-0,5%,1/16W,CHIP,CA
SMB_EDSFF4A_3V3AUX_SDA_R1 U24              15       PCA9548APW-PCA9548APW,SMLF,IC,A
SMB_EDSFF4B_3V3AUX_SCL_R R2055            2        Q_RES_0402LF-2.2K ,5%,1/16W,CHA
SMB_EDSFF4B_3V3AUX_SCL_R R2063            2        Q_RES_0402LF-0,5%,1/16W,CHIP,CA
SMB_EDSFF4B_3V3AUX_SCL_R1 R2063            1        Q_RES_0402LF-0,5%,1/16W,CHIP,CA
SMB_EDSFF4B_3V3AUX_SCL_R1 U24              18       PCA9548APW-PCA9548APW,SMLF,IC,A
SMB_EDSFF4B_3V3AUX_SDA_R R2056            2        Q_RES_0402LF-2.2K ,5%,1/16W,CHA
SMB_EDSFF4B_3V3AUX_SDA_R R2064            2        Q_RES_0402LF-0,5%,1/16W,CHIP,CA
SMB_EDSFF4B_3V3AUX_SDA_R1 R2064            1        Q_RES_0402LF-0,5%,1/16W,CHIP,CA
SMB_EDSFF4B_3V3AUX_SDA_R1 U24              17       PCA9548APW-PCA9548APW,SMLF,IC,A
SMB_EDSFF_3V3AUX_SCL_R8  R2065            1        Q_RES_0402LF-0,5%,1/16W,CHIP,CA
SMB_EDSFF_3V3AUX_SCL_R8  U24              20       PCA9548APW-PCA9548APW,SMLF,IC,A
SMB_EDSFF_3V3AUX_SDA_R8  R2066            1        Q_RES_0402LF-0,5%,1/16W,CHIP,CA
SMB_EDSFF_3V3AUX_SDA_R8  U24              19       PCA9548APW-PCA9548APW,SMLF,IC,A
SMB_FAN_3V3AUX_SCL       J41              A29      SCONN168_623403212-SCONN168_6-A
SMB_FAN_3V3AUX_SCL       R592             1        Q_RES_0402LF-2.2K ,5%,1/16W,CHA
SMB_FAN_3V3AUX_SCL       R723             2        Q_RES_0402LF-33,5%,1/16W,CHIP,A
SMB_FAN_3V3AUX_SCL_R1    J44              14       CONN24_52SH90245BRD-CONN24_52SA
SMB_FAN_3V3AUX_SCL_R1    R723             1        Q_RES_0402LF-33,5%,1/16W,CHIP,A
SMB_FAN_3V3AUX_SDA       J41              A30      SCONN168_623403212-SCONN168_6-A
SMB_FAN_3V3AUX_SDA       R601             1        Q_RES_0402LF-2.2K ,5%,1/16W,CHA
SMB_FAN_3V3AUX_SDA       R724             2        Q_RES_0402LF-33,5%,1/16W,CHIP,A
SMB_FAN_3V3AUX_SDA_R1    J44              18       CONN24_52SH90245BRD-CONN24_52SA
SMB_FAN_3V3AUX_SDA_R1    R724             1        Q_RES_0402LF-33,5%,1/16W,CHIP,A
SMB_FRU_3V3AUX_SCL_R     R475             2        Q_RES_0402LF-33.2,1%,1/16W,CHIA
SMB_FRU_3V3AUX_SCL_R     U64              6        M24128BWDW6TP-M24128-BWDW6TP,SA
SMB_FRU_3V3AUX_SDA_R     R709             2        Q_RES_0402LF-33.2,1%,1/16W,CHIA
SMB_FRU_3V3AUX_SDA_R     U64              5        M24128BWDW6TP-M24128-BWDW6TP,SA
SMB_HOST_3V3AUX_SCL      J41              A3       SCONN168_623403212-SCONN168_6-A
SMB_HOST_3V3AUX_SCL      J42              48       SCONN60_QSH03001LDAKTR-SCONN60A
SMB_HOST_3V3AUX_SCL      R577             1        Q_RES_0402LF-33,5%,1/16W,CHIP,A
SMB_HOST_3V3AUX_SCL      R579             1        Q_RES_0402LF-33,5%,1/16W,CHIP,A
SMB_HOST_3V3AUX_SCL      R1319            1        Q_RES_0402LF-2K,1%,1/16W,CHIP,A
SMB_HOST_3V3AUX_SCL_R    R107             1        Q_RES_0402LF-0,5%,1/16W,CHIP,CA
SMB_HOST_3V3AUX_SCL_R    R577             2        Q_RES_0402LF-33,5%,1/16W,CHIP,A
SMB_HOST_3V3AUX_SCL_R    R1525            1        Q_RES_0402LF-0,5%,1/16W,CHIP,CA
SMB_HOST_3V3AUX_SDA      J41              A4       SCONN168_623403212-SCONN168_6-A
SMB_HOST_3V3AUX_SDA      J42              50       SCONN60_QSH03001LDAKTR-SCONN60A
SMB_HOST_3V3AUX_SDA      R578             1        Q_RES_0402LF-33,5%,1/16W,CHIP,A
SMB_HOST_3V3AUX_SDA      R580             1        Q_RES_0402LF-33,5%,1/16W,CHIP,A
SMB_HOST_3V3AUX_SDA      R1321            1        Q_RES_0402LF-2K,1%,1/16W,CHIP,A
SMB_HOST_3V3AUX_SDA_R    R108             1        Q_RES_0402LF-33.2,1%,1/16W,CHIA
SMB_HOST_3V3AUX_SDA_R    R578             2        Q_RES_0402LF-33,5%,1/16W,CHIP,A
SMB_HOST_3V3AUX_SDA_R    R1526            1        Q_RES_0402LF-33.2,1%,1/16W,CHIA
SMB_HOST_BMC_3V3AUX_SCL  R579             2        Q_RES_0402LF-33,5%,1/16W,CHIP,A
SMB_HOST_BMC_3V3AUX_SCL  R633             2        Q_RES_0402LF-0,5%,1/16W,EMPTY,A
SMB_HOST_BMC_3V3AUX_SCL  U4               AF2      EMMITSBURG_REV0P9-GFNOCPU04302A
SMB_HOST_BMC_3V3AUX_SDA  R580             2        Q_RES_0402LF-33,5%,1/16W,CHIP,A
SMB_HOST_BMC_3V3AUX_SDA  R632             2        Q_RES_0402LF-0,5%,1/16W,EMPTY,A
SMB_HOST_BMC_3V3AUX_SDA  U4               AE1      EMMITSBURG_REV0P9-GFNOCPU04302A
SMB_HOST_CLK_3V3AUX_SCL  R1525            2        Q_RES_0402LF-0,5%,1/16W,CHIP,CA
SMB_HOST_CLK_3V3AUX_SCL  U13              A10      9SQ440NQQI8-9SQ440NQQI8,SMLF,IA
SMB_HOST_CLK_3V3AUX_SDA  R1526            2        Q_RES_0402LF-33.2,1%,1/16W,CHIA
SMB_HOST_CLK_3V3AUX_SDA  U13              B8       9SQ440NQQI8-9SQ440NQQI8,SMLF,IA
SMB_HOST_DB2000_3V3AUX_SCL R107             2        Q_RES_0402LF-0,5%,1/16W,CHIP,CA
SMB_HOST_DB2000_3V3AUX_SCL U38              L5       9QXL2001BNHGI8-9QXL2001BNHGI8,A
SMB_HOST_DB2000_3V3AUX_SDA R108             2        Q_RES_0402LF-33.2,1%,1/16W,CHIA
SMB_HOST_DB2000_3V3AUX_SDA U38              L4       9QXL2001BNHGI8-9QXL2001BNHGI8,A
SMB_M2_P0_1V8AUX_SCL     J59              40       SCONN75K_APCI0155P004A-SCONN75A
SMB_M2_P0_1V8AUX_SCL     R1703            2        Q_RES_0402LF-4.7K,5%,1/16W,CHIA
SMB_M2_P0_1V8AUX_SCL     U98              3        PCA9306DCTR-PCA9306DCTR,SMLF,IA
SMB_M2_P0_1V8AUX_SDA     J59              42       SCONN75K_APCI0155P004A-SCONN75A
SMB_M2_P0_1V8AUX_SDA     R1702            2        Q_RES_0402LF-4.7K,5%,1/16W,CHIA
SMB_M2_P0_1V8AUX_SDA     U98              4        PCA9306DCTR-PCA9306DCTR,SMLF,IA
SMB_OCP_SFF_3V3AUX_R_SCL J37              A7       SCONN168_623403212-SCONN168_6-A
SMB_OCP_SFF_3V3AUX_R_SCL R424             1        Q_RES_0402LF-33.2,1%,1/16W,CHIA
SMB_OCP_SFF_3V3AUX_R_SDA J37              A8       SCONN168_623403212-SCONN168_6-A
SMB_OCP_SFF_3V3AUX_R_SDA R425             1        Q_RES_0402LF-33.2,1%,1/16W,CHIA
SMB_OCP_SFF_3V3AUX_SCL   R424             2        Q_RES_0402LF-33.2,1%,1/16W,CHIA
SMB_OCP_SFF_3V3AUX_SCL   R657             2        Q_RES_0402LF-2.2K ,5%,1/16W,EMA
SMB_OCP_SFF_3V3AUX_SCL   R1053            1        Q_RES_0402LF-0,5%,1/16W,CHIP,CA
SMB_OCP_SFF_3V3AUX_SCL   R2200            2        Q_RES_0402LF-2.2K ,5%,1/16W,CHA
SMB_OCP_SFF_3V3AUX_SDA   R425             2        Q_RES_0402LF-33.2,1%,1/16W,CHIA
SMB_OCP_SFF_3V3AUX_SDA   R658             2        Q_RES_0402LF-2.2K ,5%,1/16W,EMA
SMB_OCP_SFF_3V3AUX_SDA   R1054            1        Q_RES_0402LF-0,5%,1/16W,CHIP,CA
SMB_OCP_SFF_3V3AUX_SDA   R2201            2        Q_RES_0402LF-2.2K ,5%,1/16W,CHA
SMB_PCIE0_3V3AUX_SCL     J41              A23      SCONN168_623403212-SCONN168_6-A
SMB_PCIE0_3V3AUX_SCL     R589             2        Q_RES_0402LF-33.2,1%,1/16W,CHIA
SMB_PCIE0_3V3AUX_SCL     R2204            2        Q_RES_0402LF-2.2K ,5%,1/16W,CHA
SMB_PCIE0_3V3AUX_SCL_R   R589             1        Q_RES_0402LF-33.2,1%,1/16W,CHIA
SMB_PCIE0_3V3AUX_SCL_R   U36              14       PCA9546APWR-PCA9546APWR,SMLF,IA
SMB_PCIE0_3V3AUX_SCL_R0  R2188            2        Q_RES_0402LF-0,5%,1/16W,CHIP,CA
SMB_PCIE0_3V3AUX_SCL_R0  U36              5        PCA9546APWR-PCA9546APWR,SMLF,IA
SMB_PCIE0_3V3AUX_SCL_R1  R660             2        Q_RES_0402LF-0,5%,1/16W,CHIP,CA
SMB_PCIE0_3V3AUX_SCL_R1  U36              7        PCA9546APWR-PCA9546APWR,SMLF,IA
SMB_PCIE0_3V3AUX_SCL_R2  R1051            1        Q_RES_0402LF-0,5%,1/16W,CHIP,CA
SMB_PCIE0_3V3AUX_SCL_R2  U36              10       PCA9546APWR-PCA9546APWR,SMLF,IA
SMB_PCIE0_3V3AUX_SCL_R3  R2189            1        Q_RES_0402LF-0,5%,1/16W,CHIP,CA
SMB_PCIE0_3V3AUX_SCL_R3  U36              12       PCA9546APWR-PCA9546APWR,SMLF,IA
SMB_PCIE0_3V3AUX_SDA     J41              A24      SCONN168_623403212-SCONN168_6-A
SMB_PCIE0_3V3AUX_SDA     R588             2        Q_RES_0402LF-33.2,1%,1/16W,CHIA
SMB_PCIE0_3V3AUX_SDA     R2205            2        Q_RES_0402LF-2.2K ,5%,1/16W,CHA
SMB_PCIE0_3V3AUX_SDA_R   R588             1        Q_RES_0402LF-33.2,1%,1/16W,CHIA
SMB_PCIE0_3V3AUX_SDA_R   U36              15       PCA9546APWR-PCA9546APWR,SMLF,IA
SMB_PCIE0_3V3AUX_SDA_R0  R2187            2        Q_RES_0402LF-0,5%,1/16W,CHIP,CA
SMB_PCIE0_3V3AUX_SDA_R0  U36              4        PCA9546APWR-PCA9546APWR,SMLF,IA
SMB_PCIE0_3V3AUX_SDA_R1  R659             2        Q_RES_0402LF-0,5%,1/16W,CHIP,CA
SMB_PCIE0_3V3AUX_SDA_R1  U36              6        PCA9546APWR-PCA9546APWR,SMLF,IA
SMB_PCIE0_3V3AUX_SDA_R2  R1052            1        Q_RES_0402LF-0,5%,1/16W,CHIP,CA
SMB_PCIE0_3V3AUX_SDA_R2  U36              9        PCA9546APWR-PCA9546APWR,SMLF,IA
SMB_PCIE0_3V3AUX_SDA_R3  R2190            1        Q_RES_0402LF-0,5%,1/16W,CHIP,CA
SMB_PCIE0_3V3AUX_SDA_R3  U36              11       PCA9546APWR-PCA9546APWR,SMLF,IA
SMB_PCIE1_3V3AUX_SCL     J41              A27      SCONN168_623403212-SCONN168_6-A
SMB_PCIE1_3V3AUX_SCL     R648             2        Q_RES_0402LF-0,5%,1/16W,CHIP,CA
SMB_PCIE1_3V3AUX_SCL     R914             2        Q_RES_0402LF-2.2K ,5%,1/16W,CHA
SMB_PCIE1_3V3AUX_SCL_R   R648             1        Q_RES_0402LF-0,5%,1/16W,CHIP,CA
SMB_PCIE1_3V3AUX_SCL_R   U10              14       PCA9546APWR-PCA9546APWR,SMLF,IA
SMB_PCIE1_3V3AUX_SCL_R0  R1057            2        Q_RES_0402LF-33.2,1%,1/16W,CHIA
SMB_PCIE1_3V3AUX_SCL_R0  U10              5        PCA9546APWR-PCA9546APWR,SMLF,IA
SMB_PCIE1_3V3AUX_SCL_R1  R1059            2        Q_RES_0402LF-0,5%,1/16W,CHIP,CA
SMB_PCIE1_3V3AUX_SCL_R1  U10              7        PCA9546APWR-PCA9546APWR,SMLF,IA
SMB_PCIE1_3V3AUX_SCL_R2  R1061            1        Q_RES_0402LF-0,5%,1/16W,CHIP,CA
SMB_PCIE1_3V3AUX_SCL_R2  U10              10       PCA9546APWR-PCA9546APWR,SMLF,IA
SMB_PCIE1_3V3AUX_SCL_R3  R1063            1        Q_RES_0402LF-0,5%,1/16W,CHIP,CA
SMB_PCIE1_3V3AUX_SCL_R3  U10              12       PCA9546APWR-PCA9546APWR,SMLF,IA
SMB_PCIE1_3V3AUX_SDA     J41              A28      SCONN168_623403212-SCONN168_6-A
SMB_PCIE1_3V3AUX_SDA     R647             2        Q_RES_0402LF-33.2,1%,1/16W,CHIA
SMB_PCIE1_3V3AUX_SDA     R1314            2        Q_RES_0402LF-2.2K ,5%,1/16W,CHA
SMB_PCIE1_3V3AUX_SDA_R   R647             1        Q_RES_0402LF-33.2,1%,1/16W,CHIA
SMB_PCIE1_3V3AUX_SDA_R   U10              15       PCA9546APWR-PCA9546APWR,SMLF,IA
SMB_PCIE1_3V3AUX_SDA_R0  R1058            2        Q_RES_0402LF-0,5%,1/16W,CHIP,CA
SMB_PCIE1_3V3AUX_SDA_R0  U10              4        PCA9546APWR-PCA9546APWR,SMLF,IA
SMB_PCIE1_3V3AUX_SDA_R1  R1060            2        Q_RES_0402LF-0,5%,1/16W,CHIP,CA
SMB_PCIE1_3V3AUX_SDA_R1  U10              6        PCA9546APWR-PCA9546APWR,SMLF,IA
SMB_PCIE1_3V3AUX_SDA_R2  R1062            1        Q_RES_0402LF-0,5%,1/16W,CHIP,CA
SMB_PCIE1_3V3AUX_SDA_R2  U10              9        PCA9546APWR-PCA9546APWR,SMLF,IA
SMB_PCIE1_3V3AUX_SDA_R3  R1064            1        Q_RES_0402LF-0,5%,1/16W,CHIP,CA
SMB_PCIE1_3V3AUX_SDA_R3  U10              11       PCA9546APWR-PCA9546APWR,SMLF,IA
SMB_PCIE2_3V3AUX_SCL     J41              A31      SCONN168_623403212-SCONN168_6-A
SMB_PCIE2_3V3AUX_SCL     R2206            2        Q_RES_0402LF-2.2K ,5%,1/16W,CHA
SMB_PCIE2_3V3AUX_SCL     U24              22       PCA9548APW-PCA9548APW,SMLF,IC,A
SMB_PCIE2_3V3AUX_SDA     J41              A32      SCONN168_623403212-SCONN168_6-A
SMB_PCIE2_3V3AUX_SDA     R2207            2        Q_RES_0402LF-2.2K ,5%,1/16W,CHA
SMB_PCIE2_3V3AUX_SDA     U24              23       PCA9548APW-PCA9548APW,SMLF,IC,A
SMB_PCIE3_3V3AUX_SCL     J41              A38      SCONN168_623403212-SCONN168_6-A
SMB_PCIE3_3V3AUX_SCL     R2198            2        Q_RES_0402LF-2.2K ,5%,1/16W,CHA
SMB_PCIE3_3V3AUX_SCL     U141             14       PCA9546APWR-PCA9546APWR,SMLF,IA
SMB_PCIE3_3V3AUX_SDA     J41              A39      SCONN168_623403212-SCONN168_6-A
SMB_PCIE3_3V3AUX_SDA     R2199            2        Q_RES_0402LF-2.2K ,5%,1/16W,CHA
SMB_PCIE3_3V3AUX_SDA     U141             15       PCA9546APWR-PCA9546APWR,SMLF,IA
SMB_PCIE_3V3AUX_B_SCL    R1560            1        Q_RES_0402LF-0,5%,1/16W,EMPTY,A
SMB_PCIE_3V3AUX_B_SCL    U122             B16      10M04SAU324I7G-10M04SAU324I7G,A
SMB_PCIE_3V3AUX_B_SDA    R1559            1        Q_RES_0402LF-0,5%,1/16W,EMPTY,A
SMB_PCIE_3V3AUX_B_SDA    U122             B17      10M04SAU324I7G-10M04SAU324I7G,A
SMB_PCIE_3V3AUX_SCL      R1550            2        Q_RES_0402LF-4.7K,1%,1/16W,CHIA
SMB_PCIE_3V3AUX_SCL      R1560            2        Q_RES_0402LF-0,5%,1/16W,EMPTY,A
SMB_PCIE_3V3AUX_SCL_R3   R1055            2        Q_RES_0402LF-0,5%,1/16W,CHIP,CA
SMB_PCIE_3V3AUX_SCL_R3   U141             7        PCA9546APWR-PCA9546APWR,SMLF,IA
SMB_PCIE_3V3AUX_SCL_R4   R1053            2        Q_RES_0402LF-0,5%,1/16W,CHIP,CA
SMB_PCIE_3V3AUX_SCL_R4   U141             5        PCA9546APWR-PCA9546APWR,SMLF,IA
SMB_PCIE_3V3AUX_SDA      R1549            2        Q_RES_0402LF-4.7K,1%,1/16W,CHIA
SMB_PCIE_3V3AUX_SDA      R1559            2        Q_RES_0402LF-0,5%,1/16W,EMPTY,A
SMB_PCIE_3V3AUX_SDA_R3   R1056            2        Q_RES_0402LF-0,5%,1/16W,CHIP,CA
SMB_PCIE_3V3AUX_SDA_R3   U141             6        PCA9546APWR-PCA9546APWR,SMLF,IA
SMB_PCIE_3V3AUX_SDA_R4   R1054            2        Q_RES_0402LF-0,5%,1/16W,CHIP,CA
SMB_PCIE_3V3AUX_SDA_R4   U141             4        PCA9546APWR-PCA9546APWR,SMLF,IA
SMB_PCIE_M2_EN           R1700            2        Q_RES_0402LF-4.7K,5%,1/16W,CHIA
SMB_PCIE_M2_EN           R1701            1        Q_RES_0402LF-100K,1%,1/16W,EMPB
SMB_PCIE_M2_EN           U98              8        PCA9306DCTR-PCA9306DCTR,SMLF,IA
SMB_PEHPCPU0_EDSFF1ALVC3_R_SDA J62              B9       SCONN84_123318136-SCONN84_1-23A
SMB_PEHPCPU0_EDSFF1ALVC3_R_SDA R1966            2        Q_RES_0402LF-33.2,1%,1/16W,CHIA
SMB_PEHPCPU0_EDSFF1A_LVC3_R_SCL J62              A10      SCONN84_123318136-SCONN84_1-23A
SMB_PEHPCPU0_EDSFF1A_LVC3_R_SCL R1971            1        Q_RES_0402LF-33.2,1%,1/16W,CHIA
SMB_PEHPCPU0_EDSFF1B_LVC3_R_SCL J87              A10      SCONN84_123318136-SCONN84_1-23A
SMB_PEHPCPU0_EDSFF1B_LVC3_R_SCL R1981            1        Q_RES_0402LF-33.2,1%,1/16W,CHIA
SMB_PEHPCPU0_EDSFF1B_LVC3_R_SDA J87              B9       SCONN84_123318136-SCONN84_1-23A
SMB_PEHPCPU0_EDSFF1B_LVC3_R_SDA R1976            2        Q_RES_0402LF-33.2,1%,1/16W,CHIA
SMB_PEHPCPU0_GTL_R_SCL   R910             2        Q_RES_0402LF-240,1%,1/16W,CHIPA
SMB_PEHPCPU0_GTL_R_SCL   R960             2        Q_RES_0402LF-33.2,1%,1/16W,CHIA
SMB_PEHPCPU0_GTL_R_SCL   U28              2        PCA9617ADP-PCA9617ADP,SMLF,IC,A
SMB_PEHPCPU0_GTL_R_SDA   R909             2        Q_RES_0402LF-33.2,1%,1/16W,CHIA
SMB_PEHPCPU0_GTL_R_SDA   R911             2        Q_RES_0402LF-240,1%,1/16W,CHIPA
SMB_PEHPCPU0_GTL_R_SDA   U28              3        PCA9617ADP-PCA9617ADP,SMLF,IC,A
SMB_PEHPCPU0_GTL_SCL     R960             1        Q_RES_0402LF-33.2,1%,1/16W,CHIA
SMB_PEHPCPU0_GTL_SCL     U2               CA25     SOCKET4677_AZIFS054P001C01-SOCA
SMB_PEHPCPU0_GTL_SDA     R909             1        Q_RES_0402LF-33.2,1%,1/16W,CHIA
SMB_PEHPCPU0_GTL_SDA     U2               BY26     SOCKET4677_AZIFS054P001C01-SOCA
SMB_PEHPCPU0_LVC3_R1_SCL R2101            2        Q_RES_0402LF-33,5%,1/16W,CHIP,A
SMB_PEHPCPU0_LVC3_R1_SCL U130             22       PCA9555PW_SMLF-PCA9555PW,IC,TMA
SMB_PEHPCPU0_LVC3_R1_SDA R2102            2        Q_RES_0402LF-33,5%,1/16W,CHIP,A
SMB_PEHPCPU0_LVC3_R1_SDA U130             23       PCA9555PW_SMLF-PCA9555PW,IC,TMA
SMB_PEHPCPU0_LVC3_R2_SCL R2103            2        Q_RES_0402LF-33,5%,1/16W,CHIP,A
SMB_PEHPCPU0_LVC3_R2_SCL U131             22       PCA9555PW_SMLF-PCA9555PW,IC,TMA
SMB_PEHPCPU0_LVC3_R2_SDA R2104            2        Q_RES_0402LF-33,5%,1/16W,CHIP,A
SMB_PEHPCPU0_LVC3_R2_SDA U131             23       PCA9555PW_SMLF-PCA9555PW,IC,TMA
SMB_PEHPCPU0_LVC3_R_SCL  R1130            2        Q_RES_0402LF-33,5%,1/16W,CHIP,A
SMB_PEHPCPU0_LVC3_R_SCL  U51              22       PCA9555PW_SMLF-PCA9555PW,IC,TMA
SMB_PEHPCPU0_LVC3_R_SDA  R1131            2        Q_RES_0402LF-33,5%,1/16W,CHIP,A
SMB_PEHPCPU0_LVC3_R_SDA  U51              23       PCA9555PW_SMLF-PCA9555PW,IC,TMA
SMB_PEHPCPU0_LVC3_SCL    R965             2        Q_RES_0402LF-1K,1%,1/16W,CHIP,A
SMB_PEHPCPU0_LVC3_SCL    R1130            1        Q_RES_0402LF-33,5%,1/16W,CHIP,A
SMB_PEHPCPU0_LVC3_SCL    R1971            2        Q_RES_0402LF-33.2,1%,1/16W,CHIA
SMB_PEHPCPU0_LVC3_SCL    R1981            2        Q_RES_0402LF-33.2,1%,1/16W,CHIA
SMB_PEHPCPU0_LVC3_SCL    R2101            1        Q_RES_0402LF-33,5%,1/16W,CHIP,A
SMB_PEHPCPU0_LVC3_SCL    R2103            1        Q_RES_0402LF-33,5%,1/16W,CHIP,A
SMB_PEHPCPU0_LVC3_SCL    U28              7        PCA9617ADP-PCA9617ADP,SMLF,IC,A
SMB_PEHPCPU0_LVC3_SDA    R967             2        Q_RES_0402LF-1K,1%,1/16W,CHIP,A
SMB_PEHPCPU0_LVC3_SDA    R1131            1        Q_RES_0402LF-33,5%,1/16W,CHIP,A
SMB_PEHPCPU0_LVC3_SDA    R1966            1        Q_RES_0402LF-33.2,1%,1/16W,CHIA
SMB_PEHPCPU0_LVC3_SDA    R1976            1        Q_RES_0402LF-33.2,1%,1/16W,CHIA
SMB_PEHPCPU0_LVC3_SDA    R2102            1        Q_RES_0402LF-33,5%,1/16W,CHIP,A
SMB_PEHPCPU0_LVC3_SDA    R2104            1        Q_RES_0402LF-33,5%,1/16W,CHIP,A
SMB_PEHPCPU0_LVC3_SDA    U28              6        PCA9617ADP-PCA9617ADP,SMLF,IC,A
SMB_PEHPCPU1_EDSFF4A_LVC3_R_SCL J88              A10      SCONN84_123318136-SCONN84_1-23A
SMB_PEHPCPU1_EDSFF4A_LVC3_R_SCL R1991            1        Q_RES_0402LF-33.2,1%,1/16W,CHIA
SMB_PEHPCPU1_EDSFF4A_LVC3_R_SDA J88              B9       SCONN84_123318136-SCONN84_1-23A
SMB_PEHPCPU1_EDSFF4A_LVC3_R_SDA R1986            2        Q_RES_0402LF-33.2,1%,1/16W,CHIA
SMB_PEHPCPU1_GTL_R_SCL   R961             2        Q_RES_0402LF-33.2,1%,1/16W,CHIA
SMB_PEHPCPU1_GTL_R_SCL   R963             2        Q_RES_0402LF-240,1%,1/16W,CHIPA
SMB_PEHPCPU1_GTL_R_SCL   U29              2        PCA9617ADP-PCA9617ADP,SMLF,IC,A
SMB_PEHPCPU1_GTL_R_SDA   R962             2        Q_RES_0402LF-33.2,1%,1/16W,CHIA
SMB_PEHPCPU1_GTL_R_SDA   R964             2        Q_RES_0402LF-240,1%,1/16W,CHIPA
SMB_PEHPCPU1_GTL_R_SDA   U29              3        PCA9617ADP-PCA9617ADP,SMLF,IC,A
SMB_PEHPCPU1_GTL_SCL     R961             1        Q_RES_0402LF-33.2,1%,1/16W,CHIA
SMB_PEHPCPU1_GTL_SCL     U1               CA25     SOCKET4677_AZIFS054P001C01-SOCA
SMB_PEHPCPU1_GTL_SDA     R962             1        Q_RES_0402LF-33.2,1%,1/16W,CHIA
SMB_PEHPCPU1_GTL_SDA     U1               BY26     SOCKET4677_AZIFS054P001C01-SOCA
SMB_PEHPCPU1_LVC3_SCL    R966             2        Q_RES_0402LF-1K,1%,1/16W,CHIP,A
SMB_PEHPCPU1_LVC3_SCL    R1991            2        Q_RES_0402LF-33.2,1%,1/16W,CHIA
SMB_PEHPCPU1_LVC3_SCL    U29              7        PCA9617ADP-PCA9617ADP,SMLF,IC,A
SMB_PEHPCPU1_LVC3_SDA    R968             2        Q_RES_0402LF-1K,1%,1/16W,CHIP,A
SMB_PEHPCPU1_LVC3_SDA    R1986            1        Q_RES_0402LF-33.2,1%,1/16W,CHIA
SMB_PEHPCPU1_LVC3_SDA    U29              6        PCA9617ADP-PCA9617ADP,SMLF,IC,A
SMB_PLD_3V3AUX_SCL       J41              A1       SCONN168_623403212-SCONN168_6-A
SMB_PLD_3V3AUX_SCL       R1761            1        Q_RES_0402LF-33,5%,1/16W,CHIP,A
SMB_PLD_3V3AUX_SCL_R     R1551            2        Q_RES_0402LF-4.7K,1%,1/16W,CHIA
SMB_PLD_3V3AUX_SCL_R     R1761            2        Q_RES_0402LF-33,5%,1/16W,CHIP,A
SMB_PLD_3V3AUX_SCL_R     U122             J2       10M04SAU324I7G-10M04SAU324I7G,A
SMB_PLD_3V3AUX_SDA       J41              A2       SCONN168_623403212-SCONN168_6-A
SMB_PLD_3V3AUX_SDA       R1762            1        Q_RES_0402LF-33,5%,1/16W,CHIP,A
SMB_PLD_3V3AUX_SDA_R     R1467            2        Q_RES_0402LF-4.7K,1%,1/16W,CHIA
SMB_PLD_3V3AUX_SDA_R     R1762            2        Q_RES_0402LF-33,5%,1/16W,CHIP,A
SMB_PLD_3V3AUX_SDA_R     U122             J1       10M04SAU324I7G-10M04SAU324I7G,A
SMB_PMBUS_PSU1_SCL       R1537            2        Q_RES_0402LF-33.2,1%,1/16W,CHIA
SMB_PMBUS_PSU1_SCL       R1940            2        Q_RES_0402LF-33.2,1%,1/16W,CHIA
SMB_PMBUS_PSU1_SCL_R2    J44              6        CONN24_52SH90245BRD-CONN24_52SA
SMB_PMBUS_PSU1_SCL_R2    R1940            1        Q_RES_0402LF-33.2,1%,1/16W,CHIA
SMB_PMBUS_PSU1_SDA       R1538            2        Q_RES_0402LF-33.2,1%,1/16W,CHIA
SMB_PMBUS_PSU1_SDA       R1941            2        Q_RES_0402LF-33.2,1%,1/16W,CHIA
SMB_PMBUS_PSU1_SDA_R2    J44              10       CONN24_52SH90245BRD-CONN24_52SA
SMB_PMBUS_PSU1_SDA_R2    R1941            1        Q_RES_0402LF-33.2,1%,1/16W,CHIA
SMB_RISER1_3V3AUX_SCL    J55              B7       SCONN140_G64V3431BHR-SCONN140_A
SMB_RISER1_3V3AUX_SCL    R1091            2        Q_RES_0402LF-2.2K ,5%,1/16W,CHA
SMB_RISER1_3V3AUX_SCL    R2188            1        Q_RES_0402LF-0,5%,1/16W,CHIP,CA
SMB_RISER1_3V3AUX_SDA    J55              B8       SCONN140_G64V3431BHR-SCONN140_A
SMB_RISER1_3V3AUX_SDA    R1092            2        Q_RES_0402LF-2.2K ,5%,1/16W,CHA
SMB_RISER1_3V3AUX_SDA    R2187            1        Q_RES_0402LF-0,5%,1/16W,CHIP,CA
SMB_RISER2_0_3V3AUX_SCL  J89              A20      SCONN280_ME1028040102011-SCONNA
SMB_RISER2_0_3V3AUX_SCL  R651             2        Q_RES_0402LF-2.2K ,5%,1/16W,CHA
SMB_RISER2_0_3V3AUX_SCL  R660             1        Q_RES_0402LF-0,5%,1/16W,CHIP,CA
SMB_RISER2_0_3V3AUX_SDA  J89              A21      SCONN280_ME1028040102011-SCONNA
SMB_RISER2_0_3V3AUX_SDA  R652             2        Q_RES_0402LF-2.2K ,5%,1/16W,CHA
SMB_RISER2_0_3V3AUX_SDA  R659             1        Q_RES_0402LF-0,5%,1/16W,CHIP,CA
SMB_RISER2_1_3V3AUX_SCL  J89              B24      SCONN280_ME1028040102011-SCONNA
SMB_RISER2_1_3V3AUX_SCL  R653             2        Q_RES_0402LF-2.2K ,5%,1/16W,CHA
SMB_RISER2_1_3V3AUX_SCL  R1051            2        Q_RES_0402LF-0,5%,1/16W,CHIP,CA
SMB_RISER2_1_3V3AUX_SDA  J89              B25      SCONN280_ME1028040102011-SCONNA
SMB_RISER2_1_3V3AUX_SDA  R654             2        Q_RES_0402LF-2.2K ,5%,1/16W,CHA
SMB_RISER2_1_3V3AUX_SDA  R1052            2        Q_RES_0402LF-0,5%,1/16W,CHIP,CA
SMB_RISER3_3V3AUX_SCL    J57              B7       SCONN140_G64V3431BHR-SCONN140_A
SMB_RISER3_3V3AUX_SCL    R655             2        Q_RES_0402LF-2.2K ,5%,1/16W,CHA
SMB_RISER3_3V3AUX_SCL    R1055            1        Q_RES_0402LF-0,5%,1/16W,CHIP,CA
SMB_RISER3_3V3AUX_SCL    R2202            2        Q_RES_0402LF-2.2K ,5%,1/16W,CHA
SMB_RISER3_3V3AUX_SDA    J57              B8       SCONN140_G64V3431BHR-SCONN140_A
SMB_RISER3_3V3AUX_SDA    R656             2        Q_RES_0402LF-2.2K ,5%,1/16W,CHA
SMB_RISER3_3V3AUX_SDA    R1056            1        Q_RES_0402LF-0,5%,1/16W,CHIP,CA
SMB_RISER3_3V3AUX_SDA    R2203            2        Q_RES_0402LF-2.2K ,5%,1/16W,CHA
SMB_S3M_CPU0_3V3AUX_SCL  R448             1        Q_RES_0402LF-0,5%,1/16W,EMPTY,A
SMB_S3M_CPU0_3V3AUX_SCL  R977             2        Q_RES_0402LF-412,1%,1/16W,CHIPA
SMB_S3M_CPU0_3V3AUX_SCL  R1759            1        Q_RES_0402LF-0,5%,1/16W,EMPTY,A
SMB_S3M_CPU0_3V3AUX_SCL  R2208            2        Q_RES_0402LF-0,5%,1/16W,CHIP,CA
SMB_S3M_CPU0_3V3AUX_SCL  U30              7        PCA9617ADP-PCA9617ADP,SMLF,IC,A
SMB_S3M_CPU0_3V3AUX_SDA  R979             2        Q_RES_0402LF-412,1%,1/16W,CHIPA
SMB_S3M_CPU0_3V3AUX_SDA  R1648            1        Q_RES_0402LF-0,5%,1/16W,EMPTY,A
SMB_S3M_CPU0_3V3AUX_SDA  R1760            1        Q_RES_0402LF-0,5%,1/16W,EMPTY,A
SMB_S3M_CPU0_3V3AUX_SDA  R2209            2        Q_RES_0402LF-0,5%,1/16W,CHIP,CA
SMB_S3M_CPU0_3V3AUX_SDA  U30              6        PCA9617ADP-PCA9617ADP,SMLF,IC,A
SMB_S3M_CPU0_LVC1_SCL    R973             2        Q_RES_0402LF-33.2,1%,1/16W,CHIA
SMB_S3M_CPU0_LVC1_SCL    R1759            2        Q_RES_0402LF-0,5%,1/16W,EMPTY,A
SMB_S3M_CPU0_LVC1_SCL    U122             R8       10M04SAU324I7G-10M04SAU324I7G,A
SMB_S3M_CPU0_LVC1_SDA    R974             2        Q_RES_0402LF-33.2,1%,1/16W,CHIA
SMB_S3M_CPU0_LVC1_SDA    R1760            2        Q_RES_0402LF-0,5%,1/16W,EMPTY,A
SMB_S3M_CPU0_LVC1_SDA    U122             R9       10M04SAU324I7G-10M04SAU324I7G,A
SMB_S3M_CPU0_R_SCL       R969             2        Q_RES_0402LF-240,1%,1/16W,CHIPA
SMB_S3M_CPU0_R_SCL       R973             1        Q_RES_0402LF-33.2,1%,1/16W,CHIA
SMB_S3M_CPU0_R_SCL       R993             2        Q_RES_0402LF-33.2,1%,1/16W,CHIA
SMB_S3M_CPU0_R_SCL       U30              2        PCA9617ADP-PCA9617ADP,SMLF,IC,A
SMB_S3M_CPU0_R_SDA       R971             2        Q_RES_0402LF-240,1%,1/16W,CHIPA
SMB_S3M_CPU0_R_SDA       R974             1        Q_RES_0402LF-33.2,1%,1/16W,CHIA
SMB_S3M_CPU0_R_SDA       R994             2        Q_RES_0402LF-33.2,1%,1/16W,CHIA
SMB_S3M_CPU0_R_SDA       U30              3        PCA9617ADP-PCA9617ADP,SMLF,IC,A
SMB_S3M_CPU0_SCL         R993             1        Q_RES_0402LF-33.2,1%,1/16W,CHIA
SMB_S3M_CPU0_SCL         U2               CE64     SOCKET4677_AZIFS054P001C01-SOCA
SMB_S3M_CPU0_SDA         R994             1        Q_RES_0402LF-33.2,1%,1/16W,CHIA
SMB_S3M_CPU0_SDA         U2               CD63     SOCKET4677_AZIFS054P001C01-SOCA
SMB_S3M_CPU1_3V3AUX_SCL  R448             2        Q_RES_0402LF-0,5%,1/16W,EMPTY,A
SMB_S3M_CPU1_3V3AUX_SCL  R978             2        Q_RES_0402LF-412,1%,1/16W,CHIPA
SMB_S3M_CPU1_3V3AUX_SCL  R1829            1        Q_RES_0402LF-0,5%,1/16W,EMPTY,A
SMB_S3M_CPU1_3V3AUX_SCL  R2210            2        Q_RES_0402LF-0,5%,1/16W,CHIP,CA
SMB_S3M_CPU1_3V3AUX_SCL  U31              7        PCA9617ADP-PCA9617ADP,SMLF,IC,A
SMB_S3M_CPU1_3V3AUX_SDA  R980             2        Q_RES_0402LF-412,1%,1/16W,CHIPA
SMB_S3M_CPU1_3V3AUX_SDA  R1648            2        Q_RES_0402LF-0,5%,1/16W,EMPTY,A
SMB_S3M_CPU1_3V3AUX_SDA  R1830            1        Q_RES_0402LF-0,5%,1/16W,EMPTY,A
SMB_S3M_CPU1_3V3AUX_SDA  R2211            2        Q_RES_0402LF-0,5%,1/16W,CHIP,CA
SMB_S3M_CPU1_3V3AUX_SDA  U31              6        PCA9617ADP-PCA9617ADP,SMLF,IC,A
SMB_S3M_CPU1_LVC1_SCL    R975             2        Q_RES_0402LF-33.2,1%,1/16W,CHIA
SMB_S3M_CPU1_LVC1_SCL    R1829            2        Q_RES_0402LF-0,5%,1/16W,EMPTY,A
SMB_S3M_CPU1_LVC1_SCL    U122             N7       10M04SAU324I7G-10M04SAU324I7G,A
SMB_S3M_CPU1_LVC1_SDA    R976             2        Q_RES_0402LF-33.2,1%,1/16W,CHIA
SMB_S3M_CPU1_LVC1_SDA    R1830            2        Q_RES_0402LF-0,5%,1/16W,EMPTY,A
SMB_S3M_CPU1_LVC1_SDA    U122             N8       10M04SAU324I7G-10M04SAU324I7G,A
SMB_S3M_CPU1_R_SCL       R970             2        Q_RES_0402LF-240,1%,1/16W,CHIPA
SMB_S3M_CPU1_R_SCL       R975             1        Q_RES_0402LF-33.2,1%,1/16W,CHIA
SMB_S3M_CPU1_R_SCL       R995             2        Q_RES_0402LF-33.2,1%,1/16W,CHIA
SMB_S3M_CPU1_R_SCL       U31              2        PCA9617ADP-PCA9617ADP,SMLF,IC,A
SMB_S3M_CPU1_R_SDA       R972             2        Q_RES_0402LF-240,1%,1/16W,CHIPA
SMB_S3M_CPU1_R_SDA       R976             1        Q_RES_0402LF-33.2,1%,1/16W,CHIA
SMB_S3M_CPU1_R_SDA       R996             2        Q_RES_0402LF-33.2,1%,1/16W,CHIA
SMB_S3M_CPU1_R_SDA       U31              3        PCA9617ADP-PCA9617ADP,SMLF,IC,A
SMB_S3M_CPU1_SCL         R995             1        Q_RES_0402LF-33.2,1%,1/16W,CHIA
SMB_S3M_CPU1_SCL         U1               CE64     SOCKET4677_AZIFS054P001C01-SOCA
SMB_S3M_CPU1_SDA         R996             1        Q_RES_0402LF-33.2,1%,1/16W,CHIA
SMB_S3M_CPU1_SDA         U1               CD63     SOCKET4677_AZIFS054P001C01-SOCA
SMB_S3M_CPU_3V3AUX_SCL   J41              A40      SCONN168_623403212-SCONN168_6-A
SMB_S3M_CPU_3V3AUX_SCL   R2208            1        Q_RES_0402LF-0,5%,1/16W,CHIP,CA
SMB_S3M_CPU_3V3AUX_SCL   R2210            1        Q_RES_0402LF-0,5%,1/16W,CHIP,CA
SMB_S3M_CPU_3V3AUX_SCL   R2212            1        Q_RES_0402LF-2.2K ,5%,1/16W,CHA
SMB_S3M_CPU_3V3AUX_SDA   J41              A41      SCONN168_623403212-SCONN168_6-A
SMB_S3M_CPU_3V3AUX_SDA   R2209            1        Q_RES_0402LF-0,5%,1/16W,CHIP,CA
SMB_S3M_CPU_3V3AUX_SDA   R2211            1        Q_RES_0402LF-0,5%,1/16W,CHIP,CA
SMB_S3M_CPU_3V3AUX_SDA   R2213            1        Q_RES_0402LF-2.2K ,5%,1/16W,CHA
SMB_SENSOR_3V3AUX_SCL    J41              A9       SCONN168_623403212-SCONN168_6-A
SMB_SENSOR_3V3AUX_SCL    R460             1        Q_RES_0402LF-33.2,1%,1/16W,CHIA
SMB_SENSOR_3V3AUX_SCL    R475             1        Q_RES_0402LF-33.2,1%,1/16W,CHIA
SMB_SENSOR_3V3AUX_SCL    R726             1        Q_RES_0402LF-33.2,1%,1/16W,CHIA
SMB_SENSOR_3V3AUX_SCL    R1331            2        Q_RES_0402LF-4.7K,5%,1/16W,CHIA
SMB_SENSOR_3V3AUX_SCL    R1336            1        Q_RES_0402LF-2.2K ,5%,1/16W,CHA
SMB_SENSOR_3V3AUX_SDA    J41              A10      SCONN168_623403212-SCONN168_6-A
SMB_SENSOR_3V3AUX_SDA    R459             1        Q_RES_0402LF-33.2,1%,1/16W,CHIA
SMB_SENSOR_3V3AUX_SDA    R709             1        Q_RES_0402LF-33.2,1%,1/16W,CHIA
SMB_SENSOR_3V3AUX_SDA    R725             1        Q_RES_0402LF-33.2,1%,1/16W,CHIA
SMB_SENSOR_3V3AUX_SDA    R1332            2        Q_RES_0402LF-4.7K,5%,1/16W,CHIA
SMB_SENSOR_3V3AUX_SDA    R1460            1        Q_RES_0402LF-2.2K ,5%,1/16W,CHA
SMB_SENSOR_M2_P0_3V3AUX_SCL R1089            2        Q_RES_0402LF-2.2K ,5%,1/16W,CHA
SMB_SENSOR_M2_P0_3V3AUX_SCL R2189            2        Q_RES_0402LF-0,5%,1/16W,CHIP,CA
SMB_SENSOR_M2_P0_3V3AUX_SCL U98              6        PCA9306DCTR-PCA9306DCTR,SMLF,IA
SMB_SENSOR_M2_P0_3V3AUX_SDA R1090            2        Q_RES_0402LF-2.2K ,5%,1/16W,CHA
SMB_SENSOR_M2_P0_3V3AUX_SDA R2190            2        Q_RES_0402LF-0,5%,1/16W,CHIP,CA
SMB_SENSOR_M2_P0_3V3AUX_SDA U98              5        PCA9306DCTR-PCA9306DCTR,SMLF,IA
SMB_SEN_3V3AUX_SCL       R1793            2        Q_RES_0402LF-0,5%,1/16W,CHIP,CA
SMB_SEN_3V3AUX_SCL       U105             10       ADS1015IDGSR-ADS1015IDGSR,SMLFA
SMB_SEN_3V3AUX_SCL       U121             5        MAX11607EUAT-MAX11607EUA+T,SMLA
SMB_SEN_3V3AUX_SDA       R1792            2        Q_RES_0402LF-0,5%,1/16W,CHIP,CA
SMB_SEN_3V3AUX_SDA       U105             9        ADS1015IDGSR-ADS1015IDGSR,SMLFA
SMB_SEN_3V3AUX_SDA       U121             6        MAX11607EUAT-MAX11607EUA+T,SMLA
SMB_SML0B_3V3AUX_SCL     R1545            1        Q_RES_0402LF-2K,1%,1/16W,CHIP,A
SMB_SML0B_3V3AUX_SCL     U4               BB3      EMMITSBURG_REV0P9-GFNOCPU04302A
SMB_SML0B_3V3AUX_SDA     R1546            1        Q_RES_0402LF-2K,1%,1/16W,CHIP,A
SMB_SML0B_3V3AUX_SDA     U4               AU4      EMMITSBURG_REV0P9-GFNOCPU04302A
SMB_SML0_3V3AUX_PCH_SCL  R581             2        Q_RES_0402LF-33,5%,1/16W,CHIP,A
SMB_SML0_3V3AUX_PCH_SCL  U4               BC4      EMMITSBURG_REV0P9-GFNOCPU04302A
SMB_SML0_3V3AUX_PCH_SDA  R582             2        Q_RES_0402LF-33,5%,1/16W,CHIP,A
SMB_SML0_3V3AUX_PCH_SDA  U4               BA4      EMMITSBURG_REV0P9-GFNOCPU04302A
SMB_SML0_3V3AUX_SCL      J41              A25      SCONN168_623403212-SCONN168_6-A
SMB_SML0_3V3AUX_SCL      R581             1        Q_RES_0402LF-33,5%,1/16W,CHIP,A
SMB_SML0_3V3AUX_SCL      R1384            1        Q_RES_0402LF-2K,1%,1/16W,CHIP,A
SMB_SML0_3V3AUX_SDA      J41              A26      SCONN168_623403212-SCONN168_6-A
SMB_SML0_3V3AUX_SDA      R582             1        Q_RES_0402LF-33,5%,1/16W,CHIP,A
SMB_SML0_3V3AUX_SDA      R1385            1        Q_RES_0402LF-2K,1%,1/16W,CHIP,A
SMB_SML1_PMBUS_3V3AUX_PCH_SCL J41              A7       SCONN168_623403212-SCONN168_6-A
SMB_SML1_PMBUS_3V3AUX_PCH_SCL R585             1        Q_RES_0402LF-33,5%,1/16W,CHIP,A
SMB_SML1_PMBUS_3V3AUX_PCH_SCL R1386            1        Q_RES_0402LF-2K,1%,1/16W,CHIP,A
SMB_SML1_PMBUS_3V3AUX_PCH_SCL R1537            1        Q_RES_0402LF-33.2,1%,1/16W,CHIA
SMB_SML1_PMBUS_3V3AUX_PCH_SCL U4               AP1      EMMITSBURG_REV0P9-GFNOCPU04302A
SMB_SML1_PMBUS_3V3AUX_PCH_SDA J41              A8       SCONN168_623403212-SCONN168_6-A
SMB_SML1_PMBUS_3V3AUX_PCH_SDA R586             1        Q_RES_0402LF-33,5%,1/16W,CHIP,A
SMB_SML1_PMBUS_3V3AUX_PCH_SDA R1387            1        Q_RES_0402LF-2K,1%,1/16W,CHIP,A
SMB_SML1_PMBUS_3V3AUX_PCH_SDA R1538            1        Q_RES_0402LF-33.2,1%,1/16W,CHIA
SMB_SML1_PMBUS_3V3AUX_PCH_SDA U4               AW4      EMMITSBURG_REV0P9-GFNOCPU04302A
SMB_SML1_PMBUS_3V3AUX_PLD_SCL R585             2        Q_RES_0402LF-33,5%,1/16W,CHIP,A
SMB_SML1_PMBUS_3V3AUX_PLD_SCL U122             F11      10M04SAU324I7G-10M04SAU324I7G,A
SMB_SML1_PMBUS_3V3AUX_PLD_SDA R586             2        Q_RES_0402LF-33,5%,1/16W,CHIP,A
SMB_SML1_PMBUS_3V3AUX_PLD_SDA U122             F12      10M04SAU324I7G-10M04SAU324I7G,A
SMB_TMP75_1_3V3AUX_SCL_R R460             2        Q_RES_0402LF-33.2,1%,1/16W,CHIA
SMB_TMP75_1_3V3AUX_SCL_R U63              2        TMP75AIDR-TMP75AIDR,SMLF,IC,ALA
SMB_TMP75_1_3V3AUX_SDA_R R459             2        Q_RES_0402LF-33.2,1%,1/16W,CHIA
SMB_TMP75_1_3V3AUX_SDA_R U63              1        TMP75AIDR-TMP75AIDR,SMLF,IC,ALA
SMB_TMP75_2_3V3AUX_SCL_R R726             2        Q_RES_0402LF-33.2,1%,1/16W,CHIA
SMB_TMP75_2_3V3AUX_SCL_R U65              2        TMP75AIDR-TMP75AIDR,SMLF,IC,ALA
SMB_TMP75_2_3V3AUX_SDA_R R725             2        Q_RES_0402LF-33.2,1%,1/16W,CHIA
SMB_TMP75_2_3V3AUX_SDA_R U65              1        TMP75AIDR-TMP75AIDR,SMLF,IC,ALA
SMB_VR_3V3AUX_SCL        J41              A5       SCONN168_623403212-SCONN168_6-A
SMB_VR_3V3AUX_SCL        R1661            1        Q_RES_0402LF-33,5%,1/16W,CHIP,A
SMB_VR_3V3AUX_SCL        R1731            1        Q_RES_0402LF-2K,1%,1/16W,CHIP,A
SMB_VR_3V3AUX_SCL_R      JP1              3        CONN3_210HP1030BR1-CONN3_210-HA
SMB_VR_3V3AUX_SCL_R      PR115            1        Q_RES_0402LF-0,5%,1/16W,CHIP,CA
SMB_VR_3V3AUX_SCL_R      PR167            1        Q_RES_0402LF-0,5%,1/16W,CHIP,CA
SMB_VR_3V3AUX_SCL_R      PR212            1        Q_RES_0402LF-0,5%,1/16W,CHIP,CA
SMB_VR_3V3AUX_SCL_R      PR268            1        Q_RES_0402LF-0,5%,1/16W,CHIP,CA
SMB_VR_3V3AUX_SCL_R      PR314            1        Q_RES_0402LF-0,5%,1/16W,CHIP,CA
SMB_VR_3V3AUX_SCL_R      PR367            1        Q_RES_0402LF-0,5%,1/16W,CHIP,CA
SMB_VR_3V3AUX_SCL_R      R1661            2        Q_RES_0402LF-33,5%,1/16W,CHIP,A
SMB_VR_3V3AUX_SCL_R      R1713            1        Q_RES_0402LF-1K,1%,1/16W,CHIP,A
SMB_VR_3V3AUX_SDA        J41              A6       SCONN168_623403212-SCONN168_6-A
SMB_VR_3V3AUX_SDA        R1662            1        Q_RES_0402LF-33,5%,1/16W,CHIP,A
SMB_VR_3V3AUX_SDA        R1732            1        Q_RES_0402LF-2K,1%,1/16W,CHIP,A
SMB_VR_3V3AUX_SDA_R      JP1              2        CONN3_210HP1030BR1-CONN3_210-HA
SMB_VR_3V3AUX_SDA_R      PR116            1        Q_RES_0402LF-0,5%,1/16W,CHIP,CA
SMB_VR_3V3AUX_SDA_R      PR168            1        Q_RES_0402LF-0,5%,1/16W,CHIP,CA
SMB_VR_3V3AUX_SDA_R      PR213            1        Q_RES_0402LF-0,5%,1/16W,CHIP,CA
SMB_VR_3V3AUX_SDA_R      PR269            1        Q_RES_0402LF-0,5%,1/16W,CHIP,CA
SMB_VR_3V3AUX_SDA_R      PR315            1        Q_RES_0402LF-0,5%,1/16W,CHIP,CA
SMB_VR_3V3AUX_SDA_R      PR368            1        Q_RES_0402LF-0,5%,1/16W,CHIP,CA
SMB_VR_3V3AUX_SDA_R      R1662            2        Q_RES_0402LF-33,5%,1/16W,CHIP,A
SMB_VR_3V3AUX_SDA_R      R1712            1        Q_RES_0402LF-1K,1%,1/16W,CHIP,A
SPI_PCH_CLK              R499             1        Q_RES_0402LF-33.2,1%,1/16W,CHIA
SPI_PCH_CLK              U4               BB15     EMMITSBURG_REV0P9-GFNOCPU04302A
SPI_PCH_CS0_R_N          R501             1        Q_RES_0402LF-33.2,1%,1/16W,CHIA
SPI_PCH_CS0_R_N          U4               AW13     EMMITSBURG_REV0P9-GFNOCPU04302A
SPI_PCH_CS1_R_N          R500             1        Q_RES_0402LF-33.2,1%,1/16W,CHIA
SPI_PCH_CS1_R_N          U4               BA10     EMMITSBURG_REV0P9-GFNOCPU04302A
SPI_PCH_IO0              R915             1        Q_RES_0402LF-33.2,1%,1/16W,CHIA
SPI_PCH_IO0              U4               BA13     EMMITSBURG_REV0P9-GFNOCPU04302A
SPI_PCH_IO1              R916             1        Q_RES_0402LF-33.2,1%,1/16W,CHIA
SPI_PCH_IO1              U4               AW16     EMMITSBURG_REV0P9-GFNOCPU04302A
SPI_PCH_IO2              R918             1        Q_RES_0402LF-33.2,1%,1/16W,CHIA
SPI_PCH_IO2              U4               AV15     EMMITSBURG_REV0P9-GFNOCPU04302A
SPI_PCH_IO3              R917             1        Q_RES_0402LF-33.2,1%,1/16W,CHIA
SPI_PCH_IO3              U4               BA16     EMMITSBURG_REV0P9-GFNOCPU04302A
SPI_PCH_PFR_CS1_N        J41              B42      SCONN168_623403212-SCONN168_6-A
SPI_PCH_PFR_CS1_N        R500             2        Q_RES_0402LF-33.2,1%,1/16W,CHIA
SPI_PCH_TPM_CS_N         R1395            1        Q_RES_0402LF-33.2,1%,1/16W,CHIA
SPI_PCH_TPM_CS_N         U4               BB11     EMMITSBURG_REV0P9-GFNOCPU04302A
SPI_SYS_CLK              J41              B11      SCONN168_623403212-SCONN168_6-A
SPI_SYS_CLK              R499             2        Q_RES_0402LF-33.2,1%,1/16W,CHIA
SPI_SYS_CS0_N            J41              B12      SCONN168_623403212-SCONN168_6-A
SPI_SYS_CS0_N            R501             2        Q_RES_0402LF-33.2,1%,1/16W,CHIA
SPI_SYS_HOLD_IO3         J41              B16      SCONN168_623403212-SCONN168_6-A
SPI_SYS_HOLD_IO3         R917             2        Q_RES_0402LF-33.2,1%,1/16W,CHIA
SPI_SYS_MISO             J41              B14      SCONN168_623403212-SCONN168_6-A
SPI_SYS_MISO             R916             2        Q_RES_0402LF-33.2,1%,1/16W,CHIA
SPI_SYS_MOSI             J41              B13      SCONN168_623403212-SCONN168_6-A
SPI_SYS_MOSI             R915             2        Q_RES_0402LF-33.2,1%,1/16W,CHIA
SPI_SYS_WP_IO2           J41              B15      SCONN168_623403212-SCONN168_6-A
SPI_SYS_WP_IO2           R918             2        Q_RES_0402LF-33.2,1%,1/16W,CHIA
SPI_TPM_CS_N             J41              OCP_B12  SCONN168_623403212-SCONN168_6-A
SPI_TPM_CS_N             R1395            2        Q_RES_0402LF-33.2,1%,1/16W,CHIA
SVID_ALERT0_CPU0_N       R14              1        Q_RES_0402LF-200,1%,1/16W,CHIPA
SVID_ALERT0_CPU0_N       U2               BK26     SOCKET4677_AZIFS054P001C01-SOCA
SVID_ALERT0_CPU0_R_N     PR114            1        Q_RES_0402LF-0,5%,1/16W,CHIP,CA
SVID_ALERT0_CPU0_R_N     PR165            1        Q_RES_0402LF-0,5%,1/16W,CHIP,CA
SVID_ALERT0_CPU0_R_N     PR530            1        Q_RES_0402LF-49.9     ,1%  ,1/B
SVID_ALERT0_CPU0_R_N     R14              2        Q_RES_0402LF-200,1%,1/16W,CHIPA
SVID_ALERT0_CPU0_R_N     R548             1        Q_RES_0402LF-49.9     ,1%  ,1/A
SVID_ALERT0_CPU1_N       R57              1        Q_RES_0402LF-200,1%,1/16W,CHIPA
SVID_ALERT0_CPU1_N       U1               BK26     SOCKET4677_AZIFS054P001C01-SOCA
SVID_ALERT0_CPU1_R_N     PR267            1        Q_RES_0402LF-0,5%,1/16W,CHIP,CA
SVID_ALERT0_CPU1_R_N     PR312            1        Q_RES_0402LF-0,5%,1/16W,CHIP,CA
SVID_ALERT0_CPU1_R_N     PR577            1        Q_RES_0402LF-49.9     ,1%  ,1/B
SVID_ALERT0_CPU1_R_N     R57              2        Q_RES_0402LF-200,1%,1/16W,CHIPA
SVID_ALERT0_CPU1_R_N     R558             1        Q_RES_0402LF-49.9     ,1%  ,1/A
SVID_ALERT1_CPU0_N       R17              1        Q_RES_0402LF-200,1%,1/16W,CHIPA
SVID_ALERT1_CPU0_N       U2               BJ25     SOCKET4677_AZIFS054P001C01-SOCA
SVID_ALERT1_CPU0_R_N     PR366            1        Q_RES_0402LF-0,5%,1/16W,CHIP,CA
SVID_ALERT1_CPU0_R_N     R17              2        Q_RES_0402LF-200,1%,1/16W,CHIPA
SVID_ALERT1_CPU0_R_N     R556             1        Q_RES_0402LF-49.9     ,1%  ,1/A
SVID_ALERT1_CPU1_N       R60              1        Q_RES_0402LF-200,1%,1/16W,CHIPA
SVID_ALERT1_CPU1_N       U1               BJ25     SOCKET4677_AZIFS054P001C01-SOCA
SVID_ALERT1_CPU1_R_N     PR211            1        Q_RES_0402LF-0,5%,1/16W,CHIP,CA
SVID_ALERT1_CPU1_R_N     R60              2        Q_RES_0402LF-200,1%,1/16W,CHIPA
SVID_ALERT1_CPU1_R_N     R560             1        Q_RES_0402LF-49.9     ,1%  ,1/A
SVID_ALERT_PVCCD_HV_CPU0_R PR366            2        Q_RES_0402LF-0,5%,1/16W,CHIP,CA
SVID_ALERT_PVCCD_HV_CPU0_R PU35             19       ISL69260IRAZT-ISL69260IRAZ-T,SA
SVID_ALERT_PVCCD_HV_CPU1_R PR211            2        Q_RES_0402LF-0,5%,1/16W,CHIP,CA
SVID_ALERT_PVCCD_HV_CPU1_R PU18             19       ISL69260IRAZT-ISL69260IRAZ-T,SA
SVID_ALERT_PVCCINFAON_CPU0_R PR114            2        Q_RES_0402LF-0,5%,1/16W,CHIP,CA
SVID_ALERT_PVCCINFAON_CPU0_R PU5              19       ISL69260IRAZT-ISL69260IRAZ-T,SA
SVID_ALERT_PVCCINFAON_CPU1_R PR267            2        Q_RES_0402LF-0,5%,1/16W,CHIP,CA
SVID_ALERT_PVCCINFAON_CPU1_R PU22             19       ISL69260IRAZT-ISL69260IRAZ-T,SA
SVID_ALERT_PVCCIN_CPU0_R PR165            2        Q_RES_0402LF-0,5%,1/16W,CHIP,CA
SVID_ALERT_PVCCIN_CPU0_R PU14             23       RAA229126GNPHA0-RAA229126GNP#HA
SVID_ALERT_PVCCIN_CPU1_R PR312            2        Q_RES_0402LF-0,5%,1/16W,CHIP,CA
SVID_ALERT_PVCCIN_CPU1_R PU29             23       RAA229126GNPHA0-RAA229126GNP#HA
SVID_CLK0_CPU0           R13              1        Q_RES_0402LF-0,5%,1/16W,CHIP,CA
SVID_CLK0_CPU0           U2               BH26     SOCKET4677_AZIFS054P001C01-SOCA
SVID_CLK0_CPU0_R         PR112            1        Q_RES_0402LF-150,1%,1/16W,CHIPA
SVID_CLK0_CPU0_R         PR163            1        Q_RES_0402LF-150,1%,1/16W,CHIPA
SVID_CLK0_CPU0_R         PR529            1        Q_RES_0402LF-49.9     ,1%  ,1/A
SVID_CLK0_CPU0_R         R13              2        Q_RES_0402LF-0,5%,1/16W,CHIP,CA
SVID_CLK0_CPU0_R         R2322            2        Q_RES_0402LF-49.9     ,1%  ,1/B
SVID_CLK0_CPU1           R56              1        Q_RES_0402LF-0,5%,1/16W,CHIP,CA
SVID_CLK0_CPU1           U1               BH26     SOCKET4677_AZIFS054P001C01-SOCA
SVID_CLK0_CPU1_R         PR265            1        Q_RES_0402LF-150,1%,1/16W,CHIPA
SVID_CLK0_CPU1_R         PR310            1        Q_RES_0402LF-150,1%,1/16W,CHIPA
SVID_CLK0_CPU1_R         PR576            1        Q_RES_0402LF-49.9     ,1%  ,1/A
SVID_CLK0_CPU1_R         R56              2        Q_RES_0402LF-0,5%,1/16W,CHIP,CA
SVID_CLK0_CPU1_R         R2345            2        Q_RES_0402LF-49.9     ,1%  ,1/B
SVID_CLK1_CPU0           R16              1        Q_RES_0402LF-0,5%,1/16W,CHIP,CA
SVID_CLK1_CPU0           U2               BF26     SOCKET4677_AZIFS054P001C01-SOCA
SVID_CLK1_CPU0_R         PR364            1        Q_RES_0402LF-150,1%,1/16W,CHIPA
SVID_CLK1_CPU0_R         R16              2        Q_RES_0402LF-0,5%,1/16W,CHIP,CA
SVID_CLK1_CPU0_R         R1717            2        Q_RES_0402LF-49.9     ,1%  ,1/A
SVID_CLK1_CPU1           R59              1        Q_RES_0402LF-0,5%,1/16W,CHIP,CA
SVID_CLK1_CPU1           U1               BF26     SOCKET4677_AZIFS054P001C01-SOCA
SVID_CLK1_CPU1_R         PR209            1        Q_RES_0402LF-150,1%,1/16W,CHIPA
SVID_CLK1_CPU1_R         PR1718           2        Q_RES_0402LF-49.9     ,1%  ,1/A
SVID_CLK1_CPU1_R         R59              2        Q_RES_0402LF-0,5%,1/16W,CHIP,CA
SVID_CLK_PVCCD_HV_CPU0_R PR364            2        Q_RES_0402LF-150,1%,1/16W,CHIPA
SVID_CLK_PVCCD_HV_CPU0_R PU35             17       ISL69260IRAZT-ISL69260IRAZ-T,SA
SVID_CLK_PVCCD_HV_CPU1_R PR209            2        Q_RES_0402LF-150,1%,1/16W,CHIPA
SVID_CLK_PVCCD_HV_CPU1_R PU18             17       ISL69260IRAZT-ISL69260IRAZ-T,SA
SVID_CLK_PVCCINFAON_CPU0_R PR112            2        Q_RES_0402LF-150,1%,1/16W,CHIPA
SVID_CLK_PVCCINFAON_CPU0_R PU5              17       ISL69260IRAZT-ISL69260IRAZ-T,SA
SVID_CLK_PVCCINFAON_CPU1_R PR265            2        Q_RES_0402LF-150,1%,1/16W,CHIPA
SVID_CLK_PVCCINFAON_CPU1_R PU22             17       ISL69260IRAZT-ISL69260IRAZ-T,SA
SVID_CLK_PVCCIN_CPU0_R   PR163            2        Q_RES_0402LF-150,1%,1/16W,CHIPA
SVID_CLK_PVCCIN_CPU0_R   PU14             21       RAA229126GNPHA0-RAA229126GNP#HA
SVID_CLK_PVCCIN_CPU1_R   PR310            2        Q_RES_0402LF-150,1%,1/16W,CHIPA
SVID_CLK_PVCCIN_CPU1_R   PU29             21       RAA229126GNPHA0-RAA229126GNP#HA
SVID_DIO0_CPU0           R12              1        Q_RES_0402LF-0,5%,1/16W,CHIP,CA
SVID_DIO0_CPU0           U2               BD26     SOCKET4677_AZIFS054P001C01-SOCA
SVID_DIO0_CPU0_R         PR113            1        Q_RES_0402LF-0,5%,1/16W,CHIP,CA
SVID_DIO0_CPU0_R         PR164            1        Q_RES_0402LF-0,5%,1/16W,CHIP,CA
SVID_DIO0_CPU0_R         PR528            1        Q_RES_0402LF-100,1%,1/16W,CHIPA
SVID_DIO0_CPU0_R         R12              2        Q_RES_0402LF-0,5%,1/16W,CHIP,CA
SVID_DIO0_CPU0_R         R328             1        Q_RES_0402LF-100,1%,1/16W,CHIPA
SVID_DIO0_CPU0_R         R561             2        Q_RES_0402LF-100,1%,1/16W,EMPTA
SVID_DIO0_CPU1           R55              1        Q_RES_0402LF-0,5%,1/16W,CHIP,CA
SVID_DIO0_CPU1           U1               BD26     SOCKET4677_AZIFS054P001C01-SOCA
SVID_DIO0_CPU1_R         PR266            1        Q_RES_0402LF-0,5%,1/16W,CHIP,CA
SVID_DIO0_CPU1_R         PR311            1        Q_RES_0402LF-0,5%,1/16W,CHIP,CA
SVID_DIO0_CPU1_R         PR575            1        Q_RES_0402LF-100,1%,1/16W,CHIPA
SVID_DIO0_CPU1_R         R55              2        Q_RES_0402LF-0,5%,1/16W,CHIP,CA
SVID_DIO0_CPU1_R         R557             1        Q_RES_0402LF-100,1%,1/16W,CHIPA
SVID_DIO0_CPU1_R         R2354            2        Q_RES_0402LF-100,1%,1/16W,EMPTA
SVID_DIO1_CPU0           R15              1        Q_RES_0402LF-0,5%,1/16W,CHIP,CA
SVID_DIO1_CPU0           U2               BL25     SOCKET4677_AZIFS054P001C01-SOCA
SVID_DIO1_CPU0_R         PR365            1        Q_RES_0402LF-0,5%,1/16W,CHIP,CA
SVID_DIO1_CPU0_R         R15              2        Q_RES_0402LF-0,5%,1/16W,CHIP,CA
SVID_DIO1_CPU0_R         R555             1        Q_RES_0402LF-100,1%,1/16W,CHIPA
SVID_DIO1_CPU0_R         R1735            2        Q_RES_0402LF-100,1%,1/16W,CHIPA
SVID_DIO1_CPU1           R58              1        Q_RES_0402LF-0,5%,1/16W,CHIP,CA
SVID_DIO1_CPU1           U1               BL25     SOCKET4677_AZIFS054P001C01-SOCA
SVID_DIO1_CPU1_R         PR210            1        Q_RES_0402LF-0,5%,1/16W,CHIP,CA
SVID_DIO1_CPU1_R         PR1747           2        Q_RES_0402LF-100,1%,1/16W,CHIPA
SVID_DIO1_CPU1_R         R58              2        Q_RES_0402LF-0,5%,1/16W,CHIP,CA
SVID_DIO1_CPU1_R         R559             1        Q_RES_0402LF-100,1%,1/16W,CHIPA
SVID_DIO_PVCCD_HV_CPU0_R PR365            2        Q_RES_0402LF-0,5%,1/16W,CHIP,CA
SVID_DIO_PVCCD_HV_CPU0_R PU35             18       ISL69260IRAZT-ISL69260IRAZ-T,SA
SVID_DIO_PVCCD_HV_CPU1_R PR210            2        Q_RES_0402LF-0,5%,1/16W,CHIP,CA
SVID_DIO_PVCCD_HV_CPU1_R PU18             18       ISL69260IRAZT-ISL69260IRAZ-T,SA
SVID_DIO_PVCCINFAON_CPU0_R PR113            2        Q_RES_0402LF-0,5%,1/16W,CHIP,CA
SVID_DIO_PVCCINFAON_CPU0_R PU5              18       ISL69260IRAZT-ISL69260IRAZ-T,SA
SVID_DIO_PVCCINFAON_CPU1_R PR266            2        Q_RES_0402LF-0,5%,1/16W,CHIP,CA
SVID_DIO_PVCCINFAON_CPU1_R PU22             18       ISL69260IRAZT-ISL69260IRAZ-T,SA
SVID_DIO_PVCCIN_CPU0_R   PR164            2        Q_RES_0402LF-0,5%,1/16W,CHIP,CA
SVID_DIO_PVCCIN_CPU0_R   PU14             22       RAA229126GNPHA0-RAA229126GNP#HA
SVID_DIO_PVCCIN_CPU1_R   PR311            2        Q_RES_0402LF-0,5%,1/16W,CHIP,CA
SVID_DIO_PVCCIN_CPU1_R   PU29             22       RAA229126GNPHA0-RAA229126GNP#HA
SW_P12V_AUX_P1V05_PCH_AUX_FLT PC1215           1        Q_CAPP_SMLF-100UF,16V,20%,OSCOA
SW_P12V_AUX_P1V05_PCH_AUX_FLT PC1216           1        Q_CAP_C0805-22UF,16V,20%,X6S,CA
SW_P12V_AUX_P1V05_PCH_AUX_FLT PC1217           1        Q_CAP_C0805-22UF,16V,20%,X6S,CA
SW_P12V_AUX_P1V05_PCH_AUX_FLT PC1218           1        Q_CAP_C0805-22UF,16V,20%,X6S,CA
SW_P12V_AUX_P1V05_PCH_AUX_FLT PC1219           1        Q_CAP_0402-0.1UF,25V,10%,X7R,CA
SW_P12V_AUX_P1V05_PCH_AUX_FLT PL110            2        Q_INDUCTOR_SMLF-100NH/16A,IND,A
SW_P12V_AUX_P1V05_PCH_AUX_FLT PU73             10       MPQ8633BGLEC838Z-MPQ8633BGLE-CA
SW_P12V_AUX_P1V05_PCH_AUX_FLT PU73             21       MPQ8633BGLEC838Z-MPQ8633BGLE-CA
SW_P12V_PVCCFA_EHV_FIVRA_CPU0_L PC1174_P0_4      1        Q_CAP_0402-3300PF,50V,10%,EMPTA
SW_P12V_PVCCFA_EHV_FIVRA_CPU0_L PC1176_P0_4      1        Q_CAP_C0402-1UF,16V,10%,EMPTY,A
SW_P12V_PVCCFA_EHV_FIVRA_CPU0_L PC1180_P0_4      1        Q_CAP_C0805-22UF,16V,20%,EMPTYA
SW_P12V_PVCCFA_EHV_FIVRA_CPU0_L PC1182_P0_4      1        Q_CAP_C0805-22UF,16V,20%,EMPTYA
SW_P12V_PVCCFA_EHV_FIVRA_CPU0_L PC603_P0_2       1        Q_CAP_0402-3300PF,50V,10%,X7R,A
SW_P12V_PVCCFA_EHV_FIVRA_CPU0_L PC605_P0_2       1        Q_CAP_C0402-1UF,16V,10%,X6S,CHA
SW_P12V_PVCCFA_EHV_FIVRA_CPU0_L PC609_P0_2       1        Q_CAP_C0805-22UF,16V,20%,X6S,CA
SW_P12V_PVCCFA_EHV_FIVRA_CPU0_L PC611_P0_2       1        Q_CAP_C0805-22UF,16V,20%,X6S,CA
SW_P12V_PVCCFA_EHV_FIVRA_CPU0_L PC622            1        Q_CAPP_THLF-270UF,16V,20%,OSCOA
SW_P12V_PVCCFA_EHV_FIVRA_CPU0_L PC721_P0_2       1        Q_CAP_C0805-22UF,16V,20%,X6S,CA
SW_P12V_PVCCFA_EHV_FIVRA_CPU0_L PC723_P0_4       1        Q_CAP_C0805-22UF,16V,20%,EMPTYA
SW_P12V_PVCCFA_EHV_FIVRA_CPU0_L PL44             2        Q_INDUCTOR_SMLF-100NH/16A,IND,A
SW_P12V_PVCCFA_EHV_FIVRA_CPU0_L PU70_P0_2        25_29    ISL99390FRZTR5935-ISL99390FRZ-A
SW_P12V_PVCCFA_EHV_FIVRA_CPU0_L PU70_P0_2        30       ISL99390FRZTR5935-ISL99390FRZ-A
SW_P12V_PVCCFA_EHV_FIVRA_CPU0_L PU72_P0_4        25_29    ISL99390FRZTR5935-ISL99390FRZ-B
SW_P12V_PVCCFA_EHV_FIVRA_CPU0_L PU72_P0_4        30       ISL99390FRZTR5935-ISL99390FRZ-B
SW_P12V_PVCCFA_EHV_FIVRA_CPU0_R PC1173_P0_3      1        Q_CAP_0402-3300PF,50V,10%,EMPTA
SW_P12V_PVCCFA_EHV_FIVRA_CPU0_R PC1175_P0_3      1        Q_CAP_C0402-1UF,16V,10%,EMPTY,A
SW_P12V_PVCCFA_EHV_FIVRA_CPU0_R PC1179_P0_3      1        Q_CAP_C0805-22UF,16V,20%,EMPTYA
SW_P12V_PVCCFA_EHV_FIVRA_CPU0_R PC1181_P0_3      1        Q_CAP_C0805-22UF,16V,20%,EMPTYA
SW_P12V_PVCCFA_EHV_FIVRA_CPU0_R PC1189           1        Q_CAPP_THLF-270UF,16V,20%,OSCOA
SW_P12V_PVCCFA_EHV_FIVRA_CPU0_R PC602_P0_1       1        Q_CAP_0402-3300PF,50V,10%,X7R,A
SW_P12V_PVCCFA_EHV_FIVRA_CPU0_R PC604_P0_1       1        Q_CAP_C0402-1UF,16V,10%,X6S,CHA
SW_P12V_PVCCFA_EHV_FIVRA_CPU0_R PC608_P0_1       1        Q_CAP_C0805-22UF,16V,20%,X6S,CA
SW_P12V_PVCCFA_EHV_FIVRA_CPU0_R PC610_P0_1       1        Q_CAP_C0805-22UF,16V,20%,X6S,CA
SW_P12V_PVCCFA_EHV_FIVRA_CPU0_R PC720_P0_1       1        Q_CAP_C0805-22UF,16V,20%,X6S,CA
SW_P12V_PVCCFA_EHV_FIVRA_CPU0_R PC722_P0_3       1        Q_CAP_C0805-22UF,16V,20%,EMPTYA
SW_P12V_PVCCFA_EHV_FIVRA_CPU0_R PL101            2        Q_INDUCTOR_SMLF-100NH/16A,IND,A
SW_P12V_PVCCFA_EHV_FIVRA_CPU0_R PU69_P0_1        25_29    ISL99390FRZTR5935-ISL99390FRZ-A
SW_P12V_PVCCFA_EHV_FIVRA_CPU0_R PU69_P0_1        30       ISL99390FRZTR5935-ISL99390FRZ-A
SW_P12V_PVCCFA_EHV_FIVRA_CPU0_R PU71_P0_3        25_29    ISL99390FRZTR5935-ISL99390FRZ-B
SW_P12V_PVCCFA_EHV_FIVRA_CPU0_R PU71_P0_3        30       ISL99390FRZTR5935-ISL99390FRZ-B
SW_P12V_PVCCFA_EHV_FIVRA_CPU1_L PC1194_P1_4      1        Q_CAP_0402-3300PF,50V,10%,X7R,A
SW_P12V_PVCCFA_EHV_FIVRA_CPU1_L PC1196_P1_4      1        Q_CAP_C0402-1UF,16V,10%,X6S,CHA
SW_P12V_PVCCFA_EHV_FIVRA_CPU1_L PC1200_P1_4      1        Q_CAP_C0805-22UF,16V,20%,X6S,CA
SW_P12V_PVCCFA_EHV_FIVRA_CPU1_L PC1202_P1_4      1        Q_CAP_C0805-22UF,16V,20%,X6S,CA
SW_P12V_PVCCFA_EHV_FIVRA_CPU1_L PC398_P1_2       1        Q_CAP_0402-3300PF,50V,10%,X7R,A
SW_P12V_PVCCFA_EHV_FIVRA_CPU1_L PC400_P1_2       1        Q_CAP_C0402-1UF,16V,10%,X6S,CHA
SW_P12V_PVCCFA_EHV_FIVRA_CPU1_L PC404_P1_2       1        Q_CAP_C0805-22UF,16V,20%,X6S,CA
SW_P12V_PVCCFA_EHV_FIVRA_CPU1_L PC406_P1_2       1        Q_CAP_C0805-22UF,16V,20%,X6S,CA
SW_P12V_PVCCFA_EHV_FIVRA_CPU1_L PC417            1        Q_CAPP_THLF-270UF,16V,20%,OSCOA
SW_P12V_PVCCFA_EHV_FIVRA_CPU1_L PC725_P1_2       1        Q_CAP_C0805-22UF,16V,20%,X6S,CA
SW_P12V_PVCCFA_EHV_FIVRA_CPU1_L PC727_P1_4       1        Q_CAP_C0805-22UF,16V,20%,X6S,CA
SW_P12V_PVCCFA_EHV_FIVRA_CPU1_L PL43             2        Q_INDUCTOR_SMLF-100NH/16A,IND,A
SW_P12V_PVCCFA_EHV_FIVRA_CPU1_L PU76_P1_2        25_29    ISL99390FRZTR5935-ISL99390FRZ-A
SW_P12V_PVCCFA_EHV_FIVRA_CPU1_L PU76_P1_2        30       ISL99390FRZTR5935-ISL99390FRZ-A
SW_P12V_PVCCFA_EHV_FIVRA_CPU1_L PU78_P1_4        25_29    ISL99390FRZTR5935-ISL99390FRZ-A
SW_P12V_PVCCFA_EHV_FIVRA_CPU1_L PU78_P1_4        30       ISL99390FRZTR5935-ISL99390FRZ-A
SW_P12V_PVCCFA_EHV_FIVRA_CPU1_R PC1193_P1_3      1        Q_CAP_0402-3300PF,50V,10%,X7R,A
SW_P12V_PVCCFA_EHV_FIVRA_CPU1_R PC1195_P1_3      1        Q_CAP_C0402-1UF,16V,10%,X6S,CHA
SW_P12V_PVCCFA_EHV_FIVRA_CPU1_R PC1199_P1_3      1        Q_CAP_C0805-22UF,16V,20%,X6S,CA
SW_P12V_PVCCFA_EHV_FIVRA_CPU1_R PC1201_P1_3      1        Q_CAP_C0805-22UF,16V,20%,X6S,CA
SW_P12V_PVCCFA_EHV_FIVRA_CPU1_R PC1210           1        Q_CAPP_THLF-270UF,16V,20%,OSCOA
SW_P12V_PVCCFA_EHV_FIVRA_CPU1_R PC397_P1_1       1        Q_CAP_0402-3300PF,50V,10%,X7R,A
SW_P12V_PVCCFA_EHV_FIVRA_CPU1_R PC399_P1_1       1        Q_CAP_C0402-1UF,16V,10%,X6S,CHA
SW_P12V_PVCCFA_EHV_FIVRA_CPU1_R PC403_P1_1       1        Q_CAP_C0805-22UF,16V,20%,X6S,CA
SW_P12V_PVCCFA_EHV_FIVRA_CPU1_R PC405_P1_1       1        Q_CAP_C0805-22UF,16V,20%,X6S,CA
SW_P12V_PVCCFA_EHV_FIVRA_CPU1_R PC724_P1_1       1        Q_CAP_C0805-22UF,16V,20%,X6S,CA
SW_P12V_PVCCFA_EHV_FIVRA_CPU1_R PC726_P1_3       1        Q_CAP_C0805-22UF,16V,20%,X6S,CA
SW_P12V_PVCCFA_EHV_FIVRA_CPU1_R PL14             2        Q_INDUCTOR_SMLF-100NH/16A,IND,A
SW_P12V_PVCCFA_EHV_FIVRA_CPU1_R PU75_P1_1        25_29    ISL99390FRZTR5935-ISL99390FRZ-A
SW_P12V_PVCCFA_EHV_FIVRA_CPU1_R PU75_P1_1        30       ISL99390FRZTR5935-ISL99390FRZ-A
SW_P12V_PVCCFA_EHV_FIVRA_CPU1_R PU77_P1_3        25_29    ISL99390FRZTR5935-ISL99390FRZ-A
SW_P12V_PVCCFA_EHV_FIVRA_CPU1_R PU77_P1_3        30       ISL99390FRZTR5935-ISL99390FRZ-A
SW_P12V_PVCCINFAON_CPU0_FLT PC176            1        Q_CAP_0402-3300PF,50V,10%,X7R,A
SW_P12V_PVCCINFAON_CPU0_FLT PC177            1        Q_CAP_C0402-1UF,16V,10%,X6S,CHA
SW_P12V_PVCCINFAON_CPU0_FLT PC179            1        Q_CAP_C0805-22UF,16V,20%,X6S,CA
SW_P12V_PVCCINFAON_CPU0_FLT PC180            1        Q_CAP_C0805-22UF,16V,20%,X6S,CA
SW_P12V_PVCCINFAON_CPU0_FLT PC1272           1        Q_CAP_C0805-22UF,16V,20%,X6S,CA
SW_P12V_PVCCINFAON_CPU0_FLT PC1273           1        Q_CAP_C0805-22UF,16V,20%,X6S,CA
SW_P12V_PVCCINFAON_CPU0_FLT PC1274           1        Q_CAP_C0402-100NF,50V,10%,X7R,A
SW_P12V_PVCCINFAON_CPU0_FLT PC189_P0_1       1        Q_CAP_0402-3300PF,50V,10%,X7R,A
SW_P12V_PVCCINFAON_CPU0_FLT PC190_P0_2       1        Q_CAP_0402-3300PF,50V,10%,X7R,A
SW_P12V_PVCCINFAON_CPU0_FLT PC191_P0_1       1        Q_CAP_C0402-1UF,16V,10%,X6S,CHA
SW_P12V_PVCCINFAON_CPU0_FLT PC192_P0_2       1        Q_CAP_C0402-1UF,16V,10%,X6S,CHA
SW_P12V_PVCCINFAON_CPU0_FLT PC195_P0_1       1        Q_CAP_C0805-22UF,16V,20%,X6S,CA
SW_P12V_PVCCINFAON_CPU0_FLT PC196_P0_2       1        Q_CAP_C0805-22UF,16V,20%,X6S,CA
SW_P12V_PVCCINFAON_CPU0_FLT PC197_P0_1       1        Q_CAP_C0805-22UF,16V,20%,X6S,CA
SW_P12V_PVCCINFAON_CPU0_FLT PC198_P0_2       1        Q_CAP_C0805-22UF,16V,20%,X6S,CA
SW_P12V_PVCCINFAON_CPU0_FLT PC207            1        Q_CAPP_THLF-270UF,16V,20%,OSCOA
SW_P12V_PVCCINFAON_CPU0_FLT PC208            1        Q_CAPP_THLF-270UF,16V,20%,OSCOA
SW_P12V_PVCCINFAON_CPU0_FLT PC634            1        Q_CAP_0402-3300PF,50V,10%,X7R,A
SW_P12V_PVCCINFAON_CPU0_FLT PC635            1        Q_CAP_C0402-1UF,16V,10%,X6S,CHA
SW_P12V_PVCCINFAON_CPU0_FLT PC637            1        Q_CAP_C0805-22UF,16V,20%,X6S,CA
SW_P12V_PVCCINFAON_CPU0_FLT PC638            1        Q_CAP_C0805-22UF,16V,20%,X6S,CA
SW_P12V_PVCCINFAON_CPU0_FLT PL6              2        Q_INDUCTOR_SMLF-100NH/16A,IND,A
SW_P12V_PVCCINFAON_CPU0_FLT PU36             16_18-28 RAA2213404GNPHB0-RAA2213404GNPA
SW_P12V_PVCCINFAON_CPU0_FLT PU42             16_18-28 RAA2213404GNPHB0-RAA2213404GNPA
SW_P12V_PVCCINFAON_CPU0_FLT PU43_P0_1        16_18-28 RAA2213404GNPHB0-RAA2213404GNPA
SW_P12V_PVCCINFAON_CPU0_FLT PU44_P0_2        16_18-28 RAA2213404GNPHB0-RAA2213404GNPA
SW_P12V_PVCCINFAON_CPU0_FLT PU81             3        MPQ8626GDZ-MPQ8626GD-Z,SMLF,ICA
SW_P12V_PVCCINFAON_CPU1_FLT PC374            1        Q_CAP_0402-3300PF,50V,10%,X7R,A
SW_P12V_PVCCINFAON_CPU1_FLT PC375            1        Q_CAP_C0402-1UF,16V,10%,X6S,CHA
SW_P12V_PVCCINFAON_CPU1_FLT PC377            1        Q_CAP_C0805-22UF,16V,20%,X6S,CA
SW_P12V_PVCCINFAON_CPU1_FLT PC378            1        Q_CAP_C0805-22UF,16V,20%,X6S,CA
SW_P12V_PVCCINFAON_CPU1_FLT PC429            1        Q_CAP_0402-3300PF,50V,10%,X7R,A
SW_P12V_PVCCINFAON_CPU1_FLT PC430            1        Q_CAP_C0402-1UF,16V,10%,X6S,CHA
SW_P12V_PVCCINFAON_CPU1_FLT PC432            1        Q_CAP_C0805-22UF,16V,20%,X6S,CA
SW_P12V_PVCCINFAON_CPU1_FLT PC433            1        Q_CAP_C0805-22UF,16V,20%,X6S,CA
SW_P12V_PVCCINFAON_CPU1_FLT PC1280           1        Q_CAP_C0805-22UF,16V,20%,X6S,CA
SW_P12V_PVCCINFAON_CPU1_FLT PC1281           1        Q_CAP_C0805-22UF,16V,20%,X6S,CA
SW_P12V_PVCCINFAON_CPU1_FLT PC1282           1        Q_CAP_C0402-100NF,50V,10%,X7R,A
SW_P12V_PVCCINFAON_CPU1_FLT PC442_P1_1       1        Q_CAP_0402-3300PF,50V,10%,X7R,A
SW_P12V_PVCCINFAON_CPU1_FLT PC443_P1_2       1        Q_CAP_0402-3300PF,50V,10%,X7R,A
SW_P12V_PVCCINFAON_CPU1_FLT PC444_P1_1       1        Q_CAP_C0402-1UF,16V,10%,X6S,CHA
SW_P12V_PVCCINFAON_CPU1_FLT PC445_P1_2       1        Q_CAP_C0402-1UF,16V,10%,X6S,CHA
SW_P12V_PVCCINFAON_CPU1_FLT PC448_P1_1       1        Q_CAP_C0805-22UF,16V,20%,X6S,CA
SW_P12V_PVCCINFAON_CPU1_FLT PC449_P1_2       1        Q_CAP_C0805-22UF,16V,20%,X6S,CA
SW_P12V_PVCCINFAON_CPU1_FLT PC450_P1_1       1        Q_CAP_C0805-22UF,16V,20%,X6S,CA
SW_P12V_PVCCINFAON_CPU1_FLT PC451_P1_2       1        Q_CAP_C0805-22UF,16V,20%,X6S,CA
SW_P12V_PVCCINFAON_CPU1_FLT PC460            1        Q_CAPP_THLF-270UF,16V,20%,OSCOA
SW_P12V_PVCCINFAON_CPU1_FLT PC461            1        Q_CAPP_THLF-270UF,16V,20%,OSCOA
SW_P12V_PVCCINFAON_CPU1_FLT PL23             2        Q_INDUCTOR_SMLF-100NH/16A,IND,A
SW_P12V_PVCCINFAON_CPU1_FLT PU17             16_18-28 RAA2213404GNPHB0-RAA2213404GNPA
SW_P12V_PVCCINFAON_CPU1_FLT PU49             16_18-28 RAA2213404GNPHB0-RAA2213404GNPA
SW_P12V_PVCCINFAON_CPU1_FLT PU50_P1_1        16_18-28 RAA2213404GNPHB0-RAA2213404GNPA
SW_P12V_PVCCINFAON_CPU1_FLT PU51_P1_2        16_18-28 RAA2213404GNPHB0-RAA2213404GNPA
SW_P12V_PVCCINFAON_CPU1_FLT PU82             3        MPQ8626GDZ-MPQ8626GD-Z,SMLF,ICA
SW_P12V_PVCCIN_CPU0_FLT  PC230_P0_8       1        Q_CAP_0402-3300PF,50V,10%,X7R,A
SW_P12V_PVCCIN_CPU0_FLT  PC231_P0_7       1        Q_CAP_0402-3300PF,50V,10%,X7R,A
SW_P12V_PVCCIN_CPU0_FLT  PC232_P0_8       1        Q_CAP_C0402-1UF,16V,10%,X6S,CHA
SW_P12V_PVCCIN_CPU0_FLT  PC233_P0_7       1        Q_CAP_C0402-1UF,16V,10%,X6S,CHA
SW_P12V_PVCCIN_CPU0_FLT  PC236_P0_8       1        Q_CAP_C0805-22UF,16V,20%,X6S,CA
SW_P12V_PVCCIN_CPU0_FLT  PC237_P0_7       1        Q_CAP_C0805-22UF,16V,20%,X6S,CA
SW_P12V_PVCCIN_CPU0_FLT  PC238_P0_8       1        Q_CAP_C0805-22UF,16V,20%,X6S,CA
SW_P12V_PVCCIN_CPU0_FLT  PC239_P0_7       1        Q_CAP_C0805-22UF,16V,20%,X6S,CA
SW_P12V_PVCCIN_CPU0_FLT  PC240_P0_8       1        Q_CAP_C0805-22UF,16V,20%,X6S,CA
SW_P12V_PVCCIN_CPU0_FLT  PC241_P0_7       1        Q_CAP_C0805-22UF,16V,20%,X6S,CA
SW_P12V_PVCCIN_CPU0_FLT  PC252_P0_6       1        Q_CAP_0402-3300PF,50V,10%,X7R,A
SW_P12V_PVCCIN_CPU0_FLT  PC253_P0_5       1        Q_CAP_0402-3300PF,50V,10%,X7R,A
SW_P12V_PVCCIN_CPU0_FLT  PC254_P0_6       1        Q_CAP_C0402-1UF,16V,10%,X6S,CHA
SW_P12V_PVCCIN_CPU0_FLT  PC255_P0_5       1        Q_CAP_C0402-1UF,16V,10%,X6S,CHA
SW_P12V_PVCCIN_CPU0_FLT  PC258_P0_6       1        Q_CAP_C0805-22UF,16V,20%,X6S,CA
SW_P12V_PVCCIN_CPU0_FLT  PC259_P0_5       1        Q_CAP_C0805-22UF,16V,20%,X6S,CA
SW_P12V_PVCCIN_CPU0_FLT  PC260_P0_6       1        Q_CAP_C0805-22UF,16V,20%,X6S,CA
SW_P12V_PVCCIN_CPU0_FLT  PC261_P0_5       1        Q_CAP_C0805-22UF,16V,20%,X6S,CA
SW_P12V_PVCCIN_CPU0_FLT  PC262_P0_6       1        Q_CAP_C0805-22UF,16V,20%,X6S,CA
SW_P12V_PVCCIN_CPU0_FLT  PC263_P0_5       1        Q_CAP_C0805-22UF,16V,20%,X6S,CA
SW_P12V_PVCCIN_CPU0_FLT  PC274_P0_4       1        Q_CAP_0402-3300PF,50V,10%,X7R,A
SW_P12V_PVCCIN_CPU0_FLT  PC275_P0_3       1        Q_CAP_0402-3300PF,50V,10%,X7R,A
SW_P12V_PVCCIN_CPU0_FLT  PC276_P0_4       1        Q_CAP_C0402-1UF,16V,10%,X6S,CHA
SW_P12V_PVCCIN_CPU0_FLT  PC277_P0_3       1        Q_CAP_C0402-1UF,16V,10%,X6S,CHA
SW_P12V_PVCCIN_CPU0_FLT  PC280_P0_4       1        Q_CAP_C0805-22UF,16V,20%,X6S,CA
SW_P12V_PVCCIN_CPU0_FLT  PC281_P0_3       1        Q_CAP_C0805-22UF,16V,20%,X6S,CA
SW_P12V_PVCCIN_CPU0_FLT  PC282_P0_4       1        Q_CAP_C0805-22UF,16V,20%,X6S,CA
SW_P12V_PVCCIN_CPU0_FLT  PC283_P0_3       1        Q_CAP_C0805-22UF,16V,20%,X6S,CA
SW_P12V_PVCCIN_CPU0_FLT  PC284_P0_4       1        Q_CAP_C0805-22UF,16V,20%,X6S,CA
SW_P12V_PVCCIN_CPU0_FLT  PC285_P0_3       1        Q_CAP_C0805-22UF,16V,20%,X6S,CA
SW_P12V_PVCCIN_CPU0_FLT  PC296_P0_2       1        Q_CAP_0402-3300PF,50V,10%,X7R,A
SW_P12V_PVCCIN_CPU0_FLT  PC297_P0_1       1        Q_CAP_0402-3300PF,50V,10%,X7R,A
SW_P12V_PVCCIN_CPU0_FLT  PC298_P0_2       1        Q_CAP_C0402-1UF,16V,10%,X6S,CHA
SW_P12V_PVCCIN_CPU0_FLT  PC299_P0_1       1        Q_CAP_C0402-1UF,16V,10%,X6S,CHA
SW_P12V_PVCCIN_CPU0_FLT  PC302_P0_2       1        Q_CAP_C0805-22UF,16V,20%,X6S,CA
SW_P12V_PVCCIN_CPU0_FLT  PC303_P0_1       1        Q_CAP_C0805-22UF,16V,20%,X6S,CA
SW_P12V_PVCCIN_CPU0_FLT  PC304_P0_2       1        Q_CAP_C0805-22UF,16V,20%,X6S,CA
SW_P12V_PVCCIN_CPU0_FLT  PC305_P0_1       1        Q_CAP_C0805-22UF,16V,20%,X6S,CA
SW_P12V_PVCCIN_CPU0_FLT  PC306_P0_2       1        Q_CAP_C0805-22UF,16V,20%,X6S,CA
SW_P12V_PVCCIN_CPU0_FLT  PC307_P0_1       1        Q_CAP_C0805-22UF,16V,20%,X6S,CA
SW_P12V_PVCCIN_CPU0_FLT  PC315            1        Q_CAPP_THLF-270UF,16V,20%,OSCOA
SW_P12V_PVCCIN_CPU0_FLT  PC318            1        Q_CAPP_THLF-270UF,16V,20%,OSCOA
SW_P12V_PVCCIN_CPU0_FLT  PC321            1        Q_CAPP_THLF-270UF,16V,20%,OSCOA
SW_P12V_PVCCIN_CPU0_FLT  PC324            1        Q_CAPP_THLF-270UF,16V,20%,OSCOA
SW_P12V_PVCCIN_CPU0_FLT  PC831            1        Q_CAP_C0805-22UF,16V,20%,EMPTYA
SW_P12V_PVCCIN_CPU0_FLT  PC1247           1        Q_CAP_C0805-22UF,16V,20%,EMPTYA
SW_P12V_PVCCIN_CPU0_FLT  PC1248           1        Q_CAP_C0805-22UF,16V,20%,EMPTYA
SW_P12V_PVCCIN_CPU0_FLT  PC1249           1        Q_CAP_0402-0.1UF,25V,10%,EMPTYA
SW_P12V_PVCCIN_CPU0_FLT  PL15             2        Q_INDUCTOR_SMLF-50NH/148A,IND,A
SW_P12V_PVCCIN_CPU0_FLT  PU10_P0_4        25_29    ISL99390FRZTR5935-ISL99390FRZ-A
SW_P12V_PVCCIN_CPU0_FLT  PU10_P0_4        30       ISL99390FRZTR5935-ISL99390FRZ-A
SW_P12V_PVCCIN_CPU0_FLT  PU11_P0_3        25_29    ISL99390FRZTR5935-ISL99390FRZ-A
SW_P12V_PVCCIN_CPU0_FLT  PU11_P0_3        30       ISL99390FRZTR5935-ISL99390FRZ-A
SW_P12V_PVCCIN_CPU0_FLT  PU12_P0_2        25_29    ISL99390FRZTR5935-ISL99390FRZ-A
SW_P12V_PVCCIN_CPU0_FLT  PU12_P0_2        30       ISL99390FRZTR5935-ISL99390FRZ-A
SW_P12V_PVCCIN_CPU0_FLT  PU13_P0_1        25_29    ISL99390FRZTR5935-ISL99390FRZ-A
SW_P12V_PVCCIN_CPU0_FLT  PU13_P0_1        30       ISL99390FRZTR5935-ISL99390FRZ-A
SW_P12V_PVCCIN_CPU0_FLT  PU6_P0_8         25_29    ISL99390FRZTR5935-ISL99390FRZ-A
SW_P12V_PVCCIN_CPU0_FLT  PU6_P0_8         30       ISL99390FRZTR5935-ISL99390FRZ-A
SW_P12V_PVCCIN_CPU0_FLT  PU79             10       MPQ8633AGLEC807Z-MPQ8633AGLE-CA
SW_P12V_PVCCIN_CPU0_FLT  PU79             21       MPQ8633AGLEC807Z-MPQ8633AGLE-CA
SW_P12V_PVCCIN_CPU0_FLT  PU7_P0_7         25_29    ISL99390FRZTR5935-ISL99390FRZ-A
SW_P12V_PVCCIN_CPU0_FLT  PU7_P0_7         30       ISL99390FRZTR5935-ISL99390FRZ-A
SW_P12V_PVCCIN_CPU0_FLT  PU8_P0_6         25_29    ISL99390FRZTR5935-ISL99390FRZ-A
SW_P12V_PVCCIN_CPU0_FLT  PU8_P0_6         30       ISL99390FRZTR5935-ISL99390FRZ-A
SW_P12V_PVCCIN_CPU0_FLT  PU9_P0_5         25_29    ISL99390FRZTR5935-ISL99390FRZ-A
SW_P12V_PVCCIN_CPU0_FLT  PU9_P0_5         30       ISL99390FRZTR5935-ISL99390FRZ-A
SW_P12V_PVCCIN_CPU1_FLT  PC1259           1        Q_CAP_C0805-22UF,16V,20%,X6S,CA
SW_P12V_PVCCIN_CPU1_FLT  PC1260           1        Q_CAP_C0805-22UF,16V,20%,X6S,CA
SW_P12V_PVCCIN_CPU1_FLT  PC1261           1        Q_CAP_C0805-22UF,16V,20%,X6S,CA
SW_P12V_PVCCIN_CPU1_FLT  PC1262           1        Q_CAP_0402-0.1UF,25V,10%,X7R,CA
SW_P12V_PVCCIN_CPU1_FLT  PC483_P1_8       1        Q_CAP_0402-3300PF,50V,10%,X7R,A
SW_P12V_PVCCIN_CPU1_FLT  PC484_P1_7       1        Q_CAP_0402-3300PF,50V,10%,X7R,A
SW_P12V_PVCCIN_CPU1_FLT  PC485_P1_8       1        Q_CAP_C0402-1UF,16V,10%,X6S,CHA
SW_P12V_PVCCIN_CPU1_FLT  PC486_P1_7       1        Q_CAP_C0402-1UF,16V,10%,X6S,CHA
SW_P12V_PVCCIN_CPU1_FLT  PC489_P1_8       1        Q_CAP_C0805-22UF,16V,20%,X6S,CA
SW_P12V_PVCCIN_CPU1_FLT  PC490_P1_7       1        Q_CAP_C0805-22UF,16V,20%,X6S,CA
SW_P12V_PVCCIN_CPU1_FLT  PC491_P1_8       1        Q_CAP_C0805-22UF,16V,20%,X6S,CA
SW_P12V_PVCCIN_CPU1_FLT  PC492_P1_7       1        Q_CAP_C0805-22UF,16V,20%,X6S,CA
SW_P12V_PVCCIN_CPU1_FLT  PC493_P1_8       1        Q_CAP_C0805-22UF,16V,20%,X6S,CA
SW_P12V_PVCCIN_CPU1_FLT  PC494_P1_7       1        Q_CAP_C0805-22UF,16V,20%,X6S,CA
SW_P12V_PVCCIN_CPU1_FLT  PC505_P1_6       1        Q_CAP_0402-3300PF,50V,10%,X7R,A
SW_P12V_PVCCIN_CPU1_FLT  PC506_P1_5       1        Q_CAP_0402-3300PF,50V,10%,X7R,A
SW_P12V_PVCCIN_CPU1_FLT  PC507_P1_6       1        Q_CAP_C0402-1UF,16V,10%,X6S,CHA
SW_P12V_PVCCIN_CPU1_FLT  PC508_P1_5       1        Q_CAP_C0402-1UF,16V,10%,X6S,CHA
SW_P12V_PVCCIN_CPU1_FLT  PC511_P1_6       1        Q_CAP_C0805-22UF,16V,20%,X6S,CA
SW_P12V_PVCCIN_CPU1_FLT  PC512_P1_5       1        Q_CAP_C0805-22UF,16V,20%,X6S,CA
SW_P12V_PVCCIN_CPU1_FLT  PC513_P1_6       1        Q_CAP_C0805-22UF,16V,20%,X6S,CA
SW_P12V_PVCCIN_CPU1_FLT  PC514_P1_5       1        Q_CAP_C0805-22UF,16V,20%,X6S,CA
SW_P12V_PVCCIN_CPU1_FLT  PC515_P1_6       1        Q_CAP_C0805-22UF,16V,20%,X6S,CA
SW_P12V_PVCCIN_CPU1_FLT  PC516_P1_5       1        Q_CAP_C0805-22UF,16V,20%,X6S,CA
SW_P12V_PVCCIN_CPU1_FLT  PC527_P1_4       1        Q_CAP_0402-3300PF,50V,10%,X7R,A
SW_P12V_PVCCIN_CPU1_FLT  PC528_P1_3       1        Q_CAP_0402-3300PF,50V,10%,X7R,A
SW_P12V_PVCCIN_CPU1_FLT  PC529_P1_4       1        Q_CAP_C0402-1UF,16V,10%,X6S,CHA
SW_P12V_PVCCIN_CPU1_FLT  PC530_P1_3       1        Q_CAP_C0402-1UF,16V,10%,X6S,CHA
SW_P12V_PVCCIN_CPU1_FLT  PC533_P1_4       1        Q_CAP_C0805-22UF,16V,20%,X6S,CA
SW_P12V_PVCCIN_CPU1_FLT  PC534_P1_3       1        Q_CAP_C0805-22UF,16V,20%,X6S,CA
SW_P12V_PVCCIN_CPU1_FLT  PC535_P1_4       1        Q_CAP_C0805-22UF,16V,20%,X6S,CA
SW_P12V_PVCCIN_CPU1_FLT  PC536_P1_3       1        Q_CAP_C0805-22UF,16V,20%,X6S,CA
SW_P12V_PVCCIN_CPU1_FLT  PC537_P1_4       1        Q_CAP_C0805-22UF,16V,20%,X6S,CA
SW_P12V_PVCCIN_CPU1_FLT  PC538_P1_3       1        Q_CAP_C0805-22UF,16V,20%,X6S,CA
SW_P12V_PVCCIN_CPU1_FLT  PC560_P1_2       1        Q_CAP_0402-3300PF,50V,10%,X7R,A
SW_P12V_PVCCIN_CPU1_FLT  PC561_P1_1       1        Q_CAP_0402-3300PF,50V,10%,X7R,A
SW_P12V_PVCCIN_CPU1_FLT  PC562_P1_2       1        Q_CAP_C0402-1UF,16V,10%,X6S,CHA
SW_P12V_PVCCIN_CPU1_FLT  PC563_P1_1       1        Q_CAP_C0402-1UF,16V,10%,X6S,CHA
SW_P12V_PVCCIN_CPU1_FLT  PC566_P1_2       1        Q_CAP_C0805-22UF,16V,20%,X6S,CA
SW_P12V_PVCCIN_CPU1_FLT  PC567_P1_1       1        Q_CAP_C0805-22UF,16V,20%,X6S,CA
SW_P12V_PVCCIN_CPU1_FLT  PC568_P1_2       1        Q_CAP_C0805-22UF,16V,20%,X6S,CA
SW_P12V_PVCCIN_CPU1_FLT  PC569_P1_1       1        Q_CAP_C0805-22UF,16V,20%,X6S,CA
SW_P12V_PVCCIN_CPU1_FLT  PC570_P1_2       1        Q_CAP_C0805-22UF,16V,20%,X6S,CA
SW_P12V_PVCCIN_CPU1_FLT  PC571_P1_1       1        Q_CAP_C0805-22UF,16V,20%,X6S,CA
SW_P12V_PVCCIN_CPU1_FLT  PC579            1        Q_CAPP_THLF-270UF,16V,20%,OSCOA
SW_P12V_PVCCIN_CPU1_FLT  PC582            1        Q_CAPP_THLF-270UF,16V,20%,OSCOA
SW_P12V_PVCCIN_CPU1_FLT  PC585            1        Q_CAPP_THLF-270UF,16V,20%,OSCOA
SW_P12V_PVCCIN_CPU1_FLT  PC588            1        Q_CAPP_THLF-270UF,16V,20%,OSCOA
SW_P12V_PVCCIN_CPU1_FLT  PL32             2        Q_INDUCTOR_SMLF-50NH/148A,IND,A
SW_P12V_PVCCIN_CPU1_FLT  PU23_P1_8        25_29    ISL99390FRZTR5935-ISL99390FRZ-A
SW_P12V_PVCCIN_CPU1_FLT  PU23_P1_8        30       ISL99390FRZTR5935-ISL99390FRZ-A
SW_P12V_PVCCIN_CPU1_FLT  PU24_P1_7        25_29    ISL99390FRZTR5935-ISL99390FRZ-A
SW_P12V_PVCCIN_CPU1_FLT  PU24_P1_7        30       ISL99390FRZTR5935-ISL99390FRZ-A
SW_P12V_PVCCIN_CPU1_FLT  PU25_P1_6        25_29    ISL99390FRZTR5935-ISL99390FRZ-A
SW_P12V_PVCCIN_CPU1_FLT  PU25_P1_6        30       ISL99390FRZTR5935-ISL99390FRZ-A
SW_P12V_PVCCIN_CPU1_FLT  PU26_P1_5        25_29    ISL99390FRZTR5935-ISL99390FRZ-A
SW_P12V_PVCCIN_CPU1_FLT  PU26_P1_5        30       ISL99390FRZTR5935-ISL99390FRZ-A
SW_P12V_PVCCIN_CPU1_FLT  PU27_P1_4        25_29    ISL99390FRZTR5935-ISL99390FRZ-A
SW_P12V_PVCCIN_CPU1_FLT  PU27_P1_4        30       ISL99390FRZTR5935-ISL99390FRZ-A
SW_P12V_PVCCIN_CPU1_FLT  PU28_P1_3        25_29    ISL99390FRZTR5935-ISL99390FRZ-A
SW_P12V_PVCCIN_CPU1_FLT  PU28_P1_3        30       ISL99390FRZTR5935-ISL99390FRZ-A
SW_P12V_PVCCIN_CPU1_FLT  PU30_P1_2        25_29    ISL99390FRZTR5935-ISL99390FRZ-A
SW_P12V_PVCCIN_CPU1_FLT  PU30_P1_2        30       ISL99390FRZTR5935-ISL99390FRZ-A
SW_P12V_PVCCIN_CPU1_FLT  PU31_P1_1        25_29    ISL99390FRZTR5935-ISL99390FRZ-A
SW_P12V_PVCCIN_CPU1_FLT  PU31_P1_1        30       ISL99390FRZTR5935-ISL99390FRZ-A
SW_P12V_PVCCIN_CPU1_FLT  PU80             10       MPQ8633AGLEC807Z-MPQ8633AGLE-CB
SW_P12V_PVCCIN_CPU1_FLT  PU80             21       MPQ8633AGLEC807Z-MPQ8633AGLE-CB
SW_P1V05_PCH_AUX_BST     PC1222           1        Q_CAP_0402-0.22UF,16V,10%,X7R,A
SW_P1V05_PCH_AUX_BST     PU73             1        MPQ8633BGLEC838Z-MPQ8633BGLE-CA
SW_P1V05_PCH_AUX_SW      PC1222           2        Q_CAP_0402-0.22UF,16V,10%,X7R,A
SW_P1V05_PCH_AUX_SW      PL150            1        Q_INDUCTOR_SMLF-300NH/33A,IND,A
SW_P1V05_PCH_AUX_SW      PU73             20       MPQ8633BGLEC838Z-MPQ8633BGLE-CA
SW_P1V8_PCH_AUX_BST      PC1235           1        Q_CAP_0402-0.22UF,16V,10%,X7R,A
SW_P1V8_PCH_AUX_BST      PU74             9        NB695GDZ-NB695GD-Z,SMLF,IC,AL0A
SW_P1V8_PCH_AUX_FLT      PC1232           1        Q_CAP_C0805-10UF,16V,10%,X6S,CA
SW_P1V8_PCH_AUX_FLT      PC1233           1        Q_CAP_C0805-10UF,16V,10%,X6S,CA
SW_P1V8_PCH_AUX_FLT      PC1234           1        Q_CAP_C0402-100NF,50V,10%,X7R,A
SW_P1V8_PCH_AUX_FLT      PL16             2        Q_INDUCTOR_SMLF-BLM18SN220TN1DA
SW_P1V8_PCH_AUX_FLT      PU74             1        NB695GDZ-NB695GD-Z,SMLF,IC,AL0A
SW_P1V8_PCH_AUX_SW       PC1235           2        Q_CAP_0402-0.22UF,16V,10%,X7R,A
SW_P1V8_PCH_AUX_SW       PL170            1        Q_INDUCTOR_SMLF-1UH,IND,CV-10BA
SW_P1V8_PCH_AUX_SW       PU74             8        NB695GDZ-NB695GD-Z,SMLF,IC,AL0A
SW_P3V3_AUX_BOOT         PR835            1        Q_RES_0402LF-0,5%,1/16W,CHIP,CA
SW_P3V3_AUX_BOOT         PU9              26       NCP3284MNTXG-NCP3284MNTXG,SMLFA
SW_P3V3_AUX_BOOTR        PC568            1        Q_CAP_0402-0.22UF,16V,10%,X7R,A
SW_P3V3_AUX_BOOTR        PU9              25       NCP3284MNTXG-NCP3284MNTXG,SMLFA
SW_P3V3_AUX_BOOT_R       PC568            2        Q_CAP_0402-0.22UF,16V,10%,X7R,A
SW_P3V3_AUX_BOOT_R       PR835            2        Q_RES_0402LF-0,5%,1/16W,CHIP,CA
SW_P3V3_AUX_FLT          PC71             1        Q_CAP_C0805-22UF,16V,20%,X6S,CA
SW_P3V3_AUX_FLT          PC566            1        Q_CAPP_SMLF-100UF,16V,20%,OSCOA
SW_P3V3_AUX_FLT          PC567            1        Q_CAP_C0805-22UF,16V,20%,X6S,CA
SW_P3V3_AUX_FLT          PC570            1        Q_CAP_C0805-22UF,16V,20%,X6S,CA
SW_P3V3_AUX_FLT          PC571            1        Q_CAP_C0805-22UF,16V,20%,X6S,CA
SW_P3V3_AUX_FLT          PC576            1        Q_CAP_C0805-22UF,16V,20%,X6S,CA
SW_P3V3_AUX_FLT          PC577            1        Q_CAP_0402-0.1UF,25V,10%,X7R,CA
SW_P3V3_AUX_FLT          PL45             2        Q_INDUCTOR_SMLF-100NH/16A,IND,A
SW_P3V3_AUX_FLT          PU9              20_24    NCP3284MNTXG-NCP3284MNTXG,SMLFA
SW_P3V3_AUX_SW           PL66             1        Q_INDUCTOR_SMLF-1.5UH/53A,IND,A
SW_P3V3_AUX_SW           PU9              11_18    NCP3284MNTXG-NCP3284MNTXG,SMLFA
SW_P5V_AUX_BST           PC1847           1        Q_CAP_0402-0.22UF,16V,10%,X7R,A
SW_P5V_AUX_BST           PU181            1        MPQ8633BGLEC838Z-MPQ8633BGLE-CA
SW_P5V_AUX_FLT           PC1846           1        Q_CAP_0402-0.1UF,25V,10%,X7R,CA
SW_P5V_AUX_FLT           PC1849           1        Q_CAP_C0805-22UF,16V,20%,X6S,CA
SW_P5V_AUX_FLT           PC1850           1        Q_CAP_C0805-22UF,16V,20%,X6S,CA
SW_P5V_AUX_FLT           PC1898           1        Q_CAP_C0805-22UF,16V,20%,X6S,CA
SW_P5V_AUX_FLT           PL64             2        Q_INDUCTOR_SMLF-BLM18SN220TN1DA
SW_P5V_AUX_FLT           PU181            10       MPQ8633BGLEC838Z-MPQ8633BGLE-CA
SW_P5V_AUX_FLT           PU181            21       MPQ8633BGLEC838Z-MPQ8633BGLE-CA
SW_P5V_AUX_SW            PC1847           2        Q_CAP_0402-0.22UF,16V,10%,X7R,A
SW_P5V_AUX_SW            PL65             1        Q_INDUCTOR_SMLF-3.3UH/10A,IND,A
SW_P5V_AUX_SW            PU181            20       MPQ8633BGLEC838Z-MPQ8633BGLE-CA
SW_PVCCD_HV_CPU0_BOOT1   PR1784           1        Q_RES_0402LF-4.7,1%,1/16W,CHIPA
SW_PVCCD_HV_CPU0_BOOT1   PU36             20       RAA2213404GNPHB0-RAA2213404GNPA
SW_PVCCD_HV_CPU0_BOOT1_R PC636            1        Q_CAP_C0402-100NF,50V,10%,X7R,A
SW_PVCCD_HV_CPU0_BOOT1_R PR1784           2        Q_RES_0402LF-4.7,1%,1/16W,CHIPA
SW_PVCCD_HV_CPU0_BOOTR1  PC636            2        Q_CAP_C0402-100NF,50V,10%,X7R,A
SW_PVCCD_HV_CPU0_BOOTR1  PU36             19       RAA2213404GNPHB0-RAA2213404GNPA
SW_PVCCD_HV_CPU0_SW1     PL35             1        Q_INDUCTOR_SMLF-120NH/94A,IND,A
SW_PVCCD_HV_CPU0_SW1     PU36             8_12     RAA2213404GNPHB0-RAA2213404GNPA
SW_PVCCD_HV_CPU1_BOOT1   PR1804           1        Q_RES_0402LF-4.7,1%,1/16W,CHIPA
SW_PVCCD_HV_CPU1_BOOT1   PU17             20       RAA2213404GNPHB0-RAA2213404GNPA
SW_PVCCD_HV_CPU1_BOOT1_R PC376            1        Q_CAP_C0402-100NF,50V,10%,X7R,A
SW_PVCCD_HV_CPU1_BOOT1_R PR1804           2        Q_RES_0402LF-4.7,1%,1/16W,CHIPA
SW_PVCCD_HV_CPU1_BOOTR1  PC376            2        Q_CAP_C0402-100NF,50V,10%,X7R,A
SW_PVCCD_HV_CPU1_BOOTR1  PU17             19       RAA2213404GNPHB0-RAA2213404GNPA
SW_PVCCD_HV_CPU1_SW1     PL17             1        Q_INDUCTOR_SMLF-120NH/94A,IND,A
SW_PVCCD_HV_CPU1_SW1     PU17             8_12     RAA2213404GNPHB0-RAA2213404GNPA
SW_PVCCFA_EHV_CPU0_BOOT1 PR1778           1        Q_RES_0402LF-4.7,1%,1/16W,CHIPA
SW_PVCCFA_EHV_CPU0_BOOT1 PU42             20       RAA2213404GNPHB0-RAA2213404GNPA
SW_PVCCFA_EHV_CPU0_BOOT1_R PC178            1        Q_CAP_C0402-100NF,50V,10%,X7R,A
SW_PVCCFA_EHV_CPU0_BOOT1_R PR1778           2        Q_RES_0402LF-4.7,1%,1/16W,CHIPA
SW_PVCCFA_EHV_CPU0_BOOTR1 PC178            2        Q_CAP_C0402-100NF,50V,10%,X7R,A
SW_PVCCFA_EHV_CPU0_BOOTR1 PU42             19       RAA2213404GNPHB0-RAA2213404GNPA
SW_PVCCFA_EHV_CPU0_SW1   PL3              1        Q_INDUCTOR_SMLF-300NH/33A,IND,A
SW_PVCCFA_EHV_CPU0_SW1   PU42             8_12     RAA2213404GNPHB0-RAA2213404GNPA
SW_PVCCFA_EHV_CPU1_BOOT1 PR1798           1        Q_RES_0402LF-4.7,1%,1/16W,CHIPA
SW_PVCCFA_EHV_CPU1_BOOT1 PU49             20       RAA2213404GNPHB0-RAA2213404GNPA
SW_PVCCFA_EHV_CPU1_BOOT1_R PC431            1        Q_CAP_C0402-100NF,50V,10%,X7R,A
SW_PVCCFA_EHV_CPU1_BOOT1_R PR1798           2        Q_RES_0402LF-4.7,1%,1/16W,CHIPA
SW_PVCCFA_EHV_CPU1_BOOTR1 PC431            2        Q_CAP_C0402-100NF,50V,10%,X7R,A
SW_PVCCFA_EHV_CPU1_BOOTR1 PU49             19       RAA2213404GNPHB0-RAA2213404GNPA
SW_PVCCFA_EHV_CPU1_SW1   PL20             1        Q_INDUCTOR_SMLF-300NH/33A,IND,A
SW_PVCCFA_EHV_CPU1_SW1   PU49             8_12     RAA2213404GNPHB0-RAA2213404GNPA
SW_PVCCFA_EHV_FIVRA_CPU0_BOOT1 PR1780           1        Q_RES_0402LF-3.3,1%,1/16W,CHIPA
SW_PVCCFA_EHV_FIVRA_CPU0_BOOT1 PU69_P0_1        33       ISL99390FRZTR5935-ISL99390FRZ-A
SW_PVCCFA_EHV_FIVRA_CPU0_BOOT1_ PC606            1        Q_CAP_C0402-100NF,50V,10%,X7R,A
SW_PVCCFA_EHV_FIVRA_CPU0_BOOT1_ PR1780           2        Q_RES_0402LF-3.3,1%,1/16W,CHIPA
SW_PVCCFA_EHV_FIVRA_CPU0_BOOT2 PR1781           1        Q_RES_0402LF-3.3,1%,1/16W,CHIPA
SW_PVCCFA_EHV_FIVRA_CPU0_BOOT2 PU70_P0_2        33       ISL99390FRZTR5935-ISL99390FRZ-A
SW_PVCCFA_EHV_FIVRA_CPU0_BOOT2_ PC607            1        Q_CAP_C0402-100NF,50V,10%,X7R,A
SW_PVCCFA_EHV_FIVRA_CPU0_BOOT2_ PR1781           2        Q_RES_0402LF-3.3,1%,1/16W,CHIPA
SW_PVCCFA_EHV_FIVRA_CPU0_BOOT3 PR1782           1        Q_RES_0402LF-3.3,1%,1/16W,EMPTA
SW_PVCCFA_EHV_FIVRA_CPU0_BOOT3 PU71_P0_3        33       ISL99390FRZTR5935-ISL99390FRZ-B
SW_PVCCFA_EHV_FIVRA_CPU0_BOOT3_ PC1177           1        Q_CAP_C0402-100NF,50V,10%,EMPTA
SW_PVCCFA_EHV_FIVRA_CPU0_BOOT3_ PR1782           2        Q_RES_0402LF-3.3,1%,1/16W,EMPTA
SW_PVCCFA_EHV_FIVRA_CPU0_BOOT4 PR1783           1        Q_RES_0402LF-3.3,1%,1/16W,EMPTA
SW_PVCCFA_EHV_FIVRA_CPU0_BOOT4 PU72_P0_4        33       ISL99390FRZTR5935-ISL99390FRZ-B
SW_PVCCFA_EHV_FIVRA_CPU0_BOOT4_ PC1178           1        Q_CAP_C0402-100NF,50V,10%,EMPTA
SW_PVCCFA_EHV_FIVRA_CPU0_BOOT4_ PR1783           2        Q_RES_0402LF-3.3,1%,1/16W,EMPTA
SW_PVCCFA_EHV_FIVRA_CPU0_BOOTR1 PC606            2        Q_CAP_C0402-100NF,50V,10%,X7R,A
SW_PVCCFA_EHV_FIVRA_CPU0_BOOTR1 PU69_P0_1        32       ISL99390FRZTR5935-ISL99390FRZ-A
SW_PVCCFA_EHV_FIVRA_CPU0_BOOTR2 PC607            2        Q_CAP_C0402-100NF,50V,10%,X7R,A
SW_PVCCFA_EHV_FIVRA_CPU0_BOOTR2 PU70_P0_2        32       ISL99390FRZTR5935-ISL99390FRZ-A
SW_PVCCFA_EHV_FIVRA_CPU0_BOOTR3 PC1177           2        Q_CAP_C0402-100NF,50V,10%,EMPTA
SW_PVCCFA_EHV_FIVRA_CPU0_BOOTR3 PU71_P0_3        32       ISL99390FRZTR5935-ISL99390FRZ-B
SW_PVCCFA_EHV_FIVRA_CPU0_BOOTR4 PC1178           2        Q_CAP_C0402-100NF,50V,10%,EMPTA
SW_PVCCFA_EHV_FIVRA_CPU0_BOOTR4 PU72_P0_4        32       ISL99390FRZTR5935-ISL99390FRZ-B
SW_PVCCFA_EHV_FIVRA_CPU0_SW1 PL33             1        Q_INDUCTOR_SMLF-130NH/106A,INDA
SW_PVCCFA_EHV_FIVRA_CPU0_SW1 PU69_P0_1        10_19    ISL99390FRZTR5935-ISL99390FRZ-A
SW_PVCCFA_EHV_FIVRA_CPU0_SW2 PL34             1        Q_INDUCTOR_SMLF-130NH/106A,INDA
SW_PVCCFA_EHV_FIVRA_CPU0_SW2 PU70_P0_2        10_19    ISL99390FRZTR5935-ISL99390FRZ-A
SW_PVCCFA_EHV_FIVRA_CPU0_SW3 PL2              1        Q_INDUCTOR_SMLF-130NH/106A,EMPA
SW_PVCCFA_EHV_FIVRA_CPU0_SW3 PU71_P0_3        10_19    ISL99390FRZTR5935-ISL99390FRZ-B
SW_PVCCFA_EHV_FIVRA_CPU0_SW4 PL210            1        Q_INDUCTOR_SMLF-130NH/106A,EMPA
SW_PVCCFA_EHV_FIVRA_CPU0_SW4 PU72_P0_4        10_19    ISL99390FRZTR5935-ISL99390FRZ-B
SW_PVCCFA_EHV_FIVRA_CPU1_BOOT1 PR1800           1        Q_RES_0402LF-3.3,1%,1/16W,CHIPA
SW_PVCCFA_EHV_FIVRA_CPU1_BOOT1 PU75_P1_1        33       ISL99390FRZTR5935-ISL99390FRZ-A
SW_PVCCFA_EHV_FIVRA_CPU1_BOOT1_ PC401            1        Q_CAP_C0402-100NF,50V,10%,X7R,A
SW_PVCCFA_EHV_FIVRA_CPU1_BOOT1_ PR1800           2        Q_RES_0402LF-3.3,1%,1/16W,CHIPA
SW_PVCCFA_EHV_FIVRA_CPU1_BOOT2 PR1801           1        Q_RES_0402LF-3.3,1%,1/16W,CHIPA
SW_PVCCFA_EHV_FIVRA_CPU1_BOOT2 PU76_P1_2        33       ISL99390FRZTR5935-ISL99390FRZ-A
SW_PVCCFA_EHV_FIVRA_CPU1_BOOT2_ PC402            1        Q_CAP_C0402-100NF,50V,10%,X7R,A
SW_PVCCFA_EHV_FIVRA_CPU1_BOOT2_ PR1801           2        Q_RES_0402LF-3.3,1%,1/16W,CHIPA
SW_PVCCFA_EHV_FIVRA_CPU1_BOOT3 PR1802           1        Q_RES_0402LF-3.3,1%,1/16W,CHIPA
SW_PVCCFA_EHV_FIVRA_CPU1_BOOT3 PU77_P1_3        33       ISL99390FRZTR5935-ISL99390FRZ-A
SW_PVCCFA_EHV_FIVRA_CPU1_BOOT3_ PC1197           1        Q_CAP_C0402-100NF,50V,10%,X7R,A
SW_PVCCFA_EHV_FIVRA_CPU1_BOOT3_ PR1802           2        Q_RES_0402LF-3.3,1%,1/16W,CHIPA
SW_PVCCFA_EHV_FIVRA_CPU1_BOOT4 PR1803           1        Q_RES_0402LF-3.3,1%,1/16W,CHIPA
SW_PVCCFA_EHV_FIVRA_CPU1_BOOT4 PU78_P1_4        33       ISL99390FRZTR5935-ISL99390FRZ-A
SW_PVCCFA_EHV_FIVRA_CPU1_BOOT4_ PC1198           1        Q_CAP_C0402-100NF,50V,10%,X7R,A
SW_PVCCFA_EHV_FIVRA_CPU1_BOOT4_ PR1803           2        Q_RES_0402LF-3.3,1%,1/16W,CHIPA
SW_PVCCFA_EHV_FIVRA_CPU1_BOOTR1 PC401            2        Q_CAP_C0402-100NF,50V,10%,X7R,A
SW_PVCCFA_EHV_FIVRA_CPU1_BOOTR1 PU75_P1_1        32       ISL99390FRZTR5935-ISL99390FRZ-A
SW_PVCCFA_EHV_FIVRA_CPU1_BOOTR2 PC402            2        Q_CAP_C0402-100NF,50V,10%,X7R,A
SW_PVCCFA_EHV_FIVRA_CPU1_BOOTR2 PU76_P1_2        32       ISL99390FRZTR5935-ISL99390FRZ-A
SW_PVCCFA_EHV_FIVRA_CPU1_BOOTR3 PC1197           2        Q_CAP_C0402-100NF,50V,10%,X7R,A
SW_PVCCFA_EHV_FIVRA_CPU1_BOOTR3 PU77_P1_3        32       ISL99390FRZTR5935-ISL99390FRZ-A
SW_PVCCFA_EHV_FIVRA_CPU1_BOOTR4 PC1198           2        Q_CAP_C0402-100NF,50V,10%,X7R,A
SW_PVCCFA_EHV_FIVRA_CPU1_BOOTR4 PU78_P1_4        32       ISL99390FRZTR5935-ISL99390FRZ-A
SW_PVCCFA_EHV_FIVRA_CPU1_SW1 PL18             1        Q_INDUCTOR_SMLF-130NH/106A,INDA
SW_PVCCFA_EHV_FIVRA_CPU1_SW1 PU75_P1_1        10_19    ISL99390FRZTR5935-ISL99390FRZ-A
SW_PVCCFA_EHV_FIVRA_CPU1_SW2 PL19             1        Q_INDUCTOR_SMLF-130NH/106A,INDA
SW_PVCCFA_EHV_FIVRA_CPU1_SW2 PU76_P1_2        10_19    ISL99390FRZTR5935-ISL99390FRZ-A
SW_PVCCFA_EHV_FIVRA_CPU1_SW3 PL12             1        Q_INDUCTOR_SMLF-130NH/106A,INDA
SW_PVCCFA_EHV_FIVRA_CPU1_SW3 PU77_P1_3        10_19    ISL99390FRZTR5935-ISL99390FRZ-A
SW_PVCCFA_EHV_FIVRA_CPU1_SW4 PL113            1        Q_INDUCTOR_SMLF-130NH/106A,INDA
SW_PVCCFA_EHV_FIVRA_CPU1_SW4 PU78_P1_4        10_19    ISL99390FRZTR5935-ISL99390FRZ-A
SW_PVCCINFAON_CPU0_BOOT1 PR1774           1        Q_RES_0402LF-4.7,1%,1/16W,CHIPA
SW_PVCCINFAON_CPU0_BOOT1 PU43_P0_1        20       RAA2213404GNPHB0-RAA2213404GNPA
SW_PVCCINFAON_CPU0_BOOT1_R PC193            1        Q_CAP_C0402-100NF,50V,10%,X7R,A
SW_PVCCINFAON_CPU0_BOOT1_R PR1774           2        Q_RES_0402LF-4.7,1%,1/16W,CHIPA
SW_PVCCINFAON_CPU0_BOOT2 PR1775           1        Q_RES_0402LF-4.7,1%,1/16W,CHIPA
SW_PVCCINFAON_CPU0_BOOT2 PU44_P0_2        20       RAA2213404GNPHB0-RAA2213404GNPA
SW_PVCCINFAON_CPU0_BOOT2_R PC194            1        Q_CAP_C0402-100NF,50V,10%,X7R,A
SW_PVCCINFAON_CPU0_BOOT2_R PR1775           2        Q_RES_0402LF-4.7,1%,1/16W,CHIPA
SW_PVCCINFAON_CPU0_BOOTR1 PC193            2        Q_CAP_C0402-100NF,50V,10%,X7R,A
SW_PVCCINFAON_CPU0_BOOTR1 PU43_P0_1        19       RAA2213404GNPHB0-RAA2213404GNPA
SW_PVCCINFAON_CPU0_BOOTR2 PC194            2        Q_CAP_C0402-100NF,50V,10%,X7R,A
SW_PVCCINFAON_CPU0_BOOTR2 PU44_P0_2        19       RAA2213404GNPHB0-RAA2213404GNPA
SW_PVCCINFAON_CPU0_SW1   PL4              1        Q_INDUCTOR_SMLF-120NH/94A,IND,A
SW_PVCCINFAON_CPU0_SW1   PU43_P0_1        8_12     RAA2213404GNPHB0-RAA2213404GNPA
SW_PVCCINFAON_CPU0_SW2   PL5              1        Q_INDUCTOR_SMLF-120NH/94A,IND,A
SW_PVCCINFAON_CPU0_SW2   PU44_P0_2        8_12     RAA2213404GNPHB0-RAA2213404GNPA
SW_PVCCINFAON_CPU1_BOOT1 PR1794           1        Q_RES_0402LF-4.7,1%,1/16W,CHIPA
SW_PVCCINFAON_CPU1_BOOT1 PU50_P1_1        20       RAA2213404GNPHB0-RAA2213404GNPA
SW_PVCCINFAON_CPU1_BOOT1_R PC446            1        Q_CAP_C0402-100NF,50V,10%,X7R,A
SW_PVCCINFAON_CPU1_BOOT1_R PR1794           2        Q_RES_0402LF-4.7,1%,1/16W,CHIPA
SW_PVCCINFAON_CPU1_BOOT2 PR1795           1        Q_RES_0402LF-4.7,1%,1/16W,CHIPA
SW_PVCCINFAON_CPU1_BOOT2 PU51_P1_2        20       RAA2213404GNPHB0-RAA2213404GNPA
SW_PVCCINFAON_CPU1_BOOT2_R PC447            1        Q_CAP_C0402-100NF,50V,10%,X7R,A
SW_PVCCINFAON_CPU1_BOOT2_R PR1795           2        Q_RES_0402LF-4.7,1%,1/16W,CHIPA
SW_PVCCINFAON_CPU1_BOOTR1 PC446            2        Q_CAP_C0402-100NF,50V,10%,X7R,A
SW_PVCCINFAON_CPU1_BOOTR1 PU50_P1_1        19       RAA2213404GNPHB0-RAA2213404GNPA
SW_PVCCINFAON_CPU1_BOOTR2 PC447            2        Q_CAP_C0402-100NF,50V,10%,X7R,A
SW_PVCCINFAON_CPU1_BOOTR2 PU51_P1_2        19       RAA2213404GNPHB0-RAA2213404GNPA
SW_PVCCINFAON_CPU1_SW1   PL21             1        Q_INDUCTOR_SMLF-120NH/94A,IND,A
SW_PVCCINFAON_CPU1_SW1   PU50_P1_1        8_12     RAA2213404GNPHB0-RAA2213404GNPA
SW_PVCCINFAON_CPU1_SW2   PL22             1        Q_INDUCTOR_SMLF-120NH/94A,IND,A
SW_PVCCINFAON_CPU1_SW2   PU51_P1_2        8_12     RAA2213404GNPHB0-RAA2213404GNPA
SW_PVCCIN_CPU0_BOOT1     PR1787           1        Q_RES_0402LF-3.3,1%,1/16W,CHIPA
SW_PVCCIN_CPU0_BOOT1     PU13_P0_1        33       ISL99390FRZTR5935-ISL99390FRZ-A
SW_PVCCIN_CPU0_BOOT1_R   PC301            1        Q_CAP_C0402-100NF,50V,10%,X7R,A
SW_PVCCIN_CPU0_BOOT1_R   PR1787           2        Q_RES_0402LF-3.3,1%,1/16W,CHIPA
SW_PVCCIN_CPU0_BOOT2     PR1786           1        Q_RES_0402LF-3.3,1%,1/16W,CHIPA
SW_PVCCIN_CPU0_BOOT2     PU12_P0_2        33       ISL99390FRZTR5935-ISL99390FRZ-A
SW_PVCCIN_CPU0_BOOT2_R   PC300            1        Q_CAP_C0402-100NF,50V,10%,X7R,A
SW_PVCCIN_CPU0_BOOT2_R   PR1786           2        Q_RES_0402LF-3.3,1%,1/16W,CHIPA
SW_PVCCIN_CPU0_BOOT3     PR1769           1        Q_RES_0402LF-3.3,1%,1/16W,CHIPA
SW_PVCCIN_CPU0_BOOT3     PU11_P0_3        33       ISL99390FRZTR5935-ISL99390FRZ-A
SW_PVCCIN_CPU0_BOOT3_R   PC279            1        Q_CAP_C0402-100NF,50V,10%,X7R,A
SW_PVCCIN_CPU0_BOOT3_R   PR1769           2        Q_RES_0402LF-3.3,1%,1/16W,CHIPA
SW_PVCCIN_CPU0_BOOT4     PR1768           1        Q_RES_0402LF-3.3,1%,1/16W,CHIPA
SW_PVCCIN_CPU0_BOOT4     PU10_P0_4        33       ISL99390FRZTR5935-ISL99390FRZ-A
SW_PVCCIN_CPU0_BOOT4_R   PC278            1        Q_CAP_C0402-100NF,50V,10%,X7R,A
SW_PVCCIN_CPU0_BOOT4_R   PR1768           2        Q_RES_0402LF-3.3,1%,1/16W,CHIPA
SW_PVCCIN_CPU0_BOOT5     PR1771           1        Q_RES_0402LF-3.3,1%,1/16W,CHIPA
SW_PVCCIN_CPU0_BOOT5     PU9_P0_5         33       ISL99390FRZTR5935-ISL99390FRZ-A
SW_PVCCIN_CPU0_BOOT5_R   PC257            1        Q_CAP_C0402-100NF,50V,10%,X7R,A
SW_PVCCIN_CPU0_BOOT5_R   PR1771           2        Q_RES_0402LF-3.3,1%,1/16W,CHIPA
SW_PVCCIN_CPU0_BOOT6     PR1770           1        Q_RES_0402LF-3.3,1%,1/16W,CHIPA
SW_PVCCIN_CPU0_BOOT6     PU8_P0_6         33       ISL99390FRZTR5935-ISL99390FRZ-A
SW_PVCCIN_CPU0_BOOT6_R   PC256            1        Q_CAP_C0402-100NF,50V,10%,X7R,A
SW_PVCCIN_CPU0_BOOT6_R   PR1770           2        Q_RES_0402LF-3.3,1%,1/16W,CHIPA
SW_PVCCIN_CPU0_BOOT7     PR1773           1        Q_RES_0402LF-3.3,1%,1/16W,CHIPA
SW_PVCCIN_CPU0_BOOT7     PU7_P0_7         33       ISL99390FRZTR5935-ISL99390FRZ-A
SW_PVCCIN_CPU0_BOOT7_R   PC235            1        Q_CAP_C0402-100NF,50V,10%,X7R,A
SW_PVCCIN_CPU0_BOOT7_R   PR1773           2        Q_RES_0402LF-3.3,1%,1/16W,CHIPA
SW_PVCCIN_CPU0_BOOT8     PR1772           1        Q_RES_0402LF-3.3,1%,1/16W,CHIPA
SW_PVCCIN_CPU0_BOOT8     PU6_P0_8         33       ISL99390FRZTR5935-ISL99390FRZ-A
SW_PVCCIN_CPU0_BOOT8_R   PC234            1        Q_CAP_C0402-100NF,50V,10%,X7R,A
SW_PVCCIN_CPU0_BOOT8_R   PR1772           2        Q_RES_0402LF-3.3,1%,1/16W,CHIPA
SW_PVCCIN_CPU0_BOOTR1    PC301            2        Q_CAP_C0402-100NF,50V,10%,X7R,A
SW_PVCCIN_CPU0_BOOTR1    PU13_P0_1        32       ISL99390FRZTR5935-ISL99390FRZ-A
SW_PVCCIN_CPU0_BOOTR2    PC300            2        Q_CAP_C0402-100NF,50V,10%,X7R,A
SW_PVCCIN_CPU0_BOOTR2    PU12_P0_2        32       ISL99390FRZTR5935-ISL99390FRZ-A
SW_PVCCIN_CPU0_BOOTR3    PC279            2        Q_CAP_C0402-100NF,50V,10%,X7R,A
SW_PVCCIN_CPU0_BOOTR3    PU11_P0_3        32       ISL99390FRZTR5935-ISL99390FRZ-A
SW_PVCCIN_CPU0_BOOTR4    PC278            2        Q_CAP_C0402-100NF,50V,10%,X7R,A
SW_PVCCIN_CPU0_BOOTR4    PU10_P0_4        32       ISL99390FRZTR5935-ISL99390FRZ-A
SW_PVCCIN_CPU0_BOOTR5    PC257            2        Q_CAP_C0402-100NF,50V,10%,X7R,A
SW_PVCCIN_CPU0_BOOTR5    PU9_P0_5         32       ISL99390FRZTR5935-ISL99390FRZ-A
SW_PVCCIN_CPU0_BOOTR6    PC256            2        Q_CAP_C0402-100NF,50V,10%,X7R,A
SW_PVCCIN_CPU0_BOOTR6    PU8_P0_6         32       ISL99390FRZTR5935-ISL99390FRZ-A
SW_PVCCIN_CPU0_BOOTR7    PC235            2        Q_CAP_C0402-100NF,50V,10%,X7R,A
SW_PVCCIN_CPU0_BOOTR7    PU7_P0_7         32       ISL99390FRZTR5935-ISL99390FRZ-A
SW_PVCCIN_CPU0_BOOTR8    PC234            2        Q_CAP_C0402-100NF,50V,10%,X7R,A
SW_PVCCIN_CPU0_BOOTR8    PU6_P0_8         32       ISL99390FRZTR5935-ISL99390FRZ-A
SW_PVCCIN_CPU0_SW1       PL114            1        Q_INDUCTOR4P_14-150NH,SMLF,INDA
SW_PVCCIN_CPU0_SW1       PU13_P0_1        10_19    ISL99390FRZTR5935-ISL99390FRZ-A
SW_PVCCIN_CPU0_SW2       PL13             1        Q_INDUCTOR4P_14-150NH,SMLF,INDA
SW_PVCCIN_CPU0_SW2       PU12_P0_2        10_19    ISL99390FRZTR5935-ISL99390FRZ-A
SW_PVCCIN_CPU0_SW3       PL112            1        Q_INDUCTOR4P_14-150NH,SMLF,INDA
SW_PVCCIN_CPU0_SW3       PU11_P0_3        10_19    ISL99390FRZTR5935-ISL99390FRZ-A
SW_PVCCIN_CPU0_SW4       PL11             1        Q_INDUCTOR4P_14-150NH,SMLF,INDA
SW_PVCCIN_CPU0_SW4       PU10_P0_4        10_19    ISL99390FRZTR5935-ISL99390FRZ-A
SW_PVCCIN_CPU0_SW5       PL10             1        Q_INDUCTOR4P_14-150NH,SMLF,INDA
SW_PVCCIN_CPU0_SW5       PU9_P0_5         10_19    ISL99390FRZTR5935-ISL99390FRZ-A
SW_PVCCIN_CPU0_SW6       PL9              1        Q_INDUCTOR4P_14-150NH,SMLF,INDA
SW_PVCCIN_CPU0_SW6       PU8_P0_6         10_19    ISL99390FRZTR5935-ISL99390FRZ-A
SW_PVCCIN_CPU0_SW7       PL8              1        Q_INDUCTOR4P_14-150NH,SMLF,INDA
SW_PVCCIN_CPU0_SW7       PU7_P0_7         10_19    ISL99390FRZTR5935-ISL99390FRZ-A
SW_PVCCIN_CPU0_SW8       PL7              1        Q_INDUCTOR4P_14-150NH,SMLF,INDA
SW_PVCCIN_CPU0_SW8       PU6_P0_8         10_19    ISL99390FRZTR5935-ISL99390FRZ-A
SW_PVCCIN_CPU1_BOOT1     PR1767           1        Q_RES_0402LF-3.3,1%,1/16W,CHIPA
SW_PVCCIN_CPU1_BOOT1     PU31_P1_1        33       ISL99390FRZTR5935-ISL99390FRZ-A
SW_PVCCIN_CPU1_BOOT1_R   PC565            1        Q_CAP_C0402-100NF,50V,10%,X7R,A
SW_PVCCIN_CPU1_BOOT1_R   PR1767           2        Q_RES_0402LF-3.3,1%,1/16W,CHIPA
SW_PVCCIN_CPU1_BOOT2     PR1766           1        Q_RES_0402LF-3.3,1%,1/16W,CHIPA
SW_PVCCIN_CPU1_BOOT2     PU30_P1_2        33       ISL99390FRZTR5935-ISL99390FRZ-A
SW_PVCCIN_CPU1_BOOT2_R   PC564            1        Q_CAP_C0402-100NF,50V,10%,X7R,A
SW_PVCCIN_CPU1_BOOT2_R   PR1766           2        Q_RES_0402LF-3.3,1%,1/16W,CHIPA
SW_PVCCIN_CPU1_BOOT3     PR1789           1        Q_RES_0402LF-3.3,1%,1/16W,CHIPA
SW_PVCCIN_CPU1_BOOT3     PU28_P1_3        33       ISL99390FRZTR5935-ISL99390FRZ-A
SW_PVCCIN_CPU1_BOOT3_R   PC532            1        Q_CAP_C0402-100NF,50V,10%,X7R,A
SW_PVCCIN_CPU1_BOOT3_R   PR1789           2        Q_RES_0402LF-3.3,1%,1/16W,CHIPA
SW_PVCCIN_CPU1_BOOT4     PR1788           1        Q_RES_0402LF-3.3,1%,1/16W,CHIPA
SW_PVCCIN_CPU1_BOOT4     PU27_P1_4        33       ISL99390FRZTR5935-ISL99390FRZ-A
SW_PVCCIN_CPU1_BOOT4_R   PC531            1        Q_CAP_C0402-100NF,50V,10%,X7R,A
SW_PVCCIN_CPU1_BOOT4_R   PR1788           2        Q_RES_0402LF-3.3,1%,1/16W,CHIPA
SW_PVCCIN_CPU1_BOOT5     PR1791           1        Q_RES_0402LF-3.3,1%,1/16W,CHIPA
SW_PVCCIN_CPU1_BOOT5     PU26_P1_5        33       ISL99390FRZTR5935-ISL99390FRZ-A
SW_PVCCIN_CPU1_BOOT5_R   PC510            1        Q_CAP_C0402-100NF,50V,10%,X7R,A
SW_PVCCIN_CPU1_BOOT5_R   PR1791           2        Q_RES_0402LF-3.3,1%,1/16W,CHIPA
SW_PVCCIN_CPU1_BOOT6     PR1790           1        Q_RES_0402LF-3.3,1%,1/16W,CHIPA
SW_PVCCIN_CPU1_BOOT6     PU25_P1_6        33       ISL99390FRZTR5935-ISL99390FRZ-A
SW_PVCCIN_CPU1_BOOT6_R   PC509            1        Q_CAP_C0402-100NF,50V,10%,X7R,A
SW_PVCCIN_CPU1_BOOT6_R   PR1790           2        Q_RES_0402LF-3.3,1%,1/16W,CHIPA
SW_PVCCIN_CPU1_BOOT7     PR1793           1        Q_RES_0402LF-3.3,1%,1/16W,CHIPA
SW_PVCCIN_CPU1_BOOT7     PU24_P1_7        33       ISL99390FRZTR5935-ISL99390FRZ-A
SW_PVCCIN_CPU1_BOOT7_R   PC488            1        Q_CAP_C0402-100NF,50V,10%,X7R,A
SW_PVCCIN_CPU1_BOOT7_R   PR1793           2        Q_RES_0402LF-3.3,1%,1/16W,CHIPA
SW_PVCCIN_CPU1_BOOT8     PR1792           1        Q_RES_0402LF-3.3,1%,1/16W,CHIPA
SW_PVCCIN_CPU1_BOOT8     PU23_P1_8        33       ISL99390FRZTR5935-ISL99390FRZ-A
SW_PVCCIN_CPU1_BOOT8_R   PC487            1        Q_CAP_C0402-100NF,50V,10%,X7R,A
SW_PVCCIN_CPU1_BOOT8_R   PR1792           2        Q_RES_0402LF-3.3,1%,1/16W,CHIPA
SW_PVCCIN_CPU1_BOOTR1    PC565            2        Q_CAP_C0402-100NF,50V,10%,X7R,A
SW_PVCCIN_CPU1_BOOTR1    PU31_P1_1        32       ISL99390FRZTR5935-ISL99390FRZ-A
SW_PVCCIN_CPU1_BOOTR2    PC564            2        Q_CAP_C0402-100NF,50V,10%,X7R,A
SW_PVCCIN_CPU1_BOOTR2    PU30_P1_2        32       ISL99390FRZTR5935-ISL99390FRZ-A
SW_PVCCIN_CPU1_BOOTR3    PC532            2        Q_CAP_C0402-100NF,50V,10%,X7R,A
SW_PVCCIN_CPU1_BOOTR3    PU28_P1_3        32       ISL99390FRZTR5935-ISL99390FRZ-A
SW_PVCCIN_CPU1_BOOTR4    PC531            2        Q_CAP_C0402-100NF,50V,10%,X7R,A
SW_PVCCIN_CPU1_BOOTR4    PU27_P1_4        32       ISL99390FRZTR5935-ISL99390FRZ-A
SW_PVCCIN_CPU1_BOOTR5    PC510            2        Q_CAP_C0402-100NF,50V,10%,X7R,A
SW_PVCCIN_CPU1_BOOTR5    PU26_P1_5        32       ISL99390FRZTR5935-ISL99390FRZ-A
SW_PVCCIN_CPU1_BOOTR6    PC509            2        Q_CAP_C0402-100NF,50V,10%,X7R,A
SW_PVCCIN_CPU1_BOOTR6    PU25_P1_6        32       ISL99390FRZTR5935-ISL99390FRZ-A
SW_PVCCIN_CPU1_BOOTR7    PC488            2        Q_CAP_C0402-100NF,50V,10%,X7R,A
SW_PVCCIN_CPU1_BOOTR7    PU24_P1_7        32       ISL99390FRZTR5935-ISL99390FRZ-A
SW_PVCCIN_CPU1_BOOTR8    PC487            2        Q_CAP_C0402-100NF,50V,10%,X7R,A
SW_PVCCIN_CPU1_BOOTR8    PU23_P1_8        32       ISL99390FRZTR5935-ISL99390FRZ-A
SW_PVCCIN_CPU1_SW1       PL31             1        Q_INDUCTOR4P_14-150NH,SMLF,INDA
SW_PVCCIN_CPU1_SW1       PU31_P1_1        10_19    ISL99390FRZTR5935-ISL99390FRZ-A
SW_PVCCIN_CPU1_SW2       PL30             1        Q_INDUCTOR4P_14-150NH,SMLF,INDA
SW_PVCCIN_CPU1_SW2       PU30_P1_2        10_19    ISL99390FRZTR5935-ISL99390FRZ-A
SW_PVCCIN_CPU1_SW3       PL29             1        Q_INDUCTOR4P_14-150NH,SMLF,INDA
SW_PVCCIN_CPU1_SW3       PU28_P1_3        10_19    ISL99390FRZTR5935-ISL99390FRZ-A
SW_PVCCIN_CPU1_SW4       PL28             1        Q_INDUCTOR4P_14-150NH,SMLF,INDA
SW_PVCCIN_CPU1_SW4       PU27_P1_4        10_19    ISL99390FRZTR5935-ISL99390FRZ-A
SW_PVCCIN_CPU1_SW5       PL27             1        Q_INDUCTOR4P_14-150NH,SMLF,INDA
SW_PVCCIN_CPU1_SW5       PU26_P1_5        10_19    ISL99390FRZTR5935-ISL99390FRZ-A
SW_PVCCIN_CPU1_SW6       PL26             1        Q_INDUCTOR4P_14-150NH,SMLF,INDA
SW_PVCCIN_CPU1_SW6       PU25_P1_6        10_19    ISL99390FRZTR5935-ISL99390FRZ-A
SW_PVCCIN_CPU1_SW7       PL25             1        Q_INDUCTOR4P_14-150NH,SMLF,INDA
SW_PVCCIN_CPU1_SW7       PU24_P1_7        10_19    ISL99390FRZTR5935-ISL99390FRZ-A
SW_PVCCIN_CPU1_SW8       PL24             1        Q_INDUCTOR4P_14-150NH,SMLF,INDA
SW_PVCCIN_CPU1_SW8       PU23_P1_8        10_19    ISL99390FRZTR5935-ISL99390FRZ-A
SW_PVNN_MAIN_CPU0_BST    PC1275           1        Q_CAP_0402-0.22UF,16V,10%,X7R,A
SW_PVNN_MAIN_CPU0_BST    PU81             10       MPQ8626GDZ-MPQ8626GD-Z,SMLF,ICA
SW_PVNN_MAIN_CPU0_SW     PC1275           2        Q_CAP_0402-0.22UF,16V,10%,X7R,A
SW_PVNN_MAIN_CPU0_SW     PL120            1        Q_INDUCTOR_SMLF-1UH,IND,CV-10BA
SW_PVNN_MAIN_CPU0_SW     PU81             2        MPQ8626GDZ-MPQ8626GD-Z,SMLF,ICA
SW_PVNN_MAIN_CPU0_SW     PU81             11       MPQ8626GDZ-MPQ8626GD-Z,SMLF,ICA
SW_PVNN_MAIN_CPU1_BST    PC1283           1        Q_CAP_0402-0.22UF,16V,10%,X7R,A
SW_PVNN_MAIN_CPU1_BST    PU82             10       MPQ8626GDZ-MPQ8626GD-Z,SMLF,ICA
SW_PVNN_MAIN_CPU1_SW     PC1283           2        Q_CAP_0402-0.22UF,16V,10%,X7R,A
SW_PVNN_MAIN_CPU1_SW     PL121            1        Q_INDUCTOR_SMLF-1UH,IND,CV-10BA
SW_PVNN_MAIN_CPU1_SW     PU82             2        MPQ8626GDZ-MPQ8626GD-Z,SMLF,ICA
SW_PVNN_MAIN_CPU1_SW     PU82             11       MPQ8626GDZ-MPQ8626GD-Z,SMLF,ICA
SW_PVPP_HBM_CPU0_BST     PC1252           1        Q_CAP_0402-0.22UF,16V,10%,EMPTA
SW_PVPP_HBM_CPU0_BST     PU79             1        MPQ8633AGLEC807Z-MPQ8633AGLE-CA
SW_PVPP_HBM_CPU0_SW      PC1252           2        Q_CAP_0402-0.22UF,16V,10%,EMPTA
SW_PVPP_HBM_CPU0_SW      PL118            1        Q_INDUCTOR_SMLF-1UH,EMPTY,CV-1A
SW_PVPP_HBM_CPU0_SW      PU79             20       MPQ8633AGLEC807Z-MPQ8633AGLE-CA
SW_PVPP_HBM_CPU1_BST     PC1265           1        Q_CAP_0402-0.22UF,16V,10%,X7R,A
SW_PVPP_HBM_CPU1_BST     PU80             1        MPQ8633AGLEC807Z-MPQ8633AGLE-CB
SW_PVPP_HBM_CPU1_SW      PC1265           2        Q_CAP_0402-0.22UF,16V,10%,X7R,A
SW_PVPP_HBM_CPU1_SW      PL119            1        Q_INDUCTOR_SMLF-1UH,IND,CV-10BA
SW_PVPP_HBM_CPU1_SW      PU80             20       MPQ8633AGLEC807Z-MPQ8633AGLE-CB
TDR_DIFF_100_BOT_DN      X18              4        TP_TDR_4P_FTS_TH-TP_TDR_4P_DIPA
TDR_DIFF_100_BOT_DN      X24              1        TP_TDR_4P_FTS_TH-TP_TDR_4P_DIPA
TDR_DIFF_100_BOT_DP      X18              1        TP_TDR_4P_FTS_TH-TP_TDR_4P_DIPA
TDR_DIFF_100_BOT_DP      X24              4        TP_TDR_4P_FTS_TH-TP_TDR_4P_DIPA
TDR_DIFF_100_IN1_DN      X14              4        TP_TDR_4P_FTS_TH-TP_TDR_4P_DIPA
TDR_DIFF_100_IN1_DN      X20              1        TP_TDR_4P_FTS_TH-TP_TDR_4P_DIPA
TDR_DIFF_100_IN1_DP      X14              1        TP_TDR_4P_FTS_TH-TP_TDR_4P_DIPA
TDR_DIFF_100_IN1_DP      X20              4        TP_TDR_4P_FTS_TH-TP_TDR_4P_DIPA
TDR_DIFF_100_IN2_DN      X15              4        TP_TDR_4P_FTS_TH-TP_TDR_4P_DIPA
TDR_DIFF_100_IN2_DN      X21              1        TP_TDR_4P_FTS_TH-TP_TDR_4P_DIPA
TDR_DIFF_100_IN2_DP      X15              1        TP_TDR_4P_FTS_TH-TP_TDR_4P_DIPA
TDR_DIFF_100_IN2_DP      X21              4        TP_TDR_4P_FTS_TH-TP_TDR_4P_DIPA
TDR_DIFF_100_IN3_DN      X16              4        TP_TDR_4P_FTS_TH-TP_TDR_4P_DIPA
TDR_DIFF_100_IN3_DN      X22              1        TP_TDR_4P_FTS_TH-TP_TDR_4P_DIPA
TDR_DIFF_100_IN3_DP      X16              1        TP_TDR_4P_FTS_TH-TP_TDR_4P_DIPA
TDR_DIFF_100_IN3_DP      X22              4        TP_TDR_4P_FTS_TH-TP_TDR_4P_DIPA
TDR_DIFF_100_IN4_DN      X17              4        TP_TDR_4P_FTS_TH-TP_TDR_4P_DIPA
TDR_DIFF_100_IN4_DN      X23              1        TP_TDR_4P_FTS_TH-TP_TDR_4P_DIPA
TDR_DIFF_100_IN4_DP      X17              1        TP_TDR_4P_FTS_TH-TP_TDR_4P_DIPA
TDR_DIFF_100_IN4_DP      X23              4        TP_TDR_4P_FTS_TH-TP_TDR_4P_DIPA
TDR_DIFF_100_TOP_DN      X13              4        TP_TDR_4P_FTS_TH-TP_TDR_4P_DIPA
TDR_DIFF_100_TOP_DN      X19              1        TP_TDR_4P_FTS_TH-TP_TDR_4P_DIPA
TDR_DIFF_100_TOP_DP      X13              1        TP_TDR_4P_FTS_TH-TP_TDR_4P_DIPA
TDR_DIFF_100_TOP_DP      X19              4        TP_TDR_4P_FTS_TH-TP_TDR_4P_DIPA
TDR_DIFF_85_BOT_DN       X6               4        TP_TDR_4P_FTS_TH-TP_TDR_4P_DIPA
TDR_DIFF_85_BOT_DN       X12              1        TP_TDR_4P_FTS_TH-TP_TDR_4P_DIPA
TDR_DIFF_85_BOT_DP       X6               1        TP_TDR_4P_FTS_TH-TP_TDR_4P_DIPA
TDR_DIFF_85_BOT_DP       X12              4        TP_TDR_4P_FTS_TH-TP_TDR_4P_DIPA
TDR_DIFF_85_IN1_DN       X2               4        TP_TDR_4P_FTS_TH-TP_TDR_4P_DIPA
TDR_DIFF_85_IN1_DN       X8               1        TP_TDR_4P_FTS_TH-TP_TDR_4P_DIPA
TDR_DIFF_85_IN1_DP       X2               1        TP_TDR_4P_FTS_TH-TP_TDR_4P_DIPA
TDR_DIFF_85_IN1_DP       X8               4        TP_TDR_4P_FTS_TH-TP_TDR_4P_DIPA
TDR_DIFF_85_IN2_DN       X3               4        TP_TDR_4P_FTS_TH-TP_TDR_4P_DIPA
TDR_DIFF_85_IN2_DN       X9               1        TP_TDR_4P_FTS_TH-TP_TDR_4P_DIPA
TDR_DIFF_85_IN2_DP       X3               1        TP_TDR_4P_FTS_TH-TP_TDR_4P_DIPA
TDR_DIFF_85_IN2_DP       X9               4        TP_TDR_4P_FTS_TH-TP_TDR_4P_DIPA
TDR_DIFF_85_IN3_DN       X4               4        TP_TDR_4P_FTS_TH-TP_TDR_4P_DIPA
TDR_DIFF_85_IN3_DN       X10              1        TP_TDR_4P_FTS_TH-TP_TDR_4P_DIPA
TDR_DIFF_85_IN3_DP       X4               1        TP_TDR_4P_FTS_TH-TP_TDR_4P_DIPA
TDR_DIFF_85_IN3_DP       X10              4        TP_TDR_4P_FTS_TH-TP_TDR_4P_DIPA
TDR_DIFF_85_IN4_DN       X5               4        TP_TDR_4P_FTS_TH-TP_TDR_4P_DIPA
TDR_DIFF_85_IN4_DN       X11              1        TP_TDR_4P_FTS_TH-TP_TDR_4P_DIPA
TDR_DIFF_85_IN4_DP       X5               1        TP_TDR_4P_FTS_TH-TP_TDR_4P_DIPA
TDR_DIFF_85_IN4_DP       X11              4        TP_TDR_4P_FTS_TH-TP_TDR_4P_DIPA
TDR_DIFF_85_TOP_DN       X1               4        TP_TDR_4P_FTS_TH-TP_TDR_4P_DIPA
TDR_DIFF_85_TOP_DN       X7               1        TP_TDR_4P_FTS_TH-TP_TDR_4P_DIPA
TDR_DIFF_85_TOP_DP       X1               1        TP_TDR_4P_FTS_TH-TP_TDR_4P_DIPA
TDR_DIFF_85_TOP_DP       X7               4        TP_TDR_4P_FTS_TH-TP_TDR_4P_DIPA
TDR_SE_40_OHM_BOT        DB6              2        TDR_3P_TH2-EMPTY,N_A
TDR_SE_40_OHM_BOT        DB6              3        TDR_3P_TH2-EMPTY,N_A
TDR_SE_40_OHM_IN1        DB2              2        TDR_3P_TH2-EMPTY,N_A
TDR_SE_40_OHM_IN1        DB2              3        TDR_3P_TH2-EMPTY,N_A
TDR_SE_40_OHM_IN2        DB3              2        TDR_3P_TH2-EMPTY,N_A
TDR_SE_40_OHM_IN2        DB3              3        TDR_3P_TH2-EMPTY,N_A
TDR_SE_40_OHM_IN3        DB4              2        TDR_3P_TH2-EMPTY,N_A
TDR_SE_40_OHM_IN3        DB4              3        TDR_3P_TH2-EMPTY,N_A
TDR_SE_40_OHM_IN4        DB5              2        TDR_3P_TH2-EMPTY,N_A
TDR_SE_40_OHM_IN4        DB5              3        TDR_3P_TH2-EMPTY,N_A
TDR_SE_40_OHM_TOP        DB1              2        TDR_3P_TH2-EMPTY,N_A
TDR_SE_40_OHM_TOP        DB1              3        TDR_3P_TH2-EMPTY,N_A
TDR_SE_50_OHM_BOT        DB12             2        TDR_3P_TH2-EMPTY,N_A
TDR_SE_50_OHM_BOT        DB12             3        TDR_3P_TH2-EMPTY,N_A
TDR_SE_50_OHM_IN1        DB8              2        TDR_3P_TH2-EMPTY,N_A
TDR_SE_50_OHM_IN1        DB8              3        TDR_3P_TH2-EMPTY,N_A
TDR_SE_50_OHM_IN2        DB9              2        TDR_3P_TH2-EMPTY,N_A
TDR_SE_50_OHM_IN2        DB9              3        TDR_3P_TH2-EMPTY,N_A
TDR_SE_50_OHM_IN3        DB10             2        TDR_3P_TH2-EMPTY,N_A
TDR_SE_50_OHM_IN3        DB10             3        TDR_3P_TH2-EMPTY,N_A
TDR_SE_50_OHM_IN4        DB11             2        TDR_3P_TH2-EMPTY,N_A
TDR_SE_50_OHM_IN4        DB11             3        TDR_3P_TH2-EMPTY,N_A
TDR_SE_50_OHM_TOP        DB7              2        TDR_3P_TH2-EMPTY,N_A
TDR_SE_50_OHM_TOP        DB7              3        TDR_3P_TH2-EMPTY,N_A
TMP75_1_ADDR0            R719             2        Q_RES_0402LF-10K,1%,1/16W,CHIPA
TMP75_1_ADDR0            R720             1        Q_RES_0402LF-1K,1%,1/16W,EMPTYA
TMP75_1_ADDR0            U63              7        TMP75AIDR-TMP75AIDR,SMLF,IC,ALA
TMP75_1_ADDR1            R715             2        Q_RES_0402LF-10K,1%,1/16W,EMPTA
TMP75_1_ADDR1            R716             1        Q_RES_0402LF-1K,1%,1/16W,CHIP,A
TMP75_1_ADDR1            U63              6        TMP75AIDR-TMP75AIDR,SMLF,IC,ALA
TMP75_1_ADDR2            R711             2        Q_RES_0402LF-10K,1%,1/16W,EMPTA
TMP75_1_ADDR2            R712             1        Q_RES_0402LF-1K,1%,1/16W,CHIP,A
TMP75_1_ADDR2            U63              5        TMP75AIDR-TMP75AIDR,SMLF,IC,ALA
TMP75_2_ADDR0            R732             2        Q_RES_0402LF-10K,1%,1/16W,EMPTA
TMP75_2_ADDR0            R733             1        Q_RES_0402LF-1K,1%,1/16W,CHIP,A
TMP75_2_ADDR0            U65              7        TMP75AIDR-TMP75AIDR,SMLF,IC,ALA
TMP75_2_ADDR1            R730             2        Q_RES_0402LF-10K,1%,1/16W,CHIPA
TMP75_2_ADDR1            R731             1        Q_RES_0402LF-1K,1%,1/16W,EMPTYA
TMP75_2_ADDR1            U65              6        TMP75AIDR-TMP75AIDR,SMLF,IC,ALA
TMP75_2_ADDR2            R728             2        Q_RES_0402LF-10K,1%,1/16W,EMPTA
TMP75_2_ADDR2            R729             1        Q_RES_0402LF-1K,1%,1/16W,CHIP,A
TMP75_2_ADDR2            U65              5        TMP75AIDR-TMP75AIDR,SMLF,IC,ALA
TP_MP5981_0_IMON         R2141            1        Q_RES_0402LF-2.4K,1%,1/16W,CHIA
TP_MP5981_0_IMON         U107             22       MP5981GLUZ-MP5981GLU-Z,SMLF,ICA
TP_MP5981_1_IMON         R2142            1        Q_RES_0402LF-2.4K,1%,1/16W,CHIA
TP_MP5981_1_IMON         U81              22       MP5981GLUZ-MP5981GLU-Z,SMLF,ICA
T_GND                    DB1              1        TDR_3P_TH2-EMPTY,N_A
T_GND                    DB2              1        TDR_3P_TH2-EMPTY,N_A
T_GND                    DB3              1        TDR_3P_TH2-EMPTY,N_A
T_GND                    DB4              1        TDR_3P_TH2-EMPTY,N_A
T_GND                    DB5              1        TDR_3P_TH2-EMPTY,N_A
T_GND                    DB6              1        TDR_3P_TH2-EMPTY,N_A
T_GND                    DB7              1        TDR_3P_TH2-EMPTY,N_A
T_GND                    DB8              1        TDR_3P_TH2-EMPTY,N_A
T_GND                    DB9              1        TDR_3P_TH2-EMPTY,N_A
T_GND                    DB10             1        TDR_3P_TH2-EMPTY,N_A
T_GND                    DB11             1        TDR_3P_TH2-EMPTY,N_A
T_GND                    DB12             1        TDR_3P_TH2-EMPTY,N_A
T_GND                    X1               2        TP_TDR_4P_FTS_TH-TP_TDR_4P_DIPA
T_GND                    X1               3        TP_TDR_4P_FTS_TH-TP_TDR_4P_DIPA
T_GND                    X2               2        TP_TDR_4P_FTS_TH-TP_TDR_4P_DIPA
T_GND                    X2               3        TP_TDR_4P_FTS_TH-TP_TDR_4P_DIPA
T_GND                    X3               2        TP_TDR_4P_FTS_TH-TP_TDR_4P_DIPA
T_GND                    X3               3        TP_TDR_4P_FTS_TH-TP_TDR_4P_DIPA
T_GND                    X4               2        TP_TDR_4P_FTS_TH-TP_TDR_4P_DIPA
T_GND                    X4               3        TP_TDR_4P_FTS_TH-TP_TDR_4P_DIPA
T_GND                    X5               2        TP_TDR_4P_FTS_TH-TP_TDR_4P_DIPA
T_GND                    X5               3        TP_TDR_4P_FTS_TH-TP_TDR_4P_DIPA
T_GND                    X6               2        TP_TDR_4P_FTS_TH-TP_TDR_4P_DIPA
T_GND                    X6               3        TP_TDR_4P_FTS_TH-TP_TDR_4P_DIPA
T_GND                    X7               2        TP_TDR_4P_FTS_TH-TP_TDR_4P_DIPA
T_GND                    X7               3        TP_TDR_4P_FTS_TH-TP_TDR_4P_DIPA
T_GND                    X8               2        TP_TDR_4P_FTS_TH-TP_TDR_4P_DIPA
T_GND                    X8               3        TP_TDR_4P_FTS_TH-TP_TDR_4P_DIPA
T_GND                    X9               2        TP_TDR_4P_FTS_TH-TP_TDR_4P_DIPA
T_GND                    X9               3        TP_TDR_4P_FTS_TH-TP_TDR_4P_DIPA
T_GND                    X10              2        TP_TDR_4P_FTS_TH-TP_TDR_4P_DIPA
T_GND                    X10              3        TP_TDR_4P_FTS_TH-TP_TDR_4P_DIPA
T_GND                    X11              2        TP_TDR_4P_FTS_TH-TP_TDR_4P_DIPA
T_GND                    X11              3        TP_TDR_4P_FTS_TH-TP_TDR_4P_DIPA
T_GND                    X12              2        TP_TDR_4P_FTS_TH-TP_TDR_4P_DIPA
T_GND                    X12              3        TP_TDR_4P_FTS_TH-TP_TDR_4P_DIPA
T_GND                    X13              2        TP_TDR_4P_FTS_TH-TP_TDR_4P_DIPA
T_GND                    X13              3        TP_TDR_4P_FTS_TH-TP_TDR_4P_DIPA
T_GND                    X14              2        TP_TDR_4P_FTS_TH-TP_TDR_4P_DIPA
T_GND                    X14              3        TP_TDR_4P_FTS_TH-TP_TDR_4P_DIPA
T_GND                    X15              2        TP_TDR_4P_FTS_TH-TP_TDR_4P_DIPA
T_GND                    X15              3        TP_TDR_4P_FTS_TH-TP_TDR_4P_DIPA
T_GND                    X16              2        TP_TDR_4P_FTS_TH-TP_TDR_4P_DIPA
T_GND                    X16              3        TP_TDR_4P_FTS_TH-TP_TDR_4P_DIPA
T_GND                    X17              2        TP_TDR_4P_FTS_TH-TP_TDR_4P_DIPA
T_GND                    X17              3        TP_TDR_4P_FTS_TH-TP_TDR_4P_DIPA
T_GND                    X18              2        TP_TDR_4P_FTS_TH-TP_TDR_4P_DIPA
T_GND                    X18              3        TP_TDR_4P_FTS_TH-TP_TDR_4P_DIPA
T_GND                    X19              2        TP_TDR_4P_FTS_TH-TP_TDR_4P_DIPA
T_GND                    X19              3        TP_TDR_4P_FTS_TH-TP_TDR_4P_DIPA
T_GND                    X20              2        TP_TDR_4P_FTS_TH-TP_TDR_4P_DIPA
T_GND                    X20              3        TP_TDR_4P_FTS_TH-TP_TDR_4P_DIPA
T_GND                    X21              2        TP_TDR_4P_FTS_TH-TP_TDR_4P_DIPA
T_GND                    X21              3        TP_TDR_4P_FTS_TH-TP_TDR_4P_DIPA
T_GND                    X22              2        TP_TDR_4P_FTS_TH-TP_TDR_4P_DIPA
T_GND                    X22              3        TP_TDR_4P_FTS_TH-TP_TDR_4P_DIPA
T_GND                    X23              2        TP_TDR_4P_FTS_TH-TP_TDR_4P_DIPA
T_GND                    X23              3        TP_TDR_4P_FTS_TH-TP_TDR_4P_DIPA
T_GND                    X24              2        TP_TDR_4P_FTS_TH-TP_TDR_4P_DIPA
T_GND                    X24              3        TP_TDR_4P_FTS_TH-TP_TDR_4P_DIPA
UNNAMED_222_QRES_I129_A  R655             1        Q_RES_0402LF-2.2K ,5%,1/16W,CHA
UNNAMED_222_QRES_I129_A  R656             1        Q_RES_0402LF-2.2K ,5%,1/16W,CHA
UNNAMED_222_QRES_I129_A  R657             1        Q_RES_0402LF-2.2K ,5%,1/16W,EMA
UNNAMED_222_QRES_I129_A  R658             1        Q_RES_0402LF-2.2K ,5%,1/16W,EMA
UPI_CPU0_CPU1_P0P1_DN<0> U1               EH2      SOCKET4677_AZIFS054P001C01-SOCA
UPI_CPU0_CPU1_P0P1_DN<0> U2               K4       SOCKET4677_AZIFS054P001C01-SOCA
UPI_CPU0_CPU1_P0P1_DN<1> U1               EE3      SOCKET4677_AZIFS054P001C01-SOCA
UPI_CPU0_CPU1_P0P1_DN<1> U2               M2       SOCKET4677_AZIFS054P001C01-SOCA
UPI_CPU0_CPU1_P0P1_DN<2> U1               ED2      SOCKET4677_AZIFS054P001C01-SOCA
UPI_CPU0_CPU1_P0P1_DN<2> U2               N1       SOCKET4677_AZIFS054P001C01-SOCA
UPI_CPU0_CPU1_P0P1_DN<3> U1               EA1      SOCKET4677_AZIFS054P001C01-SOCA
UPI_CPU0_CPU1_P0P1_DN<3> U2               T2       SOCKET4677_AZIFS054P001C01-SOCA
UPI_CPU0_CPU1_P0P1_DN<4> U1               DY2      SOCKET4677_AZIFS054P001C01-SOCA
UPI_CPU0_CPU1_P0P1_DN<4> U2               U1       SOCKET4677_AZIFS054P001C01-SOCA
UPI_CPU0_CPU1_P0P1_DN<5> U1               DU1      SOCKET4677_AZIFS054P001C01-SOCA
UPI_CPU0_CPU1_P0P1_DN<5> U2               Y2       SOCKET4677_AZIFS054P001C01-SOCA
UPI_CPU0_CPU1_P0P1_DN<6> U1               DT2      SOCKET4677_AZIFS054P001C01-SOCA
UPI_CPU0_CPU1_P0P1_DN<6> U2               AA1      SOCKET4677_AZIFS054P001C01-SOCA
UPI_CPU0_CPU1_P0P1_DN<7> U1               DN1      SOCKET4677_AZIFS054P001C01-SOCA
UPI_CPU0_CPU1_P0P1_DN<7> U2               AD2      SOCKET4677_AZIFS054P001C01-SOCA
UPI_CPU0_CPU1_P0P1_DN<8> U1               DL3      SOCKET4677_AZIFS054P001C01-SOCA
UPI_CPU0_CPU1_P0P1_DN<8> U2               AF2      SOCKET4677_AZIFS054P001C01-SOCA
UPI_CPU0_CPU1_P0P1_DN<9> U1               DJ1      SOCKET4677_AZIFS054P001C01-SOCA
UPI_CPU0_CPU1_P0P1_DN<9> U2               AH2      SOCKET4677_AZIFS054P001C01-SOCA
UPI_CPU0_CPU1_P0P1_DN<10> U1               DG3      SOCKET4677_AZIFS054P001C01-SOCA
UPI_CPU0_CPU1_P0P1_DN<10> U2               AK2      SOCKET4677_AZIFS054P001C01-SOCA
UPI_CPU0_CPU1_P0P1_DN<11> U1               DE1      SOCKET4677_AZIFS054P001C01-SOCA
UPI_CPU0_CPU1_P0P1_DN<11> U2               AM2      SOCKET4677_AZIFS054P001C01-SOCA
UPI_CPU0_CPU1_P0P1_DN<12> U1               DD2      SOCKET4677_AZIFS054P001C01-SOCA
UPI_CPU0_CPU1_P0P1_DN<12> U2               AN1      SOCKET4677_AZIFS054P001C01-SOCA
UPI_CPU0_CPU1_P0P1_DN<13> U1               DB2      SOCKET4677_AZIFS054P001C01-SOCA
UPI_CPU0_CPU1_P0P1_DN<13> U2               AR3      SOCKET4677_AZIFS054P001C01-SOCA
UPI_CPU0_CPU1_P0P1_DN<14> U1               CY2      SOCKET4677_AZIFS054P001C01-SOCA
UPI_CPU0_CPU1_P0P1_DN<14> U2               AU1      SOCKET4677_AZIFS054P001C01-SOCA
UPI_CPU0_CPU1_P0P1_DN<15> U1               CV2      SOCKET4677_AZIFS054P001C01-SOCA
UPI_CPU0_CPU1_P0P1_DN<15> U2               AW3      SOCKET4677_AZIFS054P001C01-SOCA
UPI_CPU0_CPU1_P0P1_DN<16> U1               CR3      SOCKET4677_AZIFS054P001C01-SOCA
UPI_CPU0_CPU1_P0P1_DN<16> U2               BB2      SOCKET4677_AZIFS054P001C01-SOCA
UPI_CPU0_CPU1_P0P1_DN<17> U1               CN1      SOCKET4677_AZIFS054P001C01-SOCA
UPI_CPU0_CPU1_P0P1_DN<17> U2               BD2      SOCKET4677_AZIFS054P001C01-SOCA
UPI_CPU0_CPU1_P0P1_DN<18> U1               CL3      SOCKET4677_AZIFS054P001C01-SOCA
UPI_CPU0_CPU1_P0P1_DN<18> U2               BF2      SOCKET4677_AZIFS054P001C01-SOCA
UPI_CPU0_CPU1_P0P1_DN<19> U1               CJ1      SOCKET4677_AZIFS054P001C01-SOCA
UPI_CPU0_CPU1_P0P1_DN<19> U2               BH2      SOCKET4677_AZIFS054P001C01-SOCA
UPI_CPU0_CPU1_P0P1_DN<20> U1               CH2      SOCKET4677_AZIFS054P001C01-SOCA
UPI_CPU0_CPU1_P0P1_DN<20> U2               BJ1      SOCKET4677_AZIFS054P001C01-SOCA
UPI_CPU0_CPU1_P0P1_DN<21> U1               CF2      SOCKET4677_AZIFS054P001C01-SOCA
UPI_CPU0_CPU1_P0P1_DN<21> U2               BL3      SOCKET4677_AZIFS054P001C01-SOCA
UPI_CPU0_CPU1_P0P1_DN<22> U1               CD2      SOCKET4677_AZIFS054P001C01-SOCA
UPI_CPU0_CPU1_P0P1_DN<22> U2               BN3      SOCKET4677_AZIFS054P001C01-SOCA
UPI_CPU0_CPU1_P0P1_DN<23> U1               CB2      SOCKET4677_AZIFS054P001C01-SOCA
UPI_CPU0_CPU1_P0P1_DN<23> U2               BT2      SOCKET4677_AZIFS054P001C01-SOCA
UPI_CPU0_CPU1_P0P1_DP<0> U1               EJ3      SOCKET4677_AZIFS054P001C01-SOCA
UPI_CPU0_CPU1_P0P1_DP<0> U2               J3       SOCKET4677_AZIFS054P001C01-SOCA
UPI_CPU0_CPU1_P0P1_DP<1> U1               EG3      SOCKET4677_AZIFS054P001C01-SOCA
UPI_CPU0_CPU1_P0P1_DP<1> U2               L3       SOCKET4677_AZIFS054P001C01-SOCA
UPI_CPU0_CPU1_P0P1_DP<2> U1               EC3      SOCKET4677_AZIFS054P001C01-SOCA
UPI_CPU0_CPU1_P0P1_DP<2> U2               P2       SOCKET4677_AZIFS054P001C01-SOCA
UPI_CPU0_CPU1_P0P1_DP<3> U1               EB2      SOCKET4677_AZIFS054P001C01-SOCA
UPI_CPU0_CPU1_P0P1_DP<3> U2               R3       SOCKET4677_AZIFS054P001C01-SOCA
UPI_CPU0_CPU1_P0P1_DP<4> U1               DW3      SOCKET4677_AZIFS054P001C01-SOCA
UPI_CPU0_CPU1_P0P1_DP<4> U2               V2       SOCKET4677_AZIFS054P001C01-SOCA
UPI_CPU0_CPU1_P0P1_DP<5> U1               DV2      SOCKET4677_AZIFS054P001C01-SOCA
UPI_CPU0_CPU1_P0P1_DP<5> U2               W3       SOCKET4677_AZIFS054P001C01-SOCA
UPI_CPU0_CPU1_P0P1_DP<6> U1               DR3      SOCKET4677_AZIFS054P001C01-SOCA
UPI_CPU0_CPU1_P0P1_DP<6> U2               AB2      SOCKET4677_AZIFS054P001C01-SOCA
UPI_CPU0_CPU1_P0P1_DP<7> U1               DP2      SOCKET4677_AZIFS054P001C01-SOCA
UPI_CPU0_CPU1_P0P1_DP<7> U2               AC3      SOCKET4677_AZIFS054P001C01-SOCA
UPI_CPU0_CPU1_P0P1_DP<8> U1               DM2      SOCKET4677_AZIFS054P001C01-SOCA
UPI_CPU0_CPU1_P0P1_DP<8> U2               AE1      SOCKET4677_AZIFS054P001C01-SOCA
UPI_CPU0_CPU1_P0P1_DP<9> U1               DK2      SOCKET4677_AZIFS054P001C01-SOCA
UPI_CPU0_CPU1_P0P1_DP<9> U2               AG3      SOCKET4677_AZIFS054P001C01-SOCA
UPI_CPU0_CPU1_P0P1_DP<10> U1               DH2      SOCKET4677_AZIFS054P001C01-SOCA
UPI_CPU0_CPU1_P0P1_DP<10> U2               AJ1      SOCKET4677_AZIFS054P001C01-SOCA
UPI_CPU0_CPU1_P0P1_DP<11> U1               DF2      SOCKET4677_AZIFS054P001C01-SOCA
UPI_CPU0_CPU1_P0P1_DP<11> U2               AL3      SOCKET4677_AZIFS054P001C01-SOCA
UPI_CPU0_CPU1_P0P1_DP<12> U1               DC3      SOCKET4677_AZIFS054P001C01-SOCA
UPI_CPU0_CPU1_P0P1_DP<12> U2               AP2      SOCKET4677_AZIFS054P001C01-SOCA
UPI_CPU0_CPU1_P0P1_DP<13> U1               DA1      SOCKET4677_AZIFS054P001C01-SOCA
UPI_CPU0_CPU1_P0P1_DP<13> U2               AT2      SOCKET4677_AZIFS054P001C01-SOCA
UPI_CPU0_CPU1_P0P1_DP<14> U1               CW3      SOCKET4677_AZIFS054P001C01-SOCA
UPI_CPU0_CPU1_P0P1_DP<14> U2               AV2      SOCKET4677_AZIFS054P001C01-SOCA
UPI_CPU0_CPU1_P0P1_DP<15> U1               CU1      SOCKET4677_AZIFS054P001C01-SOCA
UPI_CPU0_CPU1_P0P1_DP<15> U2               AY2      SOCKET4677_AZIFS054P001C01-SOCA
UPI_CPU0_CPU1_P0P1_DP<16> U1               CT2      SOCKET4677_AZIFS054P001C01-SOCA
UPI_CPU0_CPU1_P0P1_DP<16> U2               BA1      SOCKET4677_AZIFS054P001C01-SOCA
UPI_CPU0_CPU1_P0P1_DP<17> U1               CP2      SOCKET4677_AZIFS054P001C01-SOCA
UPI_CPU0_CPU1_P0P1_DP<17> U2               BC3      SOCKET4677_AZIFS054P001C01-SOCA
UPI_CPU0_CPU1_P0P1_DP<18> U1               CM2      SOCKET4677_AZIFS054P001C01-SOCA
UPI_CPU0_CPU1_P0P1_DP<18> U2               BE1      SOCKET4677_AZIFS054P001C01-SOCA
UPI_CPU0_CPU1_P0P1_DP<19> U1               CK2      SOCKET4677_AZIFS054P001C01-SOCA
UPI_CPU0_CPU1_P0P1_DP<19> U2               BG3      SOCKET4677_AZIFS054P001C01-SOCA
UPI_CPU0_CPU1_P0P1_DP<20> U1               CG3      SOCKET4677_AZIFS054P001C01-SOCA
UPI_CPU0_CPU1_P0P1_DP<20> U2               BK2      SOCKET4677_AZIFS054P001C01-SOCA
UPI_CPU0_CPU1_P0P1_DP<21> U1               CE1      SOCKET4677_AZIFS054P001C01-SOCA
UPI_CPU0_CPU1_P0P1_DP<21> U2               BM2      SOCKET4677_AZIFS054P001C01-SOCA
UPI_CPU0_CPU1_P0P1_DP<22> U1               CC3      SOCKET4677_AZIFS054P001C01-SOCA
UPI_CPU0_CPU1_P0P1_DP<22> U2               BR3      SOCKET4677_AZIFS054P001C01-SOCA
UPI_CPU0_CPU1_P0P1_DP<23> U1               BY2      SOCKET4677_AZIFS054P001C01-SOCA
UPI_CPU0_CPU1_P0P1_DP<23> U2               BU3      SOCKET4677_AZIFS054P001C01-SOCA
UPI_CPU0_CPU1_P1P0_DN<0> U1               K6       SOCKET4677_AZIFS054P001C01-SOCA
UPI_CPU0_CPU1_P1P0_DN<0> U2               EF6      SOCKET4677_AZIFS054P001C01-SOCA
UPI_CPU0_CPU1_P1P0_DN<1> U1               N5       SOCKET4677_AZIFS054P001C01-SOCA
UPI_CPU0_CPU1_P1P0_DN<1> U2               EC7      SOCKET4677_AZIFS054P001C01-SOCA
UPI_CPU0_CPU1_P1P0_DN<2> U1               P6       SOCKET4677_AZIFS054P001C01-SOCA
UPI_CPU0_CPU1_P1P0_DN<2> U2               EB6      SOCKET4677_AZIFS054P001C01-SOCA
UPI_CPU0_CPU1_P1P0_DN<3> U1               U5       SOCKET4677_AZIFS054P001C01-SOCA
UPI_CPU0_CPU1_P1P0_DN<3> U2               DW7      SOCKET4677_AZIFS054P001C01-SOCA
UPI_CPU0_CPU1_P1P0_DN<4> U1               V6       SOCKET4677_AZIFS054P001C01-SOCA
UPI_CPU0_CPU1_P1P0_DN<4> U2               DV6      SOCKET4677_AZIFS054P001C01-SOCA
UPI_CPU0_CPU1_P1P0_DN<5> U1               AA5      SOCKET4677_AZIFS054P001C01-SOCA
UPI_CPU0_CPU1_P1P0_DN<5> U2               DR7      SOCKET4677_AZIFS054P001C01-SOCA
UPI_CPU0_CPU1_P1P0_DN<6> U1               AB6      SOCKET4677_AZIFS054P001C01-SOCA
UPI_CPU0_CPU1_P1P0_DN<6> U2               DP6      SOCKET4677_AZIFS054P001C01-SOCA
UPI_CPU0_CPU1_P1P0_DN<7> U1               AE5      SOCKET4677_AZIFS054P001C01-SOCA
UPI_CPU0_CPU1_P1P0_DN<7> U2               DL7      SOCKET4677_AZIFS054P001C01-SOCA
UPI_CPU0_CPU1_P1P0_DN<8> U1               AF6      SOCKET4677_AZIFS054P001C01-SOCA
UPI_CPU0_CPU1_P1P0_DN<8> U2               DK6      SOCKET4677_AZIFS054P001C01-SOCA
UPI_CPU0_CPU1_P1P0_DN<9> U1               AH6      SOCKET4677_AZIFS054P001C01-SOCA
UPI_CPU0_CPU1_P1P0_DN<9> U2               DH6      SOCKET4677_AZIFS054P001C01-SOCA
UPI_CPU0_CPU1_P1P0_DN<10> U1               AK6      SOCKET4677_AZIFS054P001C01-SOCA
UPI_CPU0_CPU1_P1P0_DN<10> U2               DF6      SOCKET4677_AZIFS054P001C01-SOCA
UPI_CPU0_CPU1_P1P0_DN<11> U1               AN5      SOCKET4677_AZIFS054P001C01-SOCA
UPI_CPU0_CPU1_P1P0_DN<11> U2               DC7      SOCKET4677_AZIFS054P001C01-SOCA
UPI_CPU0_CPU1_P1P0_DN<12> U1               AP6      SOCKET4677_AZIFS054P001C01-SOCA
UPI_CPU0_CPU1_P1P0_DN<12> U2               DB6      SOCKET4677_AZIFS054P001C01-SOCA
UPI_CPU0_CPU1_P1P0_DN<13> U1               AU5      SOCKET4677_AZIFS054P001C01-SOCA
UPI_CPU0_CPU1_P1P0_DN<13> U2               CW7      SOCKET4677_AZIFS054P001C01-SOCA
UPI_CPU0_CPU1_P1P0_DN<14> U1               AV6      SOCKET4677_AZIFS054P001C01-SOCA
UPI_CPU0_CPU1_P1P0_DN<14> U2               CV6      SOCKET4677_AZIFS054P001C01-SOCA
UPI_CPU0_CPU1_P1P0_DN<15> U1               BA5      SOCKET4677_AZIFS054P001C01-SOCA
UPI_CPU0_CPU1_P1P0_DN<15> U2               CR7      SOCKET4677_AZIFS054P001C01-SOCA
UPI_CPU0_CPU1_P1P0_DN<16> U1               BB6      SOCKET4677_AZIFS054P001C01-SOCA
UPI_CPU0_CPU1_P1P0_DN<16> U2               CP6      SOCKET4677_AZIFS054P001C01-SOCA
UPI_CPU0_CPU1_P1P0_DN<17> U1               BE5      SOCKET4677_AZIFS054P001C01-SOCA
UPI_CPU0_CPU1_P1P0_DN<17> U2               CL7      SOCKET4677_AZIFS054P001C01-SOCA
UPI_CPU0_CPU1_P1P0_DN<18> U1               BF6      SOCKET4677_AZIFS054P001C01-SOCA
UPI_CPU0_CPU1_P1P0_DN<18> U2               CK6      SOCKET4677_AZIFS054P001C01-SOCA
UPI_CPU0_CPU1_P1P0_DN<19> U1               BJ5      SOCKET4677_AZIFS054P001C01-SOCA
UPI_CPU0_CPU1_P1P0_DN<19> U2               CG7      SOCKET4677_AZIFS054P001C01-SOCA
UPI_CPU0_CPU1_P1P0_DN<20> U1               BK6      SOCKET4677_AZIFS054P001C01-SOCA
UPI_CPU0_CPU1_P1P0_DN<20> U2               CF6      SOCKET4677_AZIFS054P001C01-SOCA
UPI_CPU0_CPU1_P1P0_DN<21> U1               BN5      SOCKET4677_AZIFS054P001C01-SOCA
UPI_CPU0_CPU1_P1P0_DN<21> U2               CC7      SOCKET4677_AZIFS054P001C01-SOCA
UPI_CPU0_CPU1_P1P0_DN<22> U1               BR7      SOCKET4677_AZIFS054P001C01-SOCA
UPI_CPU0_CPU1_P1P0_DN<22> U2               CA5      SOCKET4677_AZIFS054P001C01-SOCA
UPI_CPU0_CPU1_P1P0_DN<23> U1               BU5      SOCKET4677_AZIFS054P001C01-SOCA
UPI_CPU0_CPU1_P1P0_DN<23> U2               BW7      SOCKET4677_AZIFS054P001C01-SOCA
UPI_CPU0_CPU1_P1P0_DP<0> U1               L7       SOCKET4677_AZIFS054P001C01-SOCA
UPI_CPU0_CPU1_P1P0_DP<0> U2               EE5      SOCKET4677_AZIFS054P001C01-SOCA
UPI_CPU0_CPU1_P1P0_DP<1> U1               M6       SOCKET4677_AZIFS054P001C01-SOCA
UPI_CPU0_CPU1_P1P0_DP<1> U2               ED6      SOCKET4677_AZIFS054P001C01-SOCA
UPI_CPU0_CPU1_P1P0_DP<2> U1               R7       SOCKET4677_AZIFS054P001C01-SOCA
UPI_CPU0_CPU1_P1P0_DP<2> U2               EA5      SOCKET4677_AZIFS054P001C01-SOCA
UPI_CPU0_CPU1_P1P0_DP<3> U1               T6       SOCKET4677_AZIFS054P001C01-SOCA
UPI_CPU0_CPU1_P1P0_DP<3> U2               DY6      SOCKET4677_AZIFS054P001C01-SOCA
UPI_CPU0_CPU1_P1P0_DP<4> U1               W7       SOCKET4677_AZIFS054P001C01-SOCA
UPI_CPU0_CPU1_P1P0_DP<4> U2               DU5      SOCKET4677_AZIFS054P001C01-SOCA
UPI_CPU0_CPU1_P1P0_DP<5> U1               Y6       SOCKET4677_AZIFS054P001C01-SOCA
UPI_CPU0_CPU1_P1P0_DP<5> U2               DT6      SOCKET4677_AZIFS054P001C01-SOCA
UPI_CPU0_CPU1_P1P0_DP<6> U1               AC7      SOCKET4677_AZIFS054P001C01-SOCA
UPI_CPU0_CPU1_P1P0_DP<6> U2               DN5      SOCKET4677_AZIFS054P001C01-SOCA
UPI_CPU0_CPU1_P1P0_DP<7> U1               AD6      SOCKET4677_AZIFS054P001C01-SOCA
UPI_CPU0_CPU1_P1P0_DP<7> U2               DM6      SOCKET4677_AZIFS054P001C01-SOCA
UPI_CPU0_CPU1_P1P0_DP<8> U1               AG7      SOCKET4677_AZIFS054P001C01-SOCA
UPI_CPU0_CPU1_P1P0_DP<8> U2               DJ5      SOCKET4677_AZIFS054P001C01-SOCA
UPI_CPU0_CPU1_P1P0_DP<9> U1               AJ5      SOCKET4677_AZIFS054P001C01-SOCA
UPI_CPU0_CPU1_P1P0_DP<9> U2               DG7      SOCKET4677_AZIFS054P001C01-SOCA
UPI_CPU0_CPU1_P1P0_DP<10> U1               AL7      SOCKET4677_AZIFS054P001C01-SOCA
UPI_CPU0_CPU1_P1P0_DP<10> U2               DE5      SOCKET4677_AZIFS054P001C01-SOCA
UPI_CPU0_CPU1_P1P0_DP<11> U1               AM6      SOCKET4677_AZIFS054P001C01-SOCA
UPI_CPU0_CPU1_P1P0_DP<11> U2               DD6      SOCKET4677_AZIFS054P001C01-SOCA
UPI_CPU0_CPU1_P1P0_DP<12> U1               AR7      SOCKET4677_AZIFS054P001C01-SOCA
UPI_CPU0_CPU1_P1P0_DP<12> U2               DA5      SOCKET4677_AZIFS054P001C01-SOCA
UPI_CPU0_CPU1_P1P0_DP<13> U1               AT6      SOCKET4677_AZIFS054P001C01-SOCA
UPI_CPU0_CPU1_P1P0_DP<13> U2               CY6      SOCKET4677_AZIFS054P001C01-SOCA
UPI_CPU0_CPU1_P1P0_DP<14> U1               AW7      SOCKET4677_AZIFS054P001C01-SOCA
UPI_CPU0_CPU1_P1P0_DP<14> U2               CU5      SOCKET4677_AZIFS054P001C01-SOCA
UPI_CPU0_CPU1_P1P0_DP<15> U1               AY6      SOCKET4677_AZIFS054P001C01-SOCA
UPI_CPU0_CPU1_P1P0_DP<15> U2               CT6      SOCKET4677_AZIFS054P001C01-SOCA
UPI_CPU0_CPU1_P1P0_DP<16> U1               BC7      SOCKET4677_AZIFS054P001C01-SOCA
UPI_CPU0_CPU1_P1P0_DP<16> U2               CN5      SOCKET4677_AZIFS054P001C01-SOCA
UPI_CPU0_CPU1_P1P0_DP<17> U1               BD6      SOCKET4677_AZIFS054P001C01-SOCA
UPI_CPU0_CPU1_P1P0_DP<17> U2               CM6      SOCKET4677_AZIFS054P001C01-SOCA
UPI_CPU0_CPU1_P1P0_DP<18> U1               BG7      SOCKET4677_AZIFS054P001C01-SOCA
UPI_CPU0_CPU1_P1P0_DP<18> U2               CJ5      SOCKET4677_AZIFS054P001C01-SOCA
UPI_CPU0_CPU1_P1P0_DP<19> U1               BH6      SOCKET4677_AZIFS054P001C01-SOCA
UPI_CPU0_CPU1_P1P0_DP<19> U2               CH6      SOCKET4677_AZIFS054P001C01-SOCA
UPI_CPU0_CPU1_P1P0_DP<20> U1               BL7      SOCKET4677_AZIFS054P001C01-SOCA
UPI_CPU0_CPU1_P1P0_DP<20> U2               CE5      SOCKET4677_AZIFS054P001C01-SOCA
UPI_CPU0_CPU1_P1P0_DP<21> U1               BM6      SOCKET4677_AZIFS054P001C01-SOCA
UPI_CPU0_CPU1_P1P0_DP<21> U2               CD6      SOCKET4677_AZIFS054P001C01-SOCA
UPI_CPU0_CPU1_P1P0_DP<22> U1               BP6      SOCKET4677_AZIFS054P001C01-SOCA
UPI_CPU0_CPU1_P1P0_DP<22> U2               CB6      SOCKET4677_AZIFS054P001C01-SOCA
UPI_CPU0_CPU1_P1P0_DP<23> U1               BT6      SOCKET4677_AZIFS054P001C01-SOCA
UPI_CPU0_CPU1_P1P0_DP<23> U2               BY6      SOCKET4677_AZIFS054P001C01-SOCA
UPI_CPU0_CPU1_P2P2_DN<0> U1               E80      SOCKET4677_AZIFS054P001C01-SOCA
UPI_CPU0_CPU1_P2P2_DN<0> U2               BM71     SOCKET4677_AZIFS054P001C01-SOCA
UPI_CPU0_CPU1_P2P2_DN<1> U1               F81      SOCKET4677_AZIFS054P001C01-SOCA
UPI_CPU0_CPU1_P2P2_DN<1> U2               BG80     SOCKET4677_AZIFS054P001C01-SOCA
UPI_CPU0_CPU1_P2P2_DN<2> U1               G82      SOCKET4677_AZIFS054P001C01-SOCA
UPI_CPU0_CPU1_P2P2_DN<2> U2               BF81     SOCKET4677_AZIFS054P001C01-SOCA
UPI_CPU0_CPU1_P2P2_DN<3> U1               K79      SOCKET4677_AZIFS054P001C01-SOCA
UPI_CPU0_CPU1_P2P2_DN<3> U2               BD79     SOCKET4677_AZIFS054P001C01-SOCA
UPI_CPU0_CPU1_P2P2_DN<4> U1               J82      SOCKET4677_AZIFS054P001C01-SOCA
UPI_CPU0_CPU1_P2P2_DN<4> U2               BE82     SOCKET4677_AZIFS054P001C01-SOCA
UPI_CPU0_CPU1_P2P2_DN<5> U1               L80      SOCKET4677_AZIFS054P001C01-SOCA
UPI_CPU0_CPU1_P2P2_DN<5> U2               BC82     SOCKET4677_AZIFS054P001C01-SOCA
UPI_CPU0_CPU1_P2P2_DN<6> U1               AC80     SOCKET4677_AZIFS054P001C01-SOCA
UPI_CPU0_CPU1_P2P2_DN<6> U2               BA80     SOCKET4677_AZIFS054P001C01-SOCA
UPI_CPU0_CPU1_P2P2_DN<7> U1               AD81     SOCKET4677_AZIFS054P001C01-SOCA
UPI_CPU0_CPU1_P2P2_DN<7> U2               AV81     SOCKET4677_AZIFS054P001C01-SOCA
UPI_CPU0_CPU1_P2P2_DN<8> U1               AF79     SOCKET4677_AZIFS054P001C01-SOCA
UPI_CPU0_CPU1_P2P2_DN<8> U2               AT83     SOCKET4677_AZIFS054P001C01-SOCA
UPI_CPU0_CPU1_P2P2_DN<9> U1               AE82     SOCKET4677_AZIFS054P001C01-SOCA
UPI_CPU0_CPU1_P2P2_DN<9> U2               AR80     SOCKET4677_AZIFS054P001C01-SOCA
UPI_CPU0_CPU1_P2P2_DN<10> U1               AJ80     SOCKET4677_AZIFS054P001C01-SOCA
UPI_CPU0_CPU1_P2P2_DN<10> U2               AN82     SOCKET4677_AZIFS054P001C01-SOCA
UPI_CPU0_CPU1_P2P2_DN<11> U1               AG82     SOCKET4677_AZIFS054P001C01-SOCA
UPI_CPU0_CPU1_P2P2_DN<11> U2               AM81     SOCKET4677_AZIFS054P001C01-SOCA
UPI_CPU0_CPU1_P2P2_DN<12> U1               BA72     SOCKET4677_AZIFS054P001C01-SOCA
UPI_CPU0_CPU1_P2P2_DN<12> U2               AU78     SOCKET4677_AZIFS054P001C01-SOCA
UPI_CPU0_CPU1_P2P2_DN<13> U1               AV73     SOCKET4677_AZIFS054P001C01-SOCA
UPI_CPU0_CPU1_P2P2_DN<13> U2               AW78     SOCKET4677_AZIFS054P001C01-SOCA
UPI_CPU0_CPU1_P2P2_DN<14> U1               AY75     SOCKET4677_AZIFS054P001C01-SOCA
UPI_CPU0_CPU1_P2P2_DN<14> U2               Y81      SOCKET4677_AZIFS054P001C01-SOCA
UPI_CPU0_CPU1_P2P2_DN<15> U1               BB75     SOCKET4677_AZIFS054P001C01-SOCA
UPI_CPU0_CPU1_P2P2_DN<15> U2               V83      SOCKET4677_AZIFS054P001C01-SOCA
UPI_CPU0_CPU1_P2P2_DN<16> U1               AW74     SOCKET4677_AZIFS054P001C01-SOCA
UPI_CPU0_CPU1_P2P2_DN<16> U2               U80      SOCKET4677_AZIFS054P001C01-SOCA
UPI_CPU0_CPU1_P2P2_DN<17> U1               BH75     SOCKET4677_AZIFS054P001C01-SOCA
UPI_CPU0_CPU1_P2P2_DN<17> U2               R82      SOCKET4677_AZIFS054P001C01-SOCA
UPI_CPU0_CPU1_P2P2_DN<18> U1               BJ76     SOCKET4677_AZIFS054P001C01-SOCA
UPI_CPU0_CPU1_P2P2_DN<18> U2               P81      SOCKET4677_AZIFS054P001C01-SOCA
UPI_CPU0_CPU1_P2P2_DN<19> U1               BL76     SOCKET4677_AZIFS054P001C01-SOCA
UPI_CPU0_CPU1_P2P2_DN<19> U2               H85      SOCKET4677_AZIFS054P001C01-SOCA
UPI_CPU0_CPU1_P2P2_DN<20> U1               BG74     SOCKET4677_AZIFS054P001C01-SOCA
UPI_CPU0_CPU1_P2P2_DN<20> U2               F87      SOCKET4677_AZIFS054P001C01-SOCA
UPI_CPU0_CPU1_P2P2_DN<21> U1               BN74     SOCKET4677_AZIFS054P001C01-SOCA
UPI_CPU0_CPU1_P2P2_DN<21> U2               D87      SOCKET4677_AZIFS054P001C01-SOCA
UPI_CPU0_CPU1_P2P2_DN<22> U1               BK73     SOCKET4677_AZIFS054P001C01-SOCA
UPI_CPU0_CPU1_P2P2_DN<22> U2               E84      SOCKET4677_AZIFS054P001C01-SOCA
UPI_CPU0_CPU1_P2P2_DN<23> U1               BD73     SOCKET4677_AZIFS054P001C01-SOCA
UPI_CPU0_CPU1_P2P2_DN<23> U2               B85      SOCKET4677_AZIFS054P001C01-SOCA
UPI_CPU0_CPU1_P2P2_DP<0> U1               G80      SOCKET4677_AZIFS054P001C01-SOCA
UPI_CPU0_CPU1_P2P2_DP<0> U2               BN72     SOCKET4677_AZIFS054P001C01-SOCA
UPI_CPU0_CPU1_P2P2_DP<1> U1               E82      SOCKET4677_AZIFS054P001C01-SOCA
UPI_CPU0_CPU1_P2P2_DP<1> U2               BE80     SOCKET4677_AZIFS054P001C01-SOCA
UPI_CPU0_CPU1_P2P2_DP<2> U1               H83      SOCKET4677_AZIFS054P001C01-SOCA
UPI_CPU0_CPU1_P2P2_DP<2> U2               BG82     SOCKET4677_AZIFS054P001C01-SOCA
UPI_CPU0_CPU1_P2P2_DP<3> U1               M79      SOCKET4677_AZIFS054P001C01-SOCA
UPI_CPU0_CPU1_P2P2_DP<3> U2               BC80     SOCKET4677_AZIFS054P001C01-SOCA
UPI_CPU0_CPU1_P2P2_DP<4> U1               L82      SOCKET4677_AZIFS054P001C01-SOCA
UPI_CPU0_CPU1_P2P2_DP<4> U2               BD83     SOCKET4677_AZIFS054P001C01-SOCA
UPI_CPU0_CPU1_P2P2_DP<5> U1               K81      SOCKET4677_AZIFS054P001C01-SOCA
UPI_CPU0_CPU1_P2P2_DP<5> U2               BA82     SOCKET4677_AZIFS054P001C01-SOCA
UPI_CPU0_CPU1_P2P2_DP<6> U1               AE80     SOCKET4677_AZIFS054P001C01-SOCA
UPI_CPU0_CPU1_P2P2_DP<6> U2               BB81     SOCKET4677_AZIFS054P001C01-SOCA
UPI_CPU0_CPU1_P2P2_DP<7> U1               AC82     SOCKET4677_AZIFS054P001C01-SOCA
UPI_CPU0_CPU1_P2P2_DP<7> U2               AU82     SOCKET4677_AZIFS054P001C01-SOCA
UPI_CPU0_CPU1_P2P2_DP<8> U1               AG80     SOCKET4677_AZIFS054P001C01-SOCA
UPI_CPU0_CPU1_P2P2_DP<8> U2               AV83     SOCKET4677_AZIFS054P001C01-SOCA
UPI_CPU0_CPU1_P2P2_DP<9> U1               AF83     SOCKET4677_AZIFS054P001C01-SOCA
UPI_CPU0_CPU1_P2P2_DP<9> U2               AT81     SOCKET4677_AZIFS054P001C01-SOCA
UPI_CPU0_CPU1_P2P2_DP<10> U1               AH81     SOCKET4677_AZIFS054P001C01-SOCA
UPI_CPU0_CPU1_P2P2_DP<10> U2               AM83     SOCKET4677_AZIFS054P001C01-SOCA
UPI_CPU0_CPU1_P2P2_DP<11> U1               AJ82     SOCKET4677_AZIFS054P001C01-SOCA
UPI_CPU0_CPU1_P2P2_DP<11> U2               AP81     SOCKET4677_AZIFS054P001C01-SOCA
UPI_CPU0_CPU1_P2P2_DP<12> U1               BB73     SOCKET4677_AZIFS054P001C01-SOCA
UPI_CPU0_CPU1_P2P2_DP<12> U2               AV79     SOCKET4677_AZIFS054P001C01-SOCA
UPI_CPU0_CPU1_P2P2_DP<13> U1               AY73     SOCKET4677_AZIFS054P001C01-SOCA
UPI_CPU0_CPU1_P2P2_DP<13> U2               BA78     SOCKET4677_AZIFS054P001C01-SOCA
UPI_CPU0_CPU1_P2P2_DP<14> U1               BA76     SOCKET4677_AZIFS054P001C01-SOCA
UPI_CPU0_CPU1_P2P2_DP<14> U2               W82      SOCKET4677_AZIFS054P001C01-SOCA
UPI_CPU0_CPU1_P2P2_DP<15> U1               BD75     SOCKET4677_AZIFS054P001C01-SOCA
UPI_CPU0_CPU1_P2P2_DP<15> U2               Y83      SOCKET4677_AZIFS054P001C01-SOCA
UPI_CPU0_CPU1_P2P2_DP<16> U1               AV75     SOCKET4677_AZIFS054P001C01-SOCA
UPI_CPU0_CPU1_P2P2_DP<16> U2               V81      SOCKET4677_AZIFS054P001C01-SOCA
UPI_CPU0_CPU1_P2P2_DP<17> U1               BG76     SOCKET4677_AZIFS054P001C01-SOCA
UPI_CPU0_CPU1_P2P2_DP<17> U2               P83      SOCKET4677_AZIFS054P001C01-SOCA
UPI_CPU0_CPU1_P2P2_DP<18> U1               BK77     SOCKET4677_AZIFS054P001C01-SOCA
UPI_CPU0_CPU1_P2P2_DP<18> U2               T81      SOCKET4677_AZIFS054P001C01-SOCA
UPI_CPU0_CPU1_P2P2_DP<19> U1               BN76     SOCKET4677_AZIFS054P001C01-SOCA
UPI_CPU0_CPU1_P2P2_DP<19> U2               G86      SOCKET4677_AZIFS054P001C01-SOCA
UPI_CPU0_CPU1_P2P2_DP<20> U1               BJ74     SOCKET4677_AZIFS054P001C01-SOCA
UPI_CPU0_CPU1_P2P2_DP<20> U2               H87      SOCKET4677_AZIFS054P001C01-SOCA
UPI_CPU0_CPU1_P2P2_DP<21> U1               BM75     SOCKET4677_AZIFS054P001C01-SOCA
UPI_CPU0_CPU1_P2P2_DP<21> U2               E88      SOCKET4677_AZIFS054P001C01-SOCA
UPI_CPU0_CPU1_P2P2_DP<22> U1               BL74     SOCKET4677_AZIFS054P001C01-SOCA
UPI_CPU0_CPU1_P2P2_DP<22> U2               F85      SOCKET4677_AZIFS054P001C01-SOCA
UPI_CPU0_CPU1_P2P2_DP<23> U1               BC74     SOCKET4677_AZIFS054P001C01-SOCA
UPI_CPU0_CPU1_P2P2_DP<23> U2               D85      SOCKET4677_AZIFS054P001C01-SOCA
UPI_CPU0_CPU1_P3P3_DN<0> U1               EJ80     SOCKET4677_AZIFS054P001C01-SOCA
UPI_CPU0_CPU1_P3P3_DN<0> U2               CD73     SOCKET4677_AZIFS054P001C01-SOCA
UPI_CPU0_CPU1_P3P3_DN<1> U1               EP81     SOCKET4677_AZIFS054P001C01-SOCA
UPI_CPU0_CPU1_P3P3_DN<1> U2               CW74     SOCKET4677_AZIFS054P001C01-SOCA
UPI_CPU0_CPU1_P3P3_DN<2> U1               EL82     SOCKET4677_AZIFS054P001C01-SOCA
UPI_CPU0_CPU1_P3P3_DN<2> U2               CK75     SOCKET4677_AZIFS054P001C01-SOCA
UPI_CPU0_CPU1_P3P3_DN<3> U1               EK81     SOCKET4677_AZIFS054P001C01-SOCA
UPI_CPU0_CPU1_P3P3_DN<3> U2               CH75     SOCKET4677_AZIFS054P001C01-SOCA
UPI_CPU0_CPU1_P3P3_DN<4> U1               EF81     SOCKET4677_AZIFS054P001C01-SOCA
UPI_CPU0_CPU1_P3P3_DN<4> U2               CG76     SOCKET4677_AZIFS054P001C01-SOCA
UPI_CPU0_CPU1_P3P3_DN<5> U1               ED83     SOCKET4677_AZIFS054P001C01-SOCA
UPI_CPU0_CPU1_P3P3_DN<5> U2               CL76     SOCKET4677_AZIFS054P001C01-SOCA
UPI_CPU0_CPU1_P3P3_DN<6> U1               EC80     SOCKET4677_AZIFS054P001C01-SOCA
UPI_CPU0_CPU1_P3P3_DN<6> U2               CH77     SOCKET4677_AZIFS054P001C01-SOCA
UPI_CPU0_CPU1_P3P3_DN<7> U1               EA82     SOCKET4677_AZIFS054P001C01-SOCA
UPI_CPU0_CPU1_P3P3_DN<7> U2               CM77     SOCKET4677_AZIFS054P001C01-SOCA
UPI_CPU0_CPU1_P3P3_DN<8> U1               DY81     SOCKET4677_AZIFS054P001C01-SOCA
UPI_CPU0_CPU1_P3P3_DN<8> U2               CU74     SOCKET4677_AZIFS054P001C01-SOCA
UPI_CPU0_CPU1_P3P3_DN<9> U1               DJ78     SOCKET4677_AZIFS054P001C01-SOCA
UPI_CPU0_CPU1_P3P3_DN<9> U2               CT75     SOCKET4677_AZIFS054P001C01-SOCA
UPI_CPU0_CPU1_P3P3_DN<10> U1               DG78     SOCKET4677_AZIFS054P001C01-SOCA
UPI_CPU0_CPU1_P3P3_DN<10> U2               CU76     SOCKET4677_AZIFS054P001C01-SOCA
UPI_CPU0_CPU1_P3P3_DN<11> U1               DH81     SOCKET4677_AZIFS054P001C01-SOCA
UPI_CPU0_CPU1_P3P3_DN<11> U2               CW76     SOCKET4677_AZIFS054P001C01-SOCA
UPI_CPU0_CPU1_P3P3_DN<12> U1               DF83     SOCKET4677_AZIFS054P001C01-SOCA
UPI_CPU0_CPU1_P3P3_DN<12> U2               DN80     SOCKET4677_AZIFS054P001C01-SOCA
UPI_CPU0_CPU1_P3P3_DN<13> U1               DE80     SOCKET4677_AZIFS054P001C01-SOCA
UPI_CPU0_CPU1_P3P3_DN<13> U2               DM81     SOCKET4677_AZIFS054P001C01-SOCA
UPI_CPU0_CPU1_P3P3_DN<14> U1               DC82     SOCKET4677_AZIFS054P001C01-SOCA
UPI_CPU0_CPU1_P3P3_DN<14> U2               DN82     SOCKET4677_AZIFS054P001C01-SOCA
UPI_CPU0_CPU1_P3P3_DN<15> U1               DB81     SOCKET4677_AZIFS054P001C01-SOCA
UPI_CPU0_CPU1_P3P3_DN<15> U2               DR80     SOCKET4677_AZIFS054P001C01-SOCA
UPI_CPU0_CPU1_P3P3_DN<16> U1               DF77     SOCKET4677_AZIFS054P001C01-SOCA
UPI_CPU0_CPU1_P3P3_DN<16> U2               DU82     SOCKET4677_AZIFS054P001C01-SOCA
UPI_CPU0_CPU1_P3P3_DN<17> U1               CU82     SOCKET4677_AZIFS054P001C01-SOCA
UPI_CPU0_CPU1_P3P3_DN<17> U2               DU80     SOCKET4677_AZIFS054P001C01-SOCA
UPI_CPU0_CPU1_P3P3_DN<18> U1               CR82     SOCKET4677_AZIFS054P001C01-SOCA
UPI_CPU0_CPU1_P3P3_DN<18> U2               EL88     SOCKET4677_AZIFS054P001C01-SOCA
UPI_CPU0_CPU1_P3P3_DN<19> U1               CW80     SOCKET4677_AZIFS054P001C01-SOCA
UPI_CPU0_CPU1_P3P3_DN<19> U2               EJ86     SOCKET4677_AZIFS054P001C01-SOCA
UPI_CPU0_CPU1_P3P3_DN<20> U1               CP81     SOCKET4677_AZIFS054P001C01-SOCA
UPI_CPU0_CPU1_P3P3_DN<20> U2               EP87     SOCKET4677_AZIFS054P001C01-SOCA
UPI_CPU0_CPU1_P3P3_DN<21> U1               CN80     SOCKET4677_AZIFS054P001C01-SOCA
UPI_CPU0_CPU1_P3P3_DN<21> U2               EP85     SOCKET4677_AZIFS054P001C01-SOCA
UPI_CPU0_CPU1_P3P3_DN<22> U1               CT79     SOCKET4677_AZIFS054P001C01-SOCA
UPI_CPU0_CPU1_P3P3_DN<22> U2               EL84     SOCKET4677_AZIFS054P001C01-SOCA
UPI_CPU0_CPU1_P3P3_DN<23> U1               DA78     SOCKET4677_AZIFS054P001C01-SOCA
UPI_CPU0_CPU1_P3P3_DN<23> U2               EH85     SOCKET4677_AZIFS054P001C01-SOCA
UPI_CPU0_CPU1_P3P3_DP<0> U1               EL80     SOCKET4677_AZIFS054P001C01-SOCA
UPI_CPU0_CPU1_P3P3_DP<0> U2               CF73     SOCKET4677_AZIFS054P001C01-SOCA
UPI_CPU0_CPU1_P3P3_DP<1> U1               ER82     SOCKET4677_AZIFS054P001C01-SOCA
UPI_CPU0_CPU1_P3P3_DP<1> U2               CV73     SOCKET4677_AZIFS054P001C01-SOCA
UPI_CPU0_CPU1_P3P3_DP<2> U1               EN82     SOCKET4677_AZIFS054P001C01-SOCA
UPI_CPU0_CPU1_P3P3_DP<2> U2               CJ74     SOCKET4677_AZIFS054P001C01-SOCA
UPI_CPU0_CPU1_P3P3_DP<3> U1               EJ82     SOCKET4677_AZIFS054P001C01-SOCA
UPI_CPU0_CPU1_P3P3_DP<3> U2               CF75     SOCKET4677_AZIFS054P001C01-SOCA
UPI_CPU0_CPU1_P3P3_DP<4> U1               EE82     SOCKET4677_AZIFS054P001C01-SOCA
UPI_CPU0_CPU1_P3P3_DP<4> U2               CF77     SOCKET4677_AZIFS054P001C01-SOCA
UPI_CPU0_CPU1_P3P3_DP<5> U1               EF83     SOCKET4677_AZIFS054P001C01-SOCA
UPI_CPU0_CPU1_P3P3_DP<5> U2               CM75     SOCKET4677_AZIFS054P001C01-SOCA
UPI_CPU0_CPU1_P3P3_DP<6> U1               ED81     SOCKET4677_AZIFS054P001C01-SOCA
UPI_CPU0_CPU1_P3P3_DP<6> U2               CJ78     SOCKET4677_AZIFS054P001C01-SOCA
UPI_CPU0_CPU1_P3P3_DP<7> U1               DY83     SOCKET4677_AZIFS054P001C01-SOCA
UPI_CPU0_CPU1_P3P3_DP<7> U2               CK77     SOCKET4677_AZIFS054P001C01-SOCA
UPI_CPU0_CPU1_P3P3_DP<8> U1               EB81     SOCKET4677_AZIFS054P001C01-SOCA
UPI_CPU0_CPU1_P3P3_DP<8> U2               CR74     SOCKET4677_AZIFS054P001C01-SOCA
UPI_CPU0_CPU1_P3P3_DP<9> U1               DL78     SOCKET4677_AZIFS054P001C01-SOCA
UPI_CPU0_CPU1_P3P3_DP<9> U2               CR76     SOCKET4677_AZIFS054P001C01-SOCA
UPI_CPU0_CPU1_P3P3_DP<10> U1               DH79     SOCKET4677_AZIFS054P001C01-SOCA
UPI_CPU0_CPU1_P3P3_DP<10> U2               CV77     SOCKET4677_AZIFS054P001C01-SOCA
UPI_CPU0_CPU1_P3P3_DP<11> U1               DG82     SOCKET4677_AZIFS054P001C01-SOCA
UPI_CPU0_CPU1_P3P3_DP<11> U2               DA76     SOCKET4677_AZIFS054P001C01-SOCA
UPI_CPU0_CPU1_P3P3_DP<12> U1               DH83     SOCKET4677_AZIFS054P001C01-SOCA
UPI_CPU0_CPU1_P3P3_DP<12> U2               DL80     SOCKET4677_AZIFS054P001C01-SOCA
UPI_CPU0_CPU1_P3P3_DP<13> U1               DF81     SOCKET4677_AZIFS054P001C01-SOCA
UPI_CPU0_CPU1_P3P3_DP<13> U2               DL82     SOCKET4677_AZIFS054P001C01-SOCA
UPI_CPU0_CPU1_P3P3_DP<14> U1               DB83     SOCKET4677_AZIFS054P001C01-SOCA
UPI_CPU0_CPU1_P3P3_DP<14> U2               DP83     SOCKET4677_AZIFS054P001C01-SOCA
UPI_CPU0_CPU1_P3P3_DP<15> U1               DD81     SOCKET4677_AZIFS054P001C01-SOCA
UPI_CPU0_CPU1_P3P3_DP<15> U2               DP79     SOCKET4677_AZIFS054P001C01-SOCA
UPI_CPU0_CPU1_P3P3_DP<16> U1               DE78     SOCKET4677_AZIFS054P001C01-SOCA
UPI_CPU0_CPU1_P3P3_DP<16> U2               DR82     SOCKET4677_AZIFS054P001C01-SOCA
UPI_CPU0_CPU1_P3P3_DP<17> U1               CW82     SOCKET4677_AZIFS054P001C01-SOCA
UPI_CPU0_CPU1_P3P3_DP<17> U2               DT81     SOCKET4677_AZIFS054P001C01-SOCA
UPI_CPU0_CPU1_P3P3_DP<18> U1               CT83     SOCKET4677_AZIFS054P001C01-SOCA
UPI_CPU0_CPU1_P3P3_DP<18> U2               EK87     SOCKET4677_AZIFS054P001C01-SOCA
UPI_CPU0_CPU1_P3P3_DP<19> U1               CV81     SOCKET4677_AZIFS054P001C01-SOCA
UPI_CPU0_CPU1_P3P3_DP<19> U2               EH87     SOCKET4677_AZIFS054P001C01-SOCA
UPI_CPU0_CPU1_P3P3_DP<20> U1               CN82     SOCKET4677_AZIFS054P001C01-SOCA
UPI_CPU0_CPU1_P3P3_DP<20> U2               EM87     SOCKET4677_AZIFS054P001C01-SOCA
UPI_CPU0_CPU1_P3P3_DP<21> U1               CR80     SOCKET4677_AZIFS054P001C01-SOCA
UPI_CPU0_CPU1_P3P3_DP<21> U2               EN86     SOCKET4677_AZIFS054P001C01-SOCA
UPI_CPU0_CPU1_P3P3_DP<22> U1               CU80     SOCKET4677_AZIFS054P001C01-SOCA
UPI_CPU0_CPU1_P3P3_DP<22> U2               EM85     SOCKET4677_AZIFS054P001C01-SOCA
UPI_CPU0_CPU1_P3P3_DP<23> U1               DB79     SOCKET4677_AZIFS054P001C01-SOCA
UPI_CPU0_CPU1_P3P3_DP<23> U2               EK85     SOCKET4677_AZIFS054P001C01-SOCA
UPI_CPU1_CPU0_P0P1_DN<0> U1               K4       SOCKET4677_AZIFS054P001C01-SOCA
UPI_CPU1_CPU0_P0P1_DN<0> U2               EH2      SOCKET4677_AZIFS054P001C01-SOCA
UPI_CPU1_CPU0_P0P1_DN<1> U1               M2       SOCKET4677_AZIFS054P001C01-SOCA
UPI_CPU1_CPU0_P0P1_DN<1> U2               EE3      SOCKET4677_AZIFS054P001C01-SOCA
UPI_CPU1_CPU0_P0P1_DN<2> U1               N1       SOCKET4677_AZIFS054P001C01-SOCA
UPI_CPU1_CPU0_P0P1_DN<2> U2               EC3      SOCKET4677_AZIFS054P001C01-SOCA
UPI_CPU1_CPU0_P0P1_DN<3> U1               T2       SOCKET4677_AZIFS054P001C01-SOCA
UPI_CPU1_CPU0_P0P1_DN<3> U2               EA1      SOCKET4677_AZIFS054P001C01-SOCA
UPI_CPU1_CPU0_P0P1_DN<4> U1               U1       SOCKET4677_AZIFS054P001C01-SOCA
UPI_CPU1_CPU0_P0P1_DN<4> U2               DY2      SOCKET4677_AZIFS054P001C01-SOCA
UPI_CPU1_CPU0_P0P1_DN<5> U1               Y2       SOCKET4677_AZIFS054P001C01-SOCA
UPI_CPU1_CPU0_P0P1_DN<5> U2               DU1      SOCKET4677_AZIFS054P001C01-SOCA
UPI_CPU1_CPU0_P0P1_DN<6> U1               AA1      SOCKET4677_AZIFS054P001C01-SOCA
UPI_CPU1_CPU0_P0P1_DN<6> U2               DT2      SOCKET4677_AZIFS054P001C01-SOCA
UPI_CPU1_CPU0_P0P1_DN<7> U1               AD2      SOCKET4677_AZIFS054P001C01-SOCA
UPI_CPU1_CPU0_P0P1_DN<7> U2               DN1      SOCKET4677_AZIFS054P001C01-SOCA
UPI_CPU1_CPU0_P0P1_DN<8> U1               AF2      SOCKET4677_AZIFS054P001C01-SOCA
UPI_CPU1_CPU0_P0P1_DN<8> U2               DL3      SOCKET4677_AZIFS054P001C01-SOCA
UPI_CPU1_CPU0_P0P1_DN<9> U1               AH2      SOCKET4677_AZIFS054P001C01-SOCA
UPI_CPU1_CPU0_P0P1_DN<9> U2               DJ1      SOCKET4677_AZIFS054P001C01-SOCA
UPI_CPU1_CPU0_P0P1_DN<10> U1               AK2      SOCKET4677_AZIFS054P001C01-SOCA
UPI_CPU1_CPU0_P0P1_DN<10> U2               DG3      SOCKET4677_AZIFS054P001C01-SOCA
UPI_CPU1_CPU0_P0P1_DN<11> U1               AM2      SOCKET4677_AZIFS054P001C01-SOCA
UPI_CPU1_CPU0_P0P1_DN<11> U2               DE1      SOCKET4677_AZIFS054P001C01-SOCA
UPI_CPU1_CPU0_P0P1_DN<12> U1               AP2      SOCKET4677_AZIFS054P001C01-SOCA
UPI_CPU1_CPU0_P0P1_DN<12> U2               DC3      SOCKET4677_AZIFS054P001C01-SOCA
UPI_CPU1_CPU0_P0P1_DN<13> U1               AT2      SOCKET4677_AZIFS054P001C01-SOCA
UPI_CPU1_CPU0_P0P1_DN<13> U2               DB2      SOCKET4677_AZIFS054P001C01-SOCA
UPI_CPU1_CPU0_P0P1_DN<14> U1               AU1      SOCKET4677_AZIFS054P001C01-SOCA
UPI_CPU1_CPU0_P0P1_DN<14> U2               CY2      SOCKET4677_AZIFS054P001C01-SOCA
UPI_CPU1_CPU0_P0P1_DN<15> U1               AY2      SOCKET4677_AZIFS054P001C01-SOCA
UPI_CPU1_CPU0_P0P1_DN<15> U2               CV2      SOCKET4677_AZIFS054P001C01-SOCA
UPI_CPU1_CPU0_P0P1_DN<16> U1               BB2      SOCKET4677_AZIFS054P001C01-SOCA
UPI_CPU1_CPU0_P0P1_DN<16> U2               CR3      SOCKET4677_AZIFS054P001C01-SOCA
UPI_CPU1_CPU0_P0P1_DN<17> U1               BD2      SOCKET4677_AZIFS054P001C01-SOCA
UPI_CPU1_CPU0_P0P1_DN<17> U2               CP2      SOCKET4677_AZIFS054P001C01-SOCA
UPI_CPU1_CPU0_P0P1_DN<18> U1               BF2      SOCKET4677_AZIFS054P001C01-SOCA
UPI_CPU1_CPU0_P0P1_DN<18> U2               CL3      SOCKET4677_AZIFS054P001C01-SOCA
UPI_CPU1_CPU0_P0P1_DN<19> U1               BH2      SOCKET4677_AZIFS054P001C01-SOCA
UPI_CPU1_CPU0_P0P1_DN<19> U2               CK2      SOCKET4677_AZIFS054P001C01-SOCA
UPI_CPU1_CPU0_P0P1_DN<20> U1               BK2      SOCKET4677_AZIFS054P001C01-SOCA
UPI_CPU1_CPU0_P0P1_DN<20> U2               CG3      SOCKET4677_AZIFS054P001C01-SOCA
UPI_CPU1_CPU0_P0P1_DN<21> U1               BM2      SOCKET4677_AZIFS054P001C01-SOCA
UPI_CPU1_CPU0_P0P1_DN<21> U2               CF2      SOCKET4677_AZIFS054P001C01-SOCA
UPI_CPU1_CPU0_P0P1_DN<22> U1               BR3      SOCKET4677_AZIFS054P001C01-SOCA
UPI_CPU1_CPU0_P0P1_DN<22> U2               CC3      SOCKET4677_AZIFS054P001C01-SOCA
UPI_CPU1_CPU0_P0P1_DN<23> U1               BT2      SOCKET4677_AZIFS054P001C01-SOCA
UPI_CPU1_CPU0_P0P1_DN<23> U2               BY2      SOCKET4677_AZIFS054P001C01-SOCA
UPI_CPU1_CPU0_P0P1_DP<0> U1               J3       SOCKET4677_AZIFS054P001C01-SOCA
UPI_CPU1_CPU0_P0P1_DP<0> U2               EJ3      SOCKET4677_AZIFS054P001C01-SOCA
UPI_CPU1_CPU0_P0P1_DP<1> U1               L3       SOCKET4677_AZIFS054P001C01-SOCA
UPI_CPU1_CPU0_P0P1_DP<1> U2               EG3      SOCKET4677_AZIFS054P001C01-SOCA
UPI_CPU1_CPU0_P0P1_DP<2> U1               P2       SOCKET4677_AZIFS054P001C01-SOCA
UPI_CPU1_CPU0_P0P1_DP<2> U2               ED2      SOCKET4677_AZIFS054P001C01-SOCA
UPI_CPU1_CPU0_P0P1_DP<3> U1               R3       SOCKET4677_AZIFS054P001C01-SOCA
UPI_CPU1_CPU0_P0P1_DP<3> U2               EB2      SOCKET4677_AZIFS054P001C01-SOCA
UPI_CPU1_CPU0_P0P1_DP<4> U1               V2       SOCKET4677_AZIFS054P001C01-SOCA
UPI_CPU1_CPU0_P0P1_DP<4> U2               DW3      SOCKET4677_AZIFS054P001C01-SOCA
UPI_CPU1_CPU0_P0P1_DP<5> U1               W3       SOCKET4677_AZIFS054P001C01-SOCA
UPI_CPU1_CPU0_P0P1_DP<5> U2               DV2      SOCKET4677_AZIFS054P001C01-SOCA
UPI_CPU1_CPU0_P0P1_DP<6> U1               AB2      SOCKET4677_AZIFS054P001C01-SOCA
UPI_CPU1_CPU0_P0P1_DP<6> U2               DR3      SOCKET4677_AZIFS054P001C01-SOCA
UPI_CPU1_CPU0_P0P1_DP<7> U1               AC3      SOCKET4677_AZIFS054P001C01-SOCA
UPI_CPU1_CPU0_P0P1_DP<7> U2               DP2      SOCKET4677_AZIFS054P001C01-SOCA
UPI_CPU1_CPU0_P0P1_DP<8> U1               AE1      SOCKET4677_AZIFS054P001C01-SOCA
UPI_CPU1_CPU0_P0P1_DP<8> U2               DM2      SOCKET4677_AZIFS054P001C01-SOCA
UPI_CPU1_CPU0_P0P1_DP<9> U1               AG3      SOCKET4677_AZIFS054P001C01-SOCA
UPI_CPU1_CPU0_P0P1_DP<9> U2               DK2      SOCKET4677_AZIFS054P001C01-SOCA
UPI_CPU1_CPU0_P0P1_DP<10> U1               AJ1      SOCKET4677_AZIFS054P001C01-SOCA
UPI_CPU1_CPU0_P0P1_DP<10> U2               DH2      SOCKET4677_AZIFS054P001C01-SOCA
UPI_CPU1_CPU0_P0P1_DP<11> U1               AL3      SOCKET4677_AZIFS054P001C01-SOCA
UPI_CPU1_CPU0_P0P1_DP<11> U2               DF2      SOCKET4677_AZIFS054P001C01-SOCA
UPI_CPU1_CPU0_P0P1_DP<12> U1               AN1      SOCKET4677_AZIFS054P001C01-SOCA
UPI_CPU1_CPU0_P0P1_DP<12> U2               DD2      SOCKET4677_AZIFS054P001C01-SOCA
UPI_CPU1_CPU0_P0P1_DP<13> U1               AR3      SOCKET4677_AZIFS054P001C01-SOCA
UPI_CPU1_CPU0_P0P1_DP<13> U2               DA1      SOCKET4677_AZIFS054P001C01-SOCA
UPI_CPU1_CPU0_P0P1_DP<14> U1               AV2      SOCKET4677_AZIFS054P001C01-SOCA
UPI_CPU1_CPU0_P0P1_DP<14> U2               CW3      SOCKET4677_AZIFS054P001C01-SOCA
UPI_CPU1_CPU0_P0P1_DP<15> U1               AW3      SOCKET4677_AZIFS054P001C01-SOCA
UPI_CPU1_CPU0_P0P1_DP<15> U2               CU1      SOCKET4677_AZIFS054P001C01-SOCA
UPI_CPU1_CPU0_P0P1_DP<16> U1               BA1      SOCKET4677_AZIFS054P001C01-SOCA
UPI_CPU1_CPU0_P0P1_DP<16> U2               CT2      SOCKET4677_AZIFS054P001C01-SOCA
UPI_CPU1_CPU0_P0P1_DP<17> U1               BC3      SOCKET4677_AZIFS054P001C01-SOCA
UPI_CPU1_CPU0_P0P1_DP<17> U2               CN1      SOCKET4677_AZIFS054P001C01-SOCA
UPI_CPU1_CPU0_P0P1_DP<18> U1               BE1      SOCKET4677_AZIFS054P001C01-SOCA
UPI_CPU1_CPU0_P0P1_DP<18> U2               CM2      SOCKET4677_AZIFS054P001C01-SOCA
UPI_CPU1_CPU0_P0P1_DP<19> U1               BG3      SOCKET4677_AZIFS054P001C01-SOCA
UPI_CPU1_CPU0_P0P1_DP<19> U2               CJ1      SOCKET4677_AZIFS054P001C01-SOCA
UPI_CPU1_CPU0_P0P1_DP<20> U1               BJ1      SOCKET4677_AZIFS054P001C01-SOCA
UPI_CPU1_CPU0_P0P1_DP<20> U2               CH2      SOCKET4677_AZIFS054P001C01-SOCA
UPI_CPU1_CPU0_P0P1_DP<21> U1               BL3      SOCKET4677_AZIFS054P001C01-SOCA
UPI_CPU1_CPU0_P0P1_DP<21> U2               CE1      SOCKET4677_AZIFS054P001C01-SOCA
UPI_CPU1_CPU0_P0P1_DP<22> U1               BN3      SOCKET4677_AZIFS054P001C01-SOCA
UPI_CPU1_CPU0_P0P1_DP<22> U2               CD2      SOCKET4677_AZIFS054P001C01-SOCA
UPI_CPU1_CPU0_P0P1_DP<23> U1               BU3      SOCKET4677_AZIFS054P001C01-SOCA
UPI_CPU1_CPU0_P0P1_DP<23> U2               CB2      SOCKET4677_AZIFS054P001C01-SOCA
UPI_CPU1_CPU0_P1P0_DN<0> U1               EF6      SOCKET4677_AZIFS054P001C01-SOCA
UPI_CPU1_CPU0_P1P0_DN<0> U2               K6       SOCKET4677_AZIFS054P001C01-SOCA
UPI_CPU1_CPU0_P1P0_DN<1> U1               EC7      SOCKET4677_AZIFS054P001C01-SOCA
UPI_CPU1_CPU0_P1P0_DN<1> U2               N5       SOCKET4677_AZIFS054P001C01-SOCA
UPI_CPU1_CPU0_P1P0_DN<2> U1               EB6      SOCKET4677_AZIFS054P001C01-SOCA
UPI_CPU1_CPU0_P1P0_DN<2> U2               P6       SOCKET4677_AZIFS054P001C01-SOCA
UPI_CPU1_CPU0_P1P0_DN<3> U1               DY6      SOCKET4677_AZIFS054P001C01-SOCA
UPI_CPU1_CPU0_P1P0_DN<3> U2               T6       SOCKET4677_AZIFS054P001C01-SOCA
UPI_CPU1_CPU0_P1P0_DN<4> U1               DV6      SOCKET4677_AZIFS054P001C01-SOCA
UPI_CPU1_CPU0_P1P0_DN<4> U2               V6       SOCKET4677_AZIFS054P001C01-SOCA
UPI_CPU1_CPU0_P1P0_DN<5> U1               DT6      SOCKET4677_AZIFS054P001C01-SOCA
UPI_CPU1_CPU0_P1P0_DN<5> U2               Y6       SOCKET4677_AZIFS054P001C01-SOCA
UPI_CPU1_CPU0_P1P0_DN<6> U1               DP6      SOCKET4677_AZIFS054P001C01-SOCA
UPI_CPU1_CPU0_P1P0_DN<6> U2               AB6      SOCKET4677_AZIFS054P001C01-SOCA
UPI_CPU1_CPU0_P1P0_DN<7> U1               DL7      SOCKET4677_AZIFS054P001C01-SOCA
UPI_CPU1_CPU0_P1P0_DN<7> U2               AE5      SOCKET4677_AZIFS054P001C01-SOCA
UPI_CPU1_CPU0_P1P0_DN<8> U1               DK6      SOCKET4677_AZIFS054P001C01-SOCA
UPI_CPU1_CPU0_P1P0_DN<8> U2               AF6      SOCKET4677_AZIFS054P001C01-SOCA
UPI_CPU1_CPU0_P1P0_DN<9> U1               DH6      SOCKET4677_AZIFS054P001C01-SOCA
UPI_CPU1_CPU0_P1P0_DN<9> U2               AH6      SOCKET4677_AZIFS054P001C01-SOCA
UPI_CPU1_CPU0_P1P0_DN<10> U1               DE5      SOCKET4677_AZIFS054P001C01-SOCA
UPI_CPU1_CPU0_P1P0_DN<10> U2               AL7      SOCKET4677_AZIFS054P001C01-SOCA
UPI_CPU1_CPU0_P1P0_DN<11> U1               DD6      SOCKET4677_AZIFS054P001C01-SOCA
UPI_CPU1_CPU0_P1P0_DN<11> U2               AM6      SOCKET4677_AZIFS054P001C01-SOCA
UPI_CPU1_CPU0_P1P0_DN<12> U1               DA5      SOCKET4677_AZIFS054P001C01-SOCA
UPI_CPU1_CPU0_P1P0_DN<12> U2               AR7      SOCKET4677_AZIFS054P001C01-SOCA
UPI_CPU1_CPU0_P1P0_DN<13> U1               CY6      SOCKET4677_AZIFS054P001C01-SOCA
UPI_CPU1_CPU0_P1P0_DN<13> U2               AT6      SOCKET4677_AZIFS054P001C01-SOCA
UPI_CPU1_CPU0_P1P0_DN<14> U1               CU5      SOCKET4677_AZIFS054P001C01-SOCA
UPI_CPU1_CPU0_P1P0_DN<14> U2               AW7      SOCKET4677_AZIFS054P001C01-SOCA
UPI_CPU1_CPU0_P1P0_DN<15> U1               CT6      SOCKET4677_AZIFS054P001C01-SOCA
UPI_CPU1_CPU0_P1P0_DN<15> U2               AY6      SOCKET4677_AZIFS054P001C01-SOCA
UPI_CPU1_CPU0_P1P0_DN<16> U1               CN5      SOCKET4677_AZIFS054P001C01-SOCA
UPI_CPU1_CPU0_P1P0_DN<16> U2               BC7      SOCKET4677_AZIFS054P001C01-SOCA
UPI_CPU1_CPU0_P1P0_DN<17> U1               CM6      SOCKET4677_AZIFS054P001C01-SOCA
UPI_CPU1_CPU0_P1P0_DN<17> U2               BD6      SOCKET4677_AZIFS054P001C01-SOCA
UPI_CPU1_CPU0_P1P0_DN<18> U1               CJ5      SOCKET4677_AZIFS054P001C01-SOCA
UPI_CPU1_CPU0_P1P0_DN<18> U2               BG7      SOCKET4677_AZIFS054P001C01-SOCA
UPI_CPU1_CPU0_P1P0_DN<19> U1               CH6      SOCKET4677_AZIFS054P001C01-SOCA
UPI_CPU1_CPU0_P1P0_DN<19> U2               BH6      SOCKET4677_AZIFS054P001C01-SOCA
UPI_CPU1_CPU0_P1P0_DN<20> U1               CE5      SOCKET4677_AZIFS054P001C01-SOCA
UPI_CPU1_CPU0_P1P0_DN<20> U2               BL7      SOCKET4677_AZIFS054P001C01-SOCA
UPI_CPU1_CPU0_P1P0_DN<21> U1               CD6      SOCKET4677_AZIFS054P001C01-SOCA
UPI_CPU1_CPU0_P1P0_DN<21> U2               BM6      SOCKET4677_AZIFS054P001C01-SOCA
UPI_CPU1_CPU0_P1P0_DN<22> U1               CA5      SOCKET4677_AZIFS054P001C01-SOCA
UPI_CPU1_CPU0_P1P0_DN<22> U2               BR7      SOCKET4677_AZIFS054P001C01-SOCA
UPI_CPU1_CPU0_P1P0_DN<23> U1               BY6      SOCKET4677_AZIFS054P001C01-SOCA
UPI_CPU1_CPU0_P1P0_DN<23> U2               BT6      SOCKET4677_AZIFS054P001C01-SOCA
UPI_CPU1_CPU0_P1P0_DP<0> U1               EE5      SOCKET4677_AZIFS054P001C01-SOCA
UPI_CPU1_CPU0_P1P0_DP<0> U2               L7       SOCKET4677_AZIFS054P001C01-SOCA
UPI_CPU1_CPU0_P1P0_DP<1> U1               ED6      SOCKET4677_AZIFS054P001C01-SOCA
UPI_CPU1_CPU0_P1P0_DP<1> U2               M6       SOCKET4677_AZIFS054P001C01-SOCA
UPI_CPU1_CPU0_P1P0_DP<2> U1               EA5      SOCKET4677_AZIFS054P001C01-SOCA
UPI_CPU1_CPU0_P1P0_DP<2> U2               R7       SOCKET4677_AZIFS054P001C01-SOCA
UPI_CPU1_CPU0_P1P0_DP<3> U1               DW7      SOCKET4677_AZIFS054P001C01-SOCA
UPI_CPU1_CPU0_P1P0_DP<3> U2               U5       SOCKET4677_AZIFS054P001C01-SOCA
UPI_CPU1_CPU0_P1P0_DP<4> U1               DU5      SOCKET4677_AZIFS054P001C01-SOCA
UPI_CPU1_CPU0_P1P0_DP<4> U2               W7       SOCKET4677_AZIFS054P001C01-SOCA
UPI_CPU1_CPU0_P1P0_DP<5> U1               DR7      SOCKET4677_AZIFS054P001C01-SOCA
UPI_CPU1_CPU0_P1P0_DP<5> U2               AA5      SOCKET4677_AZIFS054P001C01-SOCA
UPI_CPU1_CPU0_P1P0_DP<6> U1               DN5      SOCKET4677_AZIFS054P001C01-SOCA
UPI_CPU1_CPU0_P1P0_DP<6> U2               AC7      SOCKET4677_AZIFS054P001C01-SOCA
UPI_CPU1_CPU0_P1P0_DP<7> U1               DM6      SOCKET4677_AZIFS054P001C01-SOCA
UPI_CPU1_CPU0_P1P0_DP<7> U2               AD6      SOCKET4677_AZIFS054P001C01-SOCA
UPI_CPU1_CPU0_P1P0_DP<8> U1               DJ5      SOCKET4677_AZIFS054P001C01-SOCA
UPI_CPU1_CPU0_P1P0_DP<8> U2               AG7      SOCKET4677_AZIFS054P001C01-SOCA
UPI_CPU1_CPU0_P1P0_DP<9> U1               DG7      SOCKET4677_AZIFS054P001C01-SOCA
UPI_CPU1_CPU0_P1P0_DP<9> U2               AJ5      SOCKET4677_AZIFS054P001C01-SOCA
UPI_CPU1_CPU0_P1P0_DP<10> U1               DF6      SOCKET4677_AZIFS054P001C01-SOCA
UPI_CPU1_CPU0_P1P0_DP<10> U2               AK6      SOCKET4677_AZIFS054P001C01-SOCA
UPI_CPU1_CPU0_P1P0_DP<11> U1               DC7      SOCKET4677_AZIFS054P001C01-SOCA
UPI_CPU1_CPU0_P1P0_DP<11> U2               AN5      SOCKET4677_AZIFS054P001C01-SOCA
UPI_CPU1_CPU0_P1P0_DP<12> U1               DB6      SOCKET4677_AZIFS054P001C01-SOCA
UPI_CPU1_CPU0_P1P0_DP<12> U2               AP6      SOCKET4677_AZIFS054P001C01-SOCA
UPI_CPU1_CPU0_P1P0_DP<13> U1               CW7      SOCKET4677_AZIFS054P001C01-SOCA
UPI_CPU1_CPU0_P1P0_DP<13> U2               AU5      SOCKET4677_AZIFS054P001C01-SOCA
UPI_CPU1_CPU0_P1P0_DP<14> U1               CV6      SOCKET4677_AZIFS054P001C01-SOCA
UPI_CPU1_CPU0_P1P0_DP<14> U2               AV6      SOCKET4677_AZIFS054P001C01-SOCA
UPI_CPU1_CPU0_P1P0_DP<15> U1               CR7      SOCKET4677_AZIFS054P001C01-SOCA
UPI_CPU1_CPU0_P1P0_DP<15> U2               BA5      SOCKET4677_AZIFS054P001C01-SOCA
UPI_CPU1_CPU0_P1P0_DP<16> U1               CP6      SOCKET4677_AZIFS054P001C01-SOCA
UPI_CPU1_CPU0_P1P0_DP<16> U2               BB6      SOCKET4677_AZIFS054P001C01-SOCA
UPI_CPU1_CPU0_P1P0_DP<17> U1               CL7      SOCKET4677_AZIFS054P001C01-SOCA
UPI_CPU1_CPU0_P1P0_DP<17> U2               BE5      SOCKET4677_AZIFS054P001C01-SOCA
UPI_CPU1_CPU0_P1P0_DP<18> U1               CK6      SOCKET4677_AZIFS054P001C01-SOCA
UPI_CPU1_CPU0_P1P0_DP<18> U2               BF6      SOCKET4677_AZIFS054P001C01-SOCA
UPI_CPU1_CPU0_P1P0_DP<19> U1               CG7      SOCKET4677_AZIFS054P001C01-SOCA
UPI_CPU1_CPU0_P1P0_DP<19> U2               BJ5      SOCKET4677_AZIFS054P001C01-SOCA
UPI_CPU1_CPU0_P1P0_DP<20> U1               CF6      SOCKET4677_AZIFS054P001C01-SOCA
UPI_CPU1_CPU0_P1P0_DP<20> U2               BK6      SOCKET4677_AZIFS054P001C01-SOCA
UPI_CPU1_CPU0_P1P0_DP<21> U1               CC7      SOCKET4677_AZIFS054P001C01-SOCA
UPI_CPU1_CPU0_P1P0_DP<21> U2               BN5      SOCKET4677_AZIFS054P001C01-SOCA
UPI_CPU1_CPU0_P1P0_DP<22> U1               CB6      SOCKET4677_AZIFS054P001C01-SOCA
UPI_CPU1_CPU0_P1P0_DP<22> U2               BP6      SOCKET4677_AZIFS054P001C01-SOCA
UPI_CPU1_CPU0_P1P0_DP<23> U1               BW7      SOCKET4677_AZIFS054P001C01-SOCA
UPI_CPU1_CPU0_P1P0_DP<23> U2               BU5      SOCKET4677_AZIFS054P001C01-SOCA
UPI_CPU1_CPU0_P2P2_DN<0> U1               B85      SOCKET4677_AZIFS054P001C01-SOCA
UPI_CPU1_CPU0_P2P2_DN<0> U2               BC74     SOCKET4677_AZIFS054P001C01-SOCA
UPI_CPU1_CPU0_P2P2_DN<1> U1               E84      SOCKET4677_AZIFS054P001C01-SOCA
UPI_CPU1_CPU0_P2P2_DN<1> U2               BK73     SOCKET4677_AZIFS054P001C01-SOCA
UPI_CPU1_CPU0_P2P2_DN<2> U1               D87      SOCKET4677_AZIFS054P001C01-SOCA
UPI_CPU1_CPU0_P2P2_DN<2> U2               BM75     SOCKET4677_AZIFS054P001C01-SOCA
UPI_CPU1_CPU0_P2P2_DN<3> U1               F87      SOCKET4677_AZIFS054P001C01-SOCA
UPI_CPU1_CPU0_P2P2_DN<3> U2               BJ74     SOCKET4677_AZIFS054P001C01-SOCA
UPI_CPU1_CPU0_P2P2_DN<4> U1               H85      SOCKET4677_AZIFS054P001C01-SOCA
UPI_CPU1_CPU0_P2P2_DN<4> U2               BN76     SOCKET4677_AZIFS054P001C01-SOCA
UPI_CPU1_CPU0_P2P2_DN<5> U1               P81      SOCKET4677_AZIFS054P001C01-SOCA
UPI_CPU1_CPU0_P2P2_DN<5> U2               BJ76     SOCKET4677_AZIFS054P001C01-SOCA
UPI_CPU1_CPU0_P2P2_DN<6> U1               R82      SOCKET4677_AZIFS054P001C01-SOCA
UPI_CPU1_CPU0_P2P2_DN<6> U2               BH75     SOCKET4677_AZIFS054P001C01-SOCA
UPI_CPU1_CPU0_P2P2_DN<7> U1               U80      SOCKET4677_AZIFS054P001C01-SOCA
UPI_CPU1_CPU0_P2P2_DN<7> U2               AV75     SOCKET4677_AZIFS054P001C01-SOCA
UPI_CPU1_CPU0_P2P2_DN<8> U1               V83      SOCKET4677_AZIFS054P001C01-SOCA
UPI_CPU1_CPU0_P2P2_DN<8> U2               BD75     SOCKET4677_AZIFS054P001C01-SOCA
UPI_CPU1_CPU0_P2P2_DN<9> U1               Y81      SOCKET4677_AZIFS054P001C01-SOCA
UPI_CPU1_CPU0_P2P2_DN<9> U2               AY75     SOCKET4677_AZIFS054P001C01-SOCA
UPI_CPU1_CPU0_P2P2_DN<10> U1               AW78     SOCKET4677_AZIFS054P001C01-SOCA
UPI_CPU1_CPU0_P2P2_DN<10> U2               AV73     SOCKET4677_AZIFS054P001C01-SOCA
UPI_CPU1_CPU0_P2P2_DN<11> U1               AU78     SOCKET4677_AZIFS054P001C01-SOCA
UPI_CPU1_CPU0_P2P2_DN<11> U2               BB73     SOCKET4677_AZIFS054P001C01-SOCA
UPI_CPU1_CPU0_P2P2_DN<12> U1               AM81     SOCKET4677_AZIFS054P001C01-SOCA
UPI_CPU1_CPU0_P2P2_DN<12> U2               AJ82     SOCKET4677_AZIFS054P001C01-SOCA
UPI_CPU1_CPU0_P2P2_DN<13> U1               AN82     SOCKET4677_AZIFS054P001C01-SOCA
UPI_CPU1_CPU0_P2P2_DN<13> U2               AJ80     SOCKET4677_AZIFS054P001C01-SOCA
UPI_CPU1_CPU0_P2P2_DN<14> U1               AR80     SOCKET4677_AZIFS054P001C01-SOCA
UPI_CPU1_CPU0_P2P2_DN<14> U2               AF83     SOCKET4677_AZIFS054P001C01-SOCA
UPI_CPU1_CPU0_P2P2_DN<15> U1               AT83     SOCKET4677_AZIFS054P001C01-SOCA
UPI_CPU1_CPU0_P2P2_DN<15> U2               AG80     SOCKET4677_AZIFS054P001C01-SOCA
UPI_CPU1_CPU0_P2P2_DN<16> U1               AV81     SOCKET4677_AZIFS054P001C01-SOCA
UPI_CPU1_CPU0_P2P2_DN<16> U2               AC82     SOCKET4677_AZIFS054P001C01-SOCA
UPI_CPU1_CPU0_P2P2_DN<17> U1               BA80     SOCKET4677_AZIFS054P001C01-SOCA
UPI_CPU1_CPU0_P2P2_DN<17> U2               AC80     SOCKET4677_AZIFS054P001C01-SOCA
UPI_CPU1_CPU0_P2P2_DN<18> U1               BC82     SOCKET4677_AZIFS054P001C01-SOCA
UPI_CPU1_CPU0_P2P2_DN<18> U2               L80      SOCKET4677_AZIFS054P001C01-SOCA
UPI_CPU1_CPU0_P2P2_DN<19> U1               BE82     SOCKET4677_AZIFS054P001C01-SOCA
UPI_CPU1_CPU0_P2P2_DN<19> U2               J82      SOCKET4677_AZIFS054P001C01-SOCA
UPI_CPU1_CPU0_P2P2_DN<20> U1               BD79     SOCKET4677_AZIFS054P001C01-SOCA
UPI_CPU1_CPU0_P2P2_DN<20> U2               K79      SOCKET4677_AZIFS054P001C01-SOCA
UPI_CPU1_CPU0_P2P2_DN<21> U1               BF81     SOCKET4677_AZIFS054P001C01-SOCA
UPI_CPU1_CPU0_P2P2_DN<21> U2               G82      SOCKET4677_AZIFS054P001C01-SOCA
UPI_CPU1_CPU0_P2P2_DN<22> U1               BG80     SOCKET4677_AZIFS054P001C01-SOCA
UPI_CPU1_CPU0_P2P2_DN<22> U2               E82      SOCKET4677_AZIFS054P001C01-SOCA
UPI_CPU1_CPU0_P2P2_DN<23> U1               BM71     SOCKET4677_AZIFS054P001C01-SOCA
UPI_CPU1_CPU0_P2P2_DN<23> U2               E80      SOCKET4677_AZIFS054P001C01-SOCA
UPI_CPU1_CPU0_P2P2_DP<0> U1               D85      SOCKET4677_AZIFS054P001C01-SOCA
UPI_CPU1_CPU0_P2P2_DP<0> U2               BD73     SOCKET4677_AZIFS054P001C01-SOCA
UPI_CPU1_CPU0_P2P2_DP<1> U1               F85      SOCKET4677_AZIFS054P001C01-SOCA
UPI_CPU1_CPU0_P2P2_DP<1> U2               BL74     SOCKET4677_AZIFS054P001C01-SOCA
UPI_CPU1_CPU0_P2P2_DP<2> U1               E88      SOCKET4677_AZIFS054P001C01-SOCA
UPI_CPU1_CPU0_P2P2_DP<2> U2               BN74     SOCKET4677_AZIFS054P001C01-SOCA
UPI_CPU1_CPU0_P2P2_DP<3> U1               H87      SOCKET4677_AZIFS054P001C01-SOCA
UPI_CPU1_CPU0_P2P2_DP<3> U2               BG74     SOCKET4677_AZIFS054P001C01-SOCA
UPI_CPU1_CPU0_P2P2_DP<4> U1               G86      SOCKET4677_AZIFS054P001C01-SOCA
UPI_CPU1_CPU0_P2P2_DP<4> U2               BL76     SOCKET4677_AZIFS054P001C01-SOCA
UPI_CPU1_CPU0_P2P2_DP<5> U1               T81      SOCKET4677_AZIFS054P001C01-SOCA
UPI_CPU1_CPU0_P2P2_DP<5> U2               BK77     SOCKET4677_AZIFS054P001C01-SOCA
UPI_CPU1_CPU0_P2P2_DP<6> U1               P83      SOCKET4677_AZIFS054P001C01-SOCA
UPI_CPU1_CPU0_P2P2_DP<6> U2               BG76     SOCKET4677_AZIFS054P001C01-SOCA
UPI_CPU1_CPU0_P2P2_DP<7> U1               V81      SOCKET4677_AZIFS054P001C01-SOCA
UPI_CPU1_CPU0_P2P2_DP<7> U2               AW74     SOCKET4677_AZIFS054P001C01-SOCA
UPI_CPU1_CPU0_P2P2_DP<8> U1               Y83      SOCKET4677_AZIFS054P001C01-SOCA
UPI_CPU1_CPU0_P2P2_DP<8> U2               BB75     SOCKET4677_AZIFS054P001C01-SOCA
UPI_CPU1_CPU0_P2P2_DP<9> U1               W82      SOCKET4677_AZIFS054P001C01-SOCA
UPI_CPU1_CPU0_P2P2_DP<9> U2               BA76     SOCKET4677_AZIFS054P001C01-SOCA
UPI_CPU1_CPU0_P2P2_DP<10> U1               BA78     SOCKET4677_AZIFS054P001C01-SOCA
UPI_CPU1_CPU0_P2P2_DP<10> U2               AY73     SOCKET4677_AZIFS054P001C01-SOCA
UPI_CPU1_CPU0_P2P2_DP<11> U1               AV79     SOCKET4677_AZIFS054P001C01-SOCA
UPI_CPU1_CPU0_P2P2_DP<11> U2               BA72     SOCKET4677_AZIFS054P001C01-SOCA
UPI_CPU1_CPU0_P2P2_DP<12> U1               AP81     SOCKET4677_AZIFS054P001C01-SOCA
UPI_CPU1_CPU0_P2P2_DP<12> U2               AG82     SOCKET4677_AZIFS054P001C01-SOCA
UPI_CPU1_CPU0_P2P2_DP<13> U1               AM83     SOCKET4677_AZIFS054P001C01-SOCA
UPI_CPU1_CPU0_P2P2_DP<13> U2               AH81     SOCKET4677_AZIFS054P001C01-SOCA
UPI_CPU1_CPU0_P2P2_DP<14> U1               AT81     SOCKET4677_AZIFS054P001C01-SOCA
UPI_CPU1_CPU0_P2P2_DP<14> U2               AE82     SOCKET4677_AZIFS054P001C01-SOCA
UPI_CPU1_CPU0_P2P2_DP<15> U1               AV83     SOCKET4677_AZIFS054P001C01-SOCA
UPI_CPU1_CPU0_P2P2_DP<15> U2               AF79     SOCKET4677_AZIFS054P001C01-SOCA
UPI_CPU1_CPU0_P2P2_DP<16> U1               AU82     SOCKET4677_AZIFS054P001C01-SOCA
UPI_CPU1_CPU0_P2P2_DP<16> U2               AD81     SOCKET4677_AZIFS054P001C01-SOCA
UPI_CPU1_CPU0_P2P2_DP<17> U1               BB81     SOCKET4677_AZIFS054P001C01-SOCA
UPI_CPU1_CPU0_P2P2_DP<17> U2               AE80     SOCKET4677_AZIFS054P001C01-SOCA
UPI_CPU1_CPU0_P2P2_DP<18> U1               BA82     SOCKET4677_AZIFS054P001C01-SOCA
UPI_CPU1_CPU0_P2P2_DP<18> U2               K81      SOCKET4677_AZIFS054P001C01-SOCA
UPI_CPU1_CPU0_P2P2_DP<19> U1               BD83     SOCKET4677_AZIFS054P001C01-SOCA
UPI_CPU1_CPU0_P2P2_DP<19> U2               L82      SOCKET4677_AZIFS054P001C01-SOCA
UPI_CPU1_CPU0_P2P2_DP<20> U1               BC80     SOCKET4677_AZIFS054P001C01-SOCA
UPI_CPU1_CPU0_P2P2_DP<20> U2               M79      SOCKET4677_AZIFS054P001C01-SOCA
UPI_CPU1_CPU0_P2P2_DP<21> U1               BG82     SOCKET4677_AZIFS054P001C01-SOCA
UPI_CPU1_CPU0_P2P2_DP<21> U2               H83      SOCKET4677_AZIFS054P001C01-SOCA
UPI_CPU1_CPU0_P2P2_DP<22> U1               BE80     SOCKET4677_AZIFS054P001C01-SOCA
UPI_CPU1_CPU0_P2P2_DP<22> U2               F81      SOCKET4677_AZIFS054P001C01-SOCA
UPI_CPU1_CPU0_P2P2_DP<23> U1               BN72     SOCKET4677_AZIFS054P001C01-SOCA
UPI_CPU1_CPU0_P2P2_DP<23> U2               G80      SOCKET4677_AZIFS054P001C01-SOCA
UPI_CPU1_CPU0_P3P3_DN<0> U1               EH85     SOCKET4677_AZIFS054P001C01-SOCA
UPI_CPU1_CPU0_P3P3_DN<0> U2               DA78     SOCKET4677_AZIFS054P001C01-SOCA
UPI_CPU1_CPU0_P3P3_DN<1> U1               EL84     SOCKET4677_AZIFS054P001C01-SOCA
UPI_CPU1_CPU0_P3P3_DN<1> U2               CT79     SOCKET4677_AZIFS054P001C01-SOCA
UPI_CPU1_CPU0_P3P3_DN<2> U1               EP85     SOCKET4677_AZIFS054P001C01-SOCA
UPI_CPU1_CPU0_P3P3_DN<2> U2               CN80     SOCKET4677_AZIFS054P001C01-SOCA
UPI_CPU1_CPU0_P3P3_DN<3> U1               EP87     SOCKET4677_AZIFS054P001C01-SOCA
UPI_CPU1_CPU0_P3P3_DN<3> U2               CP81     SOCKET4677_AZIFS054P001C01-SOCA
UPI_CPU1_CPU0_P3P3_DN<4> U1               EJ86     SOCKET4677_AZIFS054P001C01-SOCA
UPI_CPU1_CPU0_P3P3_DN<4> U2               CW80     SOCKET4677_AZIFS054P001C01-SOCA
UPI_CPU1_CPU0_P3P3_DN<5> U1               EK87     SOCKET4677_AZIFS054P001C01-SOCA
UPI_CPU1_CPU0_P3P3_DN<5> U2               CR82     SOCKET4677_AZIFS054P001C01-SOCA
UPI_CPU1_CPU0_P3P3_DN<6> U1               DU80     SOCKET4677_AZIFS054P001C01-SOCA
UPI_CPU1_CPU0_P3P3_DN<6> U2               CU82     SOCKET4677_AZIFS054P001C01-SOCA
UPI_CPU1_CPU0_P3P3_DN<7> U1               DR82     SOCKET4677_AZIFS054P001C01-SOCA
UPI_CPU1_CPU0_P3P3_DN<7> U2               DF77     SOCKET4677_AZIFS054P001C01-SOCA
UPI_CPU1_CPU0_P3P3_DN<8> U1               DP79     SOCKET4677_AZIFS054P001C01-SOCA
UPI_CPU1_CPU0_P3P3_DN<8> U2               DB81     SOCKET4677_AZIFS054P001C01-SOCA
UPI_CPU1_CPU0_P3P3_DN<9> U1               DN82     SOCKET4677_AZIFS054P001C01-SOCA
UPI_CPU1_CPU0_P3P3_DN<9> U2               DC82     SOCKET4677_AZIFS054P001C01-SOCA
UPI_CPU1_CPU0_P3P3_DN<10> U1               DM81     SOCKET4677_AZIFS054P001C01-SOCA
UPI_CPU1_CPU0_P3P3_DN<10> U2               DE80     SOCKET4677_AZIFS054P001C01-SOCA
UPI_CPU1_CPU0_P3P3_DN<11> U1               DN80     SOCKET4677_AZIFS054P001C01-SOCA
UPI_CPU1_CPU0_P3P3_DN<11> U2               DF83     SOCKET4677_AZIFS054P001C01-SOCA
UPI_CPU1_CPU0_P3P3_DN<12> U1               CW76     SOCKET4677_AZIFS054P001C01-SOCA
UPI_CPU1_CPU0_P3P3_DN<12> U2               DH81     SOCKET4677_AZIFS054P001C01-SOCA
UPI_CPU1_CPU0_P3P3_DN<13> U1               CU76     SOCKET4677_AZIFS054P001C01-SOCA
UPI_CPU1_CPU0_P3P3_DN<13> U2               DG78     SOCKET4677_AZIFS054P001C01-SOCA
UPI_CPU1_CPU0_P3P3_DN<14> U1               CT75     SOCKET4677_AZIFS054P001C01-SOCA
UPI_CPU1_CPU0_P3P3_DN<14> U2               DJ78     SOCKET4677_AZIFS054P001C01-SOCA
UPI_CPU1_CPU0_P3P3_DN<15> U1               CU74     SOCKET4677_AZIFS054P001C01-SOCA
UPI_CPU1_CPU0_P3P3_DN<15> U2               DY81     SOCKET4677_AZIFS054P001C01-SOCA
UPI_CPU1_CPU0_P3P3_DN<16> U1               CM77     SOCKET4677_AZIFS054P001C01-SOCA
UPI_CPU1_CPU0_P3P3_DN<16> U2               EA82     SOCKET4677_AZIFS054P001C01-SOCA
UPI_CPU1_CPU0_P3P3_DN<17> U1               CH77     SOCKET4677_AZIFS054P001C01-SOCA
UPI_CPU1_CPU0_P3P3_DN<17> U2               EC80     SOCKET4677_AZIFS054P001C01-SOCA
UPI_CPU1_CPU0_P3P3_DN<18> U1               CL76     SOCKET4677_AZIFS054P001C01-SOCA
UPI_CPU1_CPU0_P3P3_DN<18> U2               ED83     SOCKET4677_AZIFS054P001C01-SOCA
UPI_CPU1_CPU0_P3P3_DN<19> U1               CG76     SOCKET4677_AZIFS054P001C01-SOCA
UPI_CPU1_CPU0_P3P3_DN<19> U2               EF81     SOCKET4677_AZIFS054P001C01-SOCA
UPI_CPU1_CPU0_P3P3_DN<20> U1               CF75     SOCKET4677_AZIFS054P001C01-SOCA
UPI_CPU1_CPU0_P3P3_DN<20> U2               EK81     SOCKET4677_AZIFS054P001C01-SOCA
UPI_CPU1_CPU0_P3P3_DN<21> U1               CK75     SOCKET4677_AZIFS054P001C01-SOCA
UPI_CPU1_CPU0_P3P3_DN<21> U2               EL82     SOCKET4677_AZIFS054P001C01-SOCA
UPI_CPU1_CPU0_P3P3_DN<22> U1               CW74     SOCKET4677_AZIFS054P001C01-SOCA
UPI_CPU1_CPU0_P3P3_DN<22> U2               EP81     SOCKET4677_AZIFS054P001C01-SOCA
UPI_CPU1_CPU0_P3P3_DN<23> U1               CD73     SOCKET4677_AZIFS054P001C01-SOCA
UPI_CPU1_CPU0_P3P3_DN<23> U2               EJ80     SOCKET4677_AZIFS054P001C01-SOCA
UPI_CPU1_CPU0_P3P3_DP<0> U1               EK85     SOCKET4677_AZIFS054P001C01-SOCA
UPI_CPU1_CPU0_P3P3_DP<0> U2               DB79     SOCKET4677_AZIFS054P001C01-SOCA
UPI_CPU1_CPU0_P3P3_DP<1> U1               EM85     SOCKET4677_AZIFS054P001C01-SOCA
UPI_CPU1_CPU0_P3P3_DP<1> U2               CU80     SOCKET4677_AZIFS054P001C01-SOCA
UPI_CPU1_CPU0_P3P3_DP<2> U1               EN86     SOCKET4677_AZIFS054P001C01-SOCA
UPI_CPU1_CPU0_P3P3_DP<2> U2               CR80     SOCKET4677_AZIFS054P001C01-SOCA
UPI_CPU1_CPU0_P3P3_DP<3> U1               EM87     SOCKET4677_AZIFS054P001C01-SOCA
UPI_CPU1_CPU0_P3P3_DP<3> U2               CN82     SOCKET4677_AZIFS054P001C01-SOCA
UPI_CPU1_CPU0_P3P3_DP<4> U1               EH87     SOCKET4677_AZIFS054P001C01-SOCA
UPI_CPU1_CPU0_P3P3_DP<4> U2               CV81     SOCKET4677_AZIFS054P001C01-SOCA
UPI_CPU1_CPU0_P3P3_DP<5> U1               EL88     SOCKET4677_AZIFS054P001C01-SOCA
UPI_CPU1_CPU0_P3P3_DP<5> U2               CT83     SOCKET4677_AZIFS054P001C01-SOCA
UPI_CPU1_CPU0_P3P3_DP<6> U1               DT81     SOCKET4677_AZIFS054P001C01-SOCA
UPI_CPU1_CPU0_P3P3_DP<6> U2               CW82     SOCKET4677_AZIFS054P001C01-SOCA
UPI_CPU1_CPU0_P3P3_DP<7> U1               DU82     SOCKET4677_AZIFS054P001C01-SOCA
UPI_CPU1_CPU0_P3P3_DP<7> U2               DE78     SOCKET4677_AZIFS054P001C01-SOCA
UPI_CPU1_CPU0_P3P3_DP<8> U1               DR80     SOCKET4677_AZIFS054P001C01-SOCA
UPI_CPU1_CPU0_P3P3_DP<8> U2               DD81     SOCKET4677_AZIFS054P001C01-SOCA
UPI_CPU1_CPU0_P3P3_DP<9> U1               DP83     SOCKET4677_AZIFS054P001C01-SOCA
UPI_CPU1_CPU0_P3P3_DP<9> U2               DB83     SOCKET4677_AZIFS054P001C01-SOCA
UPI_CPU1_CPU0_P3P3_DP<10> U1               DL82     SOCKET4677_AZIFS054P001C01-SOCA
UPI_CPU1_CPU0_P3P3_DP<10> U2               DF81     SOCKET4677_AZIFS054P001C01-SOCA
UPI_CPU1_CPU0_P3P3_DP<11> U1               DL80     SOCKET4677_AZIFS054P001C01-SOCA
UPI_CPU1_CPU0_P3P3_DP<11> U2               DH83     SOCKET4677_AZIFS054P001C01-SOCA
UPI_CPU1_CPU0_P3P3_DP<12> U1               DA76     SOCKET4677_AZIFS054P001C01-SOCA
UPI_CPU1_CPU0_P3P3_DP<12> U2               DG82     SOCKET4677_AZIFS054P001C01-SOCA
UPI_CPU1_CPU0_P3P3_DP<13> U1               CV77     SOCKET4677_AZIFS054P001C01-SOCA
UPI_CPU1_CPU0_P3P3_DP<13> U2               DH79     SOCKET4677_AZIFS054P001C01-SOCA
UPI_CPU1_CPU0_P3P3_DP<14> U1               CR76     SOCKET4677_AZIFS054P001C01-SOCA
UPI_CPU1_CPU0_P3P3_DP<14> U2               DL78     SOCKET4677_AZIFS054P001C01-SOCA
UPI_CPU1_CPU0_P3P3_DP<15> U1               CR74     SOCKET4677_AZIFS054P001C01-SOCA
UPI_CPU1_CPU0_P3P3_DP<15> U2               EB81     SOCKET4677_AZIFS054P001C01-SOCA
UPI_CPU1_CPU0_P3P3_DP<16> U1               CK77     SOCKET4677_AZIFS054P001C01-SOCA
UPI_CPU1_CPU0_P3P3_DP<16> U2               DY83     SOCKET4677_AZIFS054P001C01-SOCA
UPI_CPU1_CPU0_P3P3_DP<17> U1               CJ78     SOCKET4677_AZIFS054P001C01-SOCA
UPI_CPU1_CPU0_P3P3_DP<17> U2               ED81     SOCKET4677_AZIFS054P001C01-SOCA
UPI_CPU1_CPU0_P3P3_DP<18> U1               CM75     SOCKET4677_AZIFS054P001C01-SOCA
UPI_CPU1_CPU0_P3P3_DP<18> U2               EF83     SOCKET4677_AZIFS054P001C01-SOCA
UPI_CPU1_CPU0_P3P3_DP<19> U1               CF77     SOCKET4677_AZIFS054P001C01-SOCA
UPI_CPU1_CPU0_P3P3_DP<19> U2               EE82     SOCKET4677_AZIFS054P001C01-SOCA
UPI_CPU1_CPU0_P3P3_DP<20> U1               CH75     SOCKET4677_AZIFS054P001C01-SOCA
UPI_CPU1_CPU0_P3P3_DP<20> U2               EJ82     SOCKET4677_AZIFS054P001C01-SOCA
UPI_CPU1_CPU0_P3P3_DP<21> U1               CJ74     SOCKET4677_AZIFS054P001C01-SOCA
UPI_CPU1_CPU0_P3P3_DP<21> U2               EN82     SOCKET4677_AZIFS054P001C01-SOCA
UPI_CPU1_CPU0_P3P3_DP<22> U1               CV73     SOCKET4677_AZIFS054P001C01-SOCA
UPI_CPU1_CPU0_P3P3_DP<22> U2               ER82     SOCKET4677_AZIFS054P001C01-SOCA
UPI_CPU1_CPU0_P3P3_DP<23> U1               CF73     SOCKET4677_AZIFS054P001C01-SOCA
UPI_CPU1_CPU0_P3P3_DP<23> U2               EL80     SOCKET4677_AZIFS054P001C01-SOCA
USB2_0_DN                J41              B57      SCONN168_623403212-SCONN168_6-A
USB2_0_DN                U4               AR42     EMMITSBURG_REV0P9-GFNOCPU04302A
USB2_0_DP                J41              B56      SCONN168_623403212-SCONN168_6-A
USB2_0_DP                U4               AR40     EMMITSBURG_REV0P9-GFNOCPU04302A
USB2_1_DN                L9               4        Q_INDUCTOR4P_12-67/320MA,320MAA
USB2_1_DN                R470             1        Q_RES_0402LF-0,5%,1/16W,CHIP,CA
USB2_1_DN                U4               AP43     EMMITSBURG_REV0P9-GFNOCPU04302A
USB2_1_DP                L9               1        Q_INDUCTOR4P_12-67/320MA,320MAA
USB2_1_DP                R469             1        Q_RES_0402LF-0,5%,1/16W,CHIP,CA
USB2_1_DP                U4               AP41     EMMITSBURG_REV0P9-GFNOCPU04302A
USB2_1_F_DN              J48              2        CONN9_2UB3903013101F-CONN9_2UBA
USB2_1_F_DN              L9               3        Q_INDUCTOR4P_12-67/320MA,320MAA
USB2_1_F_DN              R470             2        Q_RES_0402LF-0,5%,1/16W,CHIP,CA
USB2_1_F_DP              J48              3        CONN9_2UB3903013101F-CONN9_2UBA
USB2_1_F_DP              L9               2        Q_INDUCTOR4P_12-67/320MA,320MAA
USB2_1_F_DP              R469             2        Q_RES_0402LF-0,5%,1/16W,CHIP,CA
USB2_3_DN                R444             2        Q_RES_0402LF-0,5%,1/16W,CHIP,CA
USB2_3_DN                U4               AN42     EMMITSBURG_REV0P9-GFNOCPU04302A
USB2_3_DP                R445             2        Q_RES_0402LF-0,5%,1/16W,CHIP,CA
USB2_3_DP                U4               AN40     EMMITSBURG_REV0P9-GFNOCPU04302A
USB2_4_DN                R2130            1        Q_RES_0402LF-0,5%,1/16W,CHIP,CA
USB2_4_DN                U4               AU42     EMMITSBURG_REV0P9-GFNOCPU04302A
USB2_4_DP                R2131            1        Q_RES_0402LF-0,5%,1/16W,CHIP,CA
USB2_4_DP                U4               AU40     EMMITSBURG_REV0P9-GFNOCPU04302A
USB2_5_DN                R2149            2        Q_RES_0402LF-0,5%,1/16W,CHIP,CA
USB2_5_DN                U4               AL43     EMMITSBURG_REV0P9-GFNOCPU04302A
USB2_5_DP                R2150            2        Q_RES_0402LF-0,5%,1/16W,CHIP,CA
USB2_5_DP                U4               AL41     EMMITSBURG_REV0P9-GFNOCPU04302A
USB2_8_DN                J41              B54      SCONN168_623403212-SCONN168_6-A
USB2_8_DN                U4               AW42     EMMITSBURG_REV0P9-GFNOCPU04302A
USB2_8_DP                J41              B53      SCONN168_623403212-SCONN168_6-A
USB2_8_DP                U4               AW40     EMMITSBURG_REV0P9-GFNOCPU04302A
USB2_9_DN                J41              B51      SCONN168_623403212-SCONN168_6-A
USB2_9_DN                U4               AJ43     EMMITSBURG_REV0P9-GFNOCPU04302A
USB2_9_DP                J41              B50      SCONN168_623403212-SCONN168_6-A
USB2_9_DP                U4               AJ41     EMMITSBURG_REV0P9-GFNOCPU04302A
USB3_9_RX_DN             L6               1        Q_INDUCTOR4P_12-67/320MA,320MAA
USB3_9_RX_DN             R466             1        Q_RES_0402LF-0,5%,1/16W,CHIP,CA
USB3_9_RX_DN             U4               R40      EMMITSBURG_REV0P9-GFNOCPU04302A
USB3_9_RX_DN_FB          J48              5        CONN9_2UB3903013101F-CONN9_2UBA
USB3_9_RX_DN_FB          L6               2        Q_INDUCTOR4P_12-67/320MA,320MAA
USB3_9_RX_DN_FB          R466             2        Q_RES_0402LF-0,5%,1/16W,CHIP,CA
USB3_9_RX_DP             L6               4        Q_INDUCTOR4P_12-67/320MA,320MAA
USB3_9_RX_DP             R468             1        Q_RES_0402LF-0,5%,1/16W,CHIP,CA
USB3_9_RX_DP             U4               R42      EMMITSBURG_REV0P9-GFNOCPU04302A
USB3_9_RX_DP_FB          J48              6        CONN9_2UB3903013101F-CONN9_2UBA
USB3_9_RX_DP_FB          L6               3        Q_INDUCTOR4P_12-67/320MA,320MAA
USB3_9_RX_DP_FB          R468             2        Q_RES_0402LF-0,5%,1/16W,CHIP,CA
USB3_9_TX_DN             C565             1        Q_CAP_0402-0.1UF,25V,10%,X7R,CA
USB3_9_TX_DN             U4               AE32     EMMITSBURG_REV0P9-GFNOCPU04302A
USB3_9_TX_DN_C           C565             2        Q_CAP_0402-0.1UF,25V,10%,X7R,CA
USB3_9_TX_DN_C           L5               1        Q_INDUCTOR4P_12-67/320MA,320MAA
USB3_9_TX_DN_C           R464             1        Q_RES_0402LF-0,5%,1/16W,CHIP,CA
USB3_9_TX_DN_FB          J48              8        CONN9_2UB3903013101F-CONN9_2UBA
USB3_9_TX_DN_FB          L5               2        Q_INDUCTOR4P_12-67/320MA,320MAA
USB3_9_TX_DN_FB          R464             2        Q_RES_0402LF-0,5%,1/16W,CHIP,CA
USB3_9_TX_DP             C566             1        Q_CAP_0402-0.1UF,25V,10%,X7R,CA
USB3_9_TX_DP             U4               AG32     EMMITSBURG_REV0P9-GFNOCPU04302A
USB3_9_TX_DP_C           C566             2        Q_CAP_0402-0.1UF,25V,10%,X7R,CA
USB3_9_TX_DP_C           L5               4        Q_INDUCTOR4P_12-67/320MA,320MAA
USB3_9_TX_DP_C           R465             1        Q_RES_0402LF-0,5%,1/16W,CHIP,CA
USB3_9_TX_DP_FB          J48              9        CONN9_2UB3903013101F-CONN9_2UBA
USB3_9_TX_DP_FB          L5               3        Q_INDUCTOR4P_12-67/320MA,320MAA
USB3_9_TX_DP_FB          R465             2        Q_RES_0402LF-0,5%,1/16W,CHIP,CA
USB_OC1_REAR_N           R1827            2        Q_RES_0402LF-33,5%,1/16W,CHIP,A
USB_OC1_REAR_N           U122             B9       10M04SAU324I7G-10M04SAU324I7G,A
USB_OC1_REAR_R_N         R1827            1        Q_RES_0402LF-33,5%,1/16W,CHIP,A
USB_OC1_REAR_R_N         R1828            1        Q_RES_0402LF-10K,1%,1/16W,CHIPA
USB_OC1_REAR_R_N         U4               BG32     EMMITSBURG_REV0P9-GFNOCPU04302A
USB_OC2_INT_N            R463             2        Q_RES_0402LF-10K,1%,1/16W,CHIPA
USB_OC2_INT_N            R471             1        Q_RES_0402LF-0,5%,1/16W,CHIP,CA
USB_OC2_INT_N            U27              4        TPS2553DBVR1-TPS2553DBVR-1,SMLA
USB_OC2_INT_R_N          R471             2        Q_RES_0402LF-0,5%,1/16W,CHIP,CA
USB_OC2_INT_R_N          U4               BG30     EMMITSBURG_REV0P9-GFNOCPU04302A
VDD3                     C1581            1        Q_CAP_C0402-1UF,25V,10%,EMPTY,A
VDD3                     C1587            1        Q_CAP_C0402-1UF,25V,10%,EMPTY,A
VDD3                     R2072            1        Q_RES_0402LF-100K,1%,1/16W,CHIA
VDD3                     R2073            1        Q_RES_0402LF-100K,1%,1/16W,CHIA
VDD3                     R2084            1        Q_RES_0402LF-100K,1%,1/16W,CHIA
VDD3                     R2085            1        Q_RES_0402LF-100K,1%,1/16W,CHIA
VDD3                     U81              21       MP5981GLUZ-MP5981GLU-Z,SMLF,ICA
VDD3                     U107             21       MP5981GLUZ-MP5981GLU-Z,SMLF,ICA
VIRTUAL_RESEAT           J41              OCP_A14  SCONN168_623403212-SCONN168_6-A
VIRTUAL_RESEAT           U122             G7       10M04SAU324I7G-10M04SAU324I7G,A
VIRTUAL_RESEAT_FPGA_N    R1853            2        Q_RES_0402LF-0,5%,1/16W,CHIP,CA
VIRTUAL_RESEAT_FPGA_N    R2135            1        Q_RES_0402LF-0,5%,1/16W,CHIP,CA
VIRTUAL_RESEAT_FPGA_R_N  R1853            1        Q_RES_0402LF-0,5%,1/16W,CHIP,CA
VIRTUAL_RESEAT_FPGA_R_N  U122             H2       10M04SAU324I7G-10M04SAU324I7G,A
VOL_SEN_ADDR             R1784            2        Q_RES_0402LF-4.7K,1%,1/16W,EMPA
VOL_SEN_ADDR             R1785            1        Q_RES_0402LF-4.7K,1%,1/16W,CHIA
VOL_SEN_ADDR             U105             1        ADS1015IDGSR-ADS1015IDGSR,SMLFA
VOL_SEN_ALERT            R1794            2        Q_RES_0402LF-4.7K,1%,1/16W,EMPA
VOL_SEN_ALERT            R2070            1        Q_RES_0402LF-0,5%,1/16W,CHIP,CA
VOL_SEN_ALERT            U105             2        ADS1015IDGSR-ADS1015IDGSR,SMLFA
VOL_SEN_ALERT_R          R2070            2        Q_RES_0402LF-0,5%,1/16W,CHIP,CA
VOL_SEN_ALERT_R          U122             B13      10M04SAU324I7G-10M04SAU324I7G,A
VR_P3V3_EN_D_R           PQ2              4        MOSFET_NCH_1D3S-PSMNR58-30YLH,A
VR_P3V3_EN_D_R           U79              7        SLG55221120010VTR-SLG55221-120A
VR_P5V_EN                Q37              2        MOSFET_NCH_DUAL-2N7002KDW,SMLFA
VR_P5V_EN                R1607            2        Q_RES_0402LF-0,5%,1/16W,CHIP,CA
VR_P5V_EN                R1640            2        Q_RES_0402LF-0,5%,1/16W,EMPTY,A
VR_P5V_EN                R1641            1        Q_RES_0402LF-100,1%,1/16W,CHIPA
VR_P5V_EN_D_R            C1226            1        Q_CAP_0402-0.22UF,16V,10%,X7R,A
VR_P5V_EN_D_R            PQ1              4        MOSFET_NCH_1D3S-PSMNR58-30YLH,A
VR_P5V_EN_D_R            R1642            2        Q_RES_0402LF-10K,5%,1/16W,CHIPA
VR_P5V_EN_D_R            R1654            1        Q_RES_0402LF-1K,5%,1/16W,CHIP,A
VR_P5V_EN_D_R1           Q37              3        MOSFET_NCH_DUAL-2N7002KDW,SMLFA
VR_P5V_EN_D_R1           R1654            2        Q_RES_0402LF-1K,5%,1/16W,CHIP,A
VR_P5V_EN_N              Q37              5        MOSFET_NCH_DUAL-2N7002KDW,SMLFA
VR_P5V_EN_N              Q37              6        MOSFET_NCH_DUAL-2N7002KDW,SMLFA
VR_P5V_EN_N              R1643            2        Q_RES_0402LF-100K,5%,1/16W,CHIA
VSENSE_PVCCD_HV_CPU0_DN  PC627            2        Q_CAP_0402-3300PF,50V,10%,X7R,A
VSENSE_PVCCD_HV_CPU0_DN  PR591            1        Q_RES_0402LF-100,1%,1/16W,CHIPA
VSENSE_PVCCD_HV_CPU0_DN  PU35             22       ISL69260IRAZT-ISL69260IRAZ-T,SA
VSENSE_PVCCD_HV_CPU0_DN  U2               BN11     SOCKET4677_AZIFS054P001C01-SOCA
VSENSE_PVCCD_HV_CPU0_DP  PJ54             1        Q_SHORT_SM-EMPTY,SHORT6
VSENSE_PVCCD_HV_CPU0_DP  PR592            1        Q_RES_0402LF-100,1%,1/16W,CHIPA
VSENSE_PVCCD_HV_CPU0_DP  U2               BU11     SOCKET4677_AZIFS054P001C01-SOCA
VSENSE_PVCCD_HV_CPU1_DN  PC389            2        Q_CAP_0402-3300PF,50V,10%,X7R,A
VSENSE_PVCCD_HV_CPU1_DN  PR558            1        Q_RES_0402LF-100,1%,1/16W,CHIPA
VSENSE_PVCCD_HV_CPU1_DN  PU18             22       ISL69260IRAZT-ISL69260IRAZ-T,SA
VSENSE_PVCCD_HV_CPU1_DN  U1               BN11     SOCKET4677_AZIFS054P001C01-SOCA
VSENSE_PVCCD_HV_CPU1_DP  PJ48             1        Q_SHORT_SM-EMPTY,SHORT6
VSENSE_PVCCD_HV_CPU1_DP  PR559            1        Q_RES_0402LF-100,1%,1/16W,CHIPA
VSENSE_PVCCD_HV_CPU1_DP  U1               BU11     SOCKET4677_AZIFS054P001C01-SOCA
VSENSE_PVCCFA_EHV_CPU0_DN PC216            2        Q_CAP_0402-3300PF,50V,10%,X7R,A
VSENSE_PVCCFA_EHV_CPU0_DN PR520            1        Q_RES_0402LF-100,1%,1/16W,CHIPA
VSENSE_PVCCFA_EHV_CPU0_DN PU5              31       ISL69260IRAZT-ISL69260IRAZ-T,SA
VSENSE_PVCCFA_EHV_CPU0_DN U2               BA11     SOCKET4677_AZIFS054P001C01-SOCA
VSENSE_PVCCFA_EHV_CPU0_DP PJ46             1        Q_SHORT_SM-EMPTY,SHORT6
VSENSE_PVCCFA_EHV_CPU0_DP PR522            1        Q_RES_0402LF-100,1%,1/16W,CHIPA
VSENSE_PVCCFA_EHV_CPU0_DP U2               AU11     SOCKET4677_AZIFS054P001C01-SOCA
VSENSE_PVCCFA_EHV_CPU1_DN PC469            2        Q_CAP_0402-3300PF,50V,10%,X7R,A
VSENSE_PVCCFA_EHV_CPU1_DN PR567            1        Q_RES_0402LF-100,1%,1/16W,CHIPA
VSENSE_PVCCFA_EHV_CPU1_DN PU22             31       ISL69260IRAZT-ISL69260IRAZ-T,SA
VSENSE_PVCCFA_EHV_CPU1_DN U1               BA11     SOCKET4677_AZIFS054P001C01-SOCA
VSENSE_PVCCFA_EHV_CPU1_DP PJ51             1        Q_SHORT_SM-EMPTY,SHORT6
VSENSE_PVCCFA_EHV_CPU1_DP PR569            1        Q_RES_0402LF-100,1%,1/16W,CHIPA
VSENSE_PVCCFA_EHV_CPU1_DP U1               AU11     SOCKET4677_AZIFS054P001C01-SOCA
VSENSE_PVCCFA_EHV_FIVRA_CPU0_DN PC594            2        Q_CAP_0402-3300PF,50V,10%,X7R,A
VSENSE_PVCCFA_EHV_FIVRA_CPU0_DN PR586            1        Q_RES_0402LF-100,1%,1/16W,CHIPA
VSENSE_PVCCFA_EHV_FIVRA_CPU0_DN PU14             39       RAA229126GNPHA0-RAA229126GNP#HA
VSENSE_PVCCFA_EHV_FIVRA_CPU0_DN U2               AT85     SOCKET4677_AZIFS054P001C01-SOCA
VSENSE_PVCCFA_EHV_FIVRA_CPU0_DP PJ53             1        Q_SHORT_SM-EMPTY,SHORT6
VSENSE_PVCCFA_EHV_FIVRA_CPU0_DP PR587            1        Q_RES_0402LF-100,1%,1/16W,CHIPA
VSENSE_PVCCFA_EHV_FIVRA_CPU0_DP U2               AY85     SOCKET4677_AZIFS054P001C01-SOCA
VSENSE_PVCCFA_EHV_FIVRA_CPU1_DN PC422            2        Q_CAP_0402-3300PF,50V,10%,X7R,A
VSENSE_PVCCFA_EHV_FIVRA_CPU1_DN PR560            1        Q_RES_0402LF-100,1%,1/16W,CHIPA
VSENSE_PVCCFA_EHV_FIVRA_CPU1_DN PU29             39       RAA229126GNPHA0-RAA229126GNP#HA
VSENSE_PVCCFA_EHV_FIVRA_CPU1_DN U1               AT85     SOCKET4677_AZIFS054P001C01-SOCA
VSENSE_PVCCFA_EHV_FIVRA_CPU1_DP PJ49             1        Q_SHORT_SM-EMPTY,SHORT6
VSENSE_PVCCFA_EHV_FIVRA_CPU1_DP PR561            1        Q_RES_0402LF-100,1%,1/16W,CHIPA
VSENSE_PVCCFA_EHV_FIVRA_CPU1_DP U1               AY85     SOCKET4677_AZIFS054P001C01-SOCA
VSENSE_PVCCINFAON_CPU0_DN PC215            2        Q_CAP_0402-3300PF,50V,10%,X7R,A
VSENSE_PVCCINFAON_CPU0_DN PR519            1        Q_RES_0402LF-100,1%,1/16W,CHIPA
VSENSE_PVCCINFAON_CPU0_DN PU5              22       ISL69260IRAZT-ISL69260IRAZ-T,SA
VSENSE_PVCCINFAON_CPU0_DN U2               CE11     SOCKET4677_AZIFS054P001C01-SOCA
VSENSE_PVCCINFAON_CPU0_DP PJ45             1        Q_SHORT_SM-EMPTY,SHORT6
VSENSE_PVCCINFAON_CPU0_DP PR521            1        Q_RES_0402LF-100,1%,1/16W,CHIPA
VSENSE_PVCCINFAON_CPU0_DP U2               CA11     SOCKET4677_AZIFS054P001C01-SOCA
VSENSE_PVCCINFAON_CPU1_DN PC468            2        Q_CAP_0402-3300PF,50V,10%,X7R,A
VSENSE_PVCCINFAON_CPU1_DN PR566            1        Q_RES_0402LF-100,1%,1/16W,CHIPA
VSENSE_PVCCINFAON_CPU1_DN PU22             22       ISL69260IRAZT-ISL69260IRAZ-T,SA
VSENSE_PVCCINFAON_CPU1_DN U1               CE11     SOCKET4677_AZIFS054P001C01-SOCA
VSENSE_PVCCINFAON_CPU1_DP PJ50             1        Q_SHORT_SM-EMPTY,SHORT6
VSENSE_PVCCINFAON_CPU1_DP PR568            1        Q_RES_0402LF-100,1%,1/16W,CHIPA
VSENSE_PVCCINFAON_CPU1_DP U1               CA11     SOCKET4677_AZIFS054P001C01-SOCA
VSENSE_PVCCIN_CPU0_DN    PC331            2        Q_CAP_0402-3300PF,50V,10%,X7R,A
VSENSE_PVCCIN_CPU0_DN    PR527            1        Q_RES_0402LF-100,1%,1/16W,CHIPA
VSENSE_PVCCIN_CPU0_DN    PU14             26       RAA229126GNPHA0-RAA229126GNP#HA
VSENSE_PVCCIN_CPU0_DN    U2               BC90     SOCKET4677_AZIFS054P001C01-SOCA
VSENSE_PVCCIN_CPU0_DP    PJ47             1        Q_SHORT_SM-EMPTY,SHORT6
VSENSE_PVCCIN_CPU0_DP    PR531            1        Q_RES_0402LF-100,1%,1/16W,CHIPA
VSENSE_PVCCIN_CPU0_DP    U2               BD87     SOCKET4677_AZIFS054P001C01-SOCA
VSENSE_PVCCIN_CPU1_DN    PC549            2        Q_CAP_0402-3300PF,50V,10%,X7R,A
VSENSE_PVCCIN_CPU1_DN    PR574            1        Q_RES_0402LF-100,1%,1/16W,CHIPA
VSENSE_PVCCIN_CPU1_DN    PU29             26       RAA229126GNPHA0-RAA229126GNP#HA
VSENSE_PVCCIN_CPU1_DN    U1               BC90     SOCKET4677_AZIFS054P001C01-SOCA
VSENSE_PVCCIN_CPU1_DP    PJ52             1        Q_SHORT_SM-EMPTY,SHORT6
VSENSE_PVCCIN_CPU1_DP    PR578            1        Q_RES_0402LF-100,1%,1/16W,CHIPA
VSENSE_PVCCIN_CPU1_DP    U1               BD87     SOCKET4677_AZIFS054P001C01-SOCA
XTAL_CLK_GEN1_25M_X1     R1724            2        Q_RES_0402LF-0,5%,1/16W,CHIP,CA
XTAL_CLK_GEN1_25M_X1     U13              A13      9SQ440NQQI8-9SQ440NQQI8,SMLF,IA
XTAL_CLK_GEN1_25M_X1_R   C113             1        Q_CAP_0402-15PF,50V,5%,C0G,CH0A
XTAL_CLK_GEN1_25M_X1_R   R1724            1        Q_RES_0402LF-0,5%,1/16W,CHIP,CA
XTAL_CLK_GEN1_25M_X1_R   Y2               1        Q_XTAL_4P_13_SMLF-25MHZ,IC,BG6A
XTAL_CLK_GEN1_25M_X2     C118             1        Q_CAP_0402-15PF,50V,5%,C0G,CH0A
XTAL_CLK_GEN1_25M_X2     U13              B11      9SQ440NQQI8-9SQ440NQQI8,SMLF,IA
XTAL_CLK_GEN1_25M_X2     Y2               3        Q_XTAL_4P_13_SMLF-25MHZ,IC,BG6A
XTAL_PCH_25M_IN          R1720            2        Q_RES_0402LF-0,5%,1/16W,EMPTY,A
XTAL_PCH_25M_IN          U4               B23      EMMITSBURG_REV0P9-GFNOCPU04302A
XTAL_PCH_25M_IN_R        C103             1        Q_CAP_0402-27PF  ,50V ,5% ,EMPA
XTAL_PCH_25M_IN_R        R1316            1        Q_RES_0603LF-200K,0.1%,1/10W,EA
XTAL_PCH_25M_IN_R        R1720            1        Q_RES_0402LF-0,5%,1/16W,EMPTY,A
XTAL_PCH_25M_IN_R        Y3               1        Q_XTAL_4P_13BI_24GND-25MHZ,SMLA
XTAL_PCH_25M_OUT         C104             1        Q_CAP_0402-27PF  ,50V ,5% ,EMPA
XTAL_PCH_25M_OUT         R1316            2        Q_RES_0603LF-200K,0.1%,1/10W,EA
XTAL_PCH_25M_OUT         U4               D23      EMMITSBURG_REV0P9-GFNOCPU04302A
XTAL_PCH_25M_OUT         Y3               3        Q_XTAL_4P_13BI_24GND-25MHZ,SMLA
XTAL_PCH_RTC1            C1508            1        Q_CAP_0402-27PF  ,50V ,5% ,NPOA
XTAL_PCH_RTC1            R120             2        Q_RES_0603LF-10M,1%,1/10W,CHIPA
XTAL_PCH_RTC1            U4               BE6      EMMITSBURG_REV0P9-GFNOCPU04302A
XTAL_PCH_RTC1            Y1               2        Q_CRYSTAL_SMLF-32.768KHZ,IC,BGA
XTAL_PCH_RTC2            R1721            2        Q_RES_0402LF-0,5%,1/16W,CHIP,CA
XTAL_PCH_RTC2            U4               BF7      EMMITSBURG_REV0P9-GFNOCPU04302A
XTAL_PCH_RTC2_R          C1507            1        Q_CAP_0402-27PF  ,50V ,5% ,NPOA
XTAL_PCH_RTC2_R          R120             1        Q_RES_0603LF-10M,1%,1/10W,CHIPA
XTAL_PCH_RTC2_R          R1721            1        Q_RES_0402LF-0,5%,1/16W,CHIP,CA
XTAL_PCH_RTC2_R          Y1               1        Q_CRYSTAL_SMLF-32.768KHZ,IC,BGA
END CONCISE NET LIST
